G04 ================== begin FILE IDENTIFICATION RECORD ==================*
G04 Layout Name:  15669-1.brd*
G04 Film Name:    TSILK*
G04 File Format:  Gerber RS274X*
G04 File Origin:  Cadence Allegro 16.5-S056*
G04 Origin Date:  Wed Nov 16 04:08:18 2016*
G04 *
G04 Layer:  VIA CLASS/FILMMASKTOP*
G04 Layer:  REF DES/ASSEMBLY_TOP*
G04 Layer:  PACKAGE GEOMETRY/SILKSCREEN_TOP*
G04 Layer:  DRAWING FORMAT/LAYER_PCB_STORY*
G04 Layer:  DRAWING FORMAT/LAYER_SILK_T*
G04 Layer:  BOARD GEOMETRY/SILKSCREEN_TOP*
G04 *
G04 Offset:    (0.00 0.00)*
G04 Mirror:    No*
G04 Mode:      Positive*
G04 Rotation:  0*
G04 FullContactRelief:  No*
G04 UndefLineWidth:     6.00*
G04 ================== end FILE IDENTIFICATION RECORD ====================*
%FSLAX35Y35*MOIN*%
%IR0*IPPOS*OFA0.00000B0.00000*MIA0B0*SFA1.00000B1.00000*%
%ADD10C,.01*%
%ADD11C,.02*%
%ADD12C,.012*%
%ADD13C,.013*%
%ADD14C,.016*%
%ADD15C,.027*%
%ADD16C,.002*%
%ADD17C,.006*%
%ADD18C,.008*%
G75*
%LPD*%
G75*
G36*
G01X122300Y1552900D02*
X111100D01*
Y1570350D01*
X122300D01*
Y1552900D01*
G37*
G36*
G01X95100Y1932800D02*
X83900D01*
Y1950250D01*
X95100D01*
Y1932800D01*
G37*
G36*
G01X169900Y60200D02*
X181100D01*
Y42750D01*
X169900D01*
Y60200D01*
G37*
G36*
G01X122800Y341300D02*
X111600D01*
Y358750D01*
X122800D01*
Y341300D01*
G37*
G36*
G01X121300Y434300D02*
X132500D01*
Y416850D01*
X121300D01*
Y434300D01*
G37*
G36*
G01X177228Y547857D02*
X169228D01*
Y538757D01*
X177228D01*
Y547857D01*
G37*
G36*
G01X122800Y746800D02*
X111600D01*
Y764250D01*
X122800D01*
Y746800D01*
G37*
G36*
G01X121300Y839800D02*
X132500D01*
Y822350D01*
X121300D01*
Y839800D01*
G37*
G36*
G01X122800Y1152700D02*
X111600D01*
Y1170150D01*
X122800D01*
Y1152700D01*
G37*
G36*
G01X121600Y1245300D02*
X132800D01*
Y1227850D01*
X121600D01*
Y1245300D01*
G37*
G36*
G01X126047Y1496676D02*
X118047D01*
Y1487576D01*
X126047D01*
Y1496676D01*
G37*
G36*
G01X122800Y1650800D02*
X134000D01*
Y1633350D01*
X122800D01*
Y1650800D01*
G37*
G36*
G01X306900Y597400D02*
X311900Y592400D01*
Y597400D01*
X306900D01*
G37*
G36*
G01X311900Y1414600D02*
X306900Y1409600D01*
X311900D01*
Y1414600D01*
G37*
G36*
G01X354035Y421700D02*
X348300Y415965D01*
Y421700D01*
X354035D01*
G37*
G36*
G01Y851700D02*
X348300Y845965D01*
Y851700D01*
X354035D01*
G37*
G36*
G01X353618Y1222782D02*
X348300Y1217465D01*
Y1222782D01*
X353618D01*
G37*
G36*
G01X353918Y1721582D02*
X348300Y1715965D01*
Y1721582D01*
X353918D01*
G37*
G36*
G01X432452Y7476D02*
X668672D01*
Y86216D01*
X432452D01*
Y7476D01*
G37*
G36*
G01X473700Y847600D02*
Y822600D01*
X598900D01*
Y847600D01*
X473700D01*
G37*
G36*
G01X473800Y817100D02*
Y792100D01*
X599000D01*
Y817100D01*
X473800D01*
G37*
G36*
G01X432452Y1905670D02*
X668672D01*
Y1984410D01*
X432452D01*
Y1905670D01*
G37*
G36*
G01X547287Y1414630D02*
X547348Y1414143D01*
X547408Y1414083D01*
X547469Y1413353D01*
X547530Y1413292D01*
X547591Y1412501D01*
X547652Y1412440D01*
X547713Y1411710D01*
X547773Y1411650D01*
X547834Y1410920D01*
X547895Y1410859D01*
X547956Y1410129D01*
X548017Y1410068D01*
X548077Y1409338D01*
X548138Y1409278D01*
X548199Y1408487D01*
X548260Y1408426D01*
X548321Y1407696D01*
X548382Y1407636D01*
X548442Y1406906D01*
X548503Y1406845D01*
X548564Y1406115D01*
X548625Y1406054D01*
X548686Y1405325D01*
X548747Y1405264D01*
X548807Y1404534D01*
X548868Y1404473D01*
X548929Y1403683D01*
X548990Y1403622D01*
X549051Y1402892D01*
X549112Y1402831D01*
X549172Y1402405D01*
X553612D01*
X553795Y1402648D01*
X553916Y1402953D01*
X554099Y1403196D01*
X554220Y1403500D01*
X554403Y1403743D01*
X554464Y1403925D01*
X554646Y1404169D01*
X554767Y1404473D01*
X554950Y1404716D01*
X555072Y1405020D01*
X555254Y1405264D01*
X555376Y1405568D01*
X555558Y1405811D01*
X555619Y1405994D01*
X555801Y1406237D01*
X555923Y1406541D01*
X556106Y1406784D01*
X556227Y1407088D01*
X556410Y1407331D01*
X556531Y1407636D01*
X556714Y1407879D01*
X556836Y1408183D01*
X557018Y1408426D01*
X557079Y1408609D01*
X557261Y1408852D01*
X557383Y1409156D01*
X557565Y1409399D01*
X557687Y1409703D01*
X557869Y1409947D01*
Y1410008D01*
X557991Y1410129D01*
X558052Y1410068D01*
X558113Y1408973D01*
X558173Y1408913D01*
X558234Y1407818D01*
X558295Y1407757D01*
X558356Y1406662D01*
X558417Y1406602D01*
X558478Y1405446D01*
X558538Y1405385D01*
X558599Y1404290D01*
X558660Y1404230D01*
X558721Y1403135D01*
X558782Y1403074D01*
X558842Y1402405D01*
X563282D01*
X563404Y1402709D01*
X563586Y1402953D01*
X563647Y1403135D01*
X563830Y1403378D01*
X563890Y1403561D01*
X564073Y1403804D01*
X564134Y1403986D01*
X564316Y1404230D01*
X564438Y1404534D01*
X564620Y1404777D01*
X564681Y1404960D01*
X564864Y1405203D01*
X564925Y1405385D01*
X565107Y1405629D01*
X565167Y1405811D01*
X565350Y1406054D01*
X565411Y1406237D01*
X565593Y1406480D01*
X565654Y1406662D01*
X565837Y1406906D01*
X565897Y1407088D01*
X566080Y1407331D01*
X566141Y1407514D01*
X566323Y1407757D01*
X566384Y1407940D01*
X566567Y1408183D01*
X566688Y1408487D01*
X566871Y1408730D01*
X566931Y1408913D01*
X567114Y1409156D01*
X567175Y1409338D01*
X567357Y1409582D01*
X567418Y1409764D01*
X567601Y1410008D01*
X567661Y1410190D01*
X567844Y1410433D01*
X567904Y1410616D01*
X568087Y1410859D01*
X568148Y1411042D01*
X568330Y1411285D01*
X568391Y1411467D01*
X568573Y1411710D01*
X568634Y1411893D01*
X568817Y1412136D01*
X568938Y1412440D01*
X569121Y1412684D01*
X569182Y1412866D01*
X569364Y1413109D01*
X569425Y1413292D01*
X569608Y1413535D01*
X569668Y1413718D01*
X569851Y1413961D01*
X569912Y1414143D01*
X570094Y1414386D01*
X570155Y1414569D01*
X570337Y1414812D01*
X570398Y1414995D01*
X570580Y1415238D01*
Y1415299D01*
X570641Y1415360D01*
X565532D01*
X565472Y1415116D01*
X565229Y1414691D01*
X565167Y1414447D01*
X564985Y1414143D01*
X564925Y1413900D01*
X564803Y1413718D01*
X564742Y1413474D01*
X564560Y1413170D01*
X564499Y1412927D01*
X564316Y1412623D01*
X564255Y1412379D01*
X564134Y1412197D01*
X564073Y1411954D01*
X563890Y1411650D01*
X563830Y1411407D01*
X563647Y1411102D01*
X563586Y1410859D01*
X563465Y1410677D01*
X563404Y1410433D01*
X563221Y1410129D01*
X563161Y1409886D01*
X562978Y1409582D01*
X562917Y1409338D01*
X562796Y1409156D01*
X562735Y1408913D01*
X562553Y1408609D01*
X562491Y1408366D01*
X562309Y1408061D01*
X562248Y1407818D01*
X562127Y1407636D01*
X562066Y1407392D01*
X561944Y1407271D01*
X561884Y1407331D01*
X561823Y1408548D01*
X561762Y1408609D01*
X561701Y1409886D01*
X561640Y1409947D01*
X561579Y1411224D01*
X561519Y1411285D01*
X561458Y1412623D01*
X561397Y1412684D01*
X561336Y1413961D01*
X561275Y1414022D01*
X561214Y1415299D01*
X561154Y1415360D01*
X556653D01*
X556471Y1414934D01*
X556288Y1414691D01*
X556106Y1414265D01*
X555923Y1414022D01*
X555741Y1413596D01*
X555558Y1413353D01*
X555376Y1412927D01*
X555193Y1412684D01*
X555072Y1412379D01*
X554889Y1412136D01*
X554707Y1411710D01*
X554524Y1411467D01*
X554342Y1411042D01*
X554159Y1410798D01*
X554038Y1410494D01*
X553855Y1410251D01*
X553673Y1409825D01*
X553490Y1409582D01*
X553308Y1409156D01*
X553125Y1408913D01*
X552943Y1408487D01*
X552760Y1408244D01*
X552639Y1407940D01*
X552456Y1407696D01*
X552274Y1407271D01*
X552153Y1407149D01*
X552091Y1407210D01*
X552031Y1409156D01*
X551970Y1409217D01*
X551909Y1411224D01*
X551848Y1411285D01*
X551788Y1413292D01*
X551727Y1413353D01*
X551666Y1415360D01*
X547165D01*
X547287Y1414630D01*
G37*
G36*
G01X558500Y1169500D02*
Y1164500D01*
X578500D01*
Y1169500D01*
X558500D01*
G37*
G36*
G01X626899Y1415603D02*
X626169Y1415542D01*
X626108Y1415481D01*
X625743Y1415420D01*
X625683Y1415360D01*
X625379Y1415299D01*
X625318Y1415238D01*
X625075Y1415177D01*
X625014Y1415116D01*
X624771Y1415055D01*
X624527Y1414934D01*
X624284Y1414751D01*
X624223D01*
X623919Y1414508D01*
X623858D01*
X623372Y1414083D01*
X623311D01*
X622642Y1413413D01*
X622581Y1413474D01*
X622642Y1413961D01*
X622703Y1414022D01*
X622764Y1414508D01*
X622824Y1414569D01*
X622885Y1415055D01*
X622946Y1415116D01*
Y1415360D01*
X618324D01*
X618263Y1414934D01*
X618202Y1414873D01*
X618141Y1414326D01*
X618080Y1414265D01*
X618019Y1413778D01*
X617959Y1413718D01*
X617898Y1413231D01*
X617837Y1413170D01*
X617776Y1412623D01*
X617716Y1412562D01*
X617654Y1412075D01*
X617594Y1412014D01*
X617533Y1411528D01*
X617472Y1411467D01*
X617411Y1410981D01*
X617351Y1410920D01*
X617290Y1410372D01*
X617229Y1410312D01*
X617168Y1409825D01*
X617107Y1409764D01*
X617047Y1409278D01*
X616986Y1409217D01*
X616925Y1408670D01*
X616864Y1408609D01*
X616803Y1408122D01*
X616742Y1408061D01*
X616682Y1407575D01*
X616621Y1407514D01*
X616560Y1406966D01*
X616499Y1406906D01*
X616438Y1406419D01*
X616377Y1406359D01*
X616317Y1405872D01*
X616256Y1405811D01*
X616195Y1405325D01*
X616134Y1405264D01*
X616073Y1404716D01*
X616012Y1404655D01*
X615952Y1404169D01*
X615891Y1404108D01*
X615830Y1403622D01*
X615769Y1403561D01*
X615708Y1403013D01*
X615647Y1402953D01*
X615587Y1402466D01*
X615526Y1402405D01*
X620574D01*
X620635Y1402953D01*
X620695Y1403013D01*
X620756Y1403500D01*
X620817Y1403561D01*
X620878Y1404047D01*
X620939Y1404108D01*
X621000Y1404595D01*
X621060Y1404655D01*
X621121Y1405142D01*
X621182Y1405203D01*
X621243Y1405750D01*
X621304Y1405811D01*
X621365Y1406297D01*
X621425Y1406359D01*
X621486Y1406845D01*
X621547Y1406906D01*
X621608Y1407392D01*
X621669Y1407453D01*
X621730Y1407940D01*
X621790Y1408001D01*
X621851Y1408487D01*
X621912Y1408548D01*
X621973Y1408913D01*
X622034Y1408973D01*
X622094Y1409278D01*
X622155Y1409338D01*
X622216Y1409643D01*
X622642Y1410494D01*
X622885Y1410798D01*
Y1410859D01*
X623432Y1411467D01*
X623736Y1411710D01*
X624223Y1411954D01*
X624710Y1412014D01*
X624771Y1412075D01*
X625379Y1412014D01*
X625743Y1411710D01*
X625865Y1411528D01*
X625926Y1411042D01*
X625865Y1410251D01*
X625804Y1410190D01*
X625743Y1409643D01*
X625683Y1409582D01*
X625622Y1409035D01*
X625561Y1408973D01*
X625500Y1408426D01*
X625440Y1408366D01*
X625379Y1407879D01*
X625318Y1407818D01*
X625257Y1407271D01*
X625196Y1407210D01*
X625135Y1406723D01*
X625075Y1406662D01*
X625014Y1406176D01*
X624953Y1406115D01*
X624892Y1405568D01*
X624831Y1405507D01*
X624771Y1405020D01*
X624710Y1404960D01*
X624649Y1404412D01*
X624588Y1404351D01*
X624527Y1403865D01*
X624466Y1403804D01*
X624406Y1403318D01*
X624345Y1403257D01*
X624284Y1402709D01*
X624223Y1402648D01*
Y1402405D01*
X629149D01*
X629210Y1402709D01*
X629271Y1402770D01*
X629332Y1403318D01*
X629393Y1403378D01*
X629454Y1403865D01*
X629514Y1403925D01*
X629575Y1404473D01*
X629636Y1404534D01*
X629697Y1405020D01*
X629758Y1405081D01*
X629818Y1405568D01*
X629879Y1405629D01*
X629940Y1406176D01*
X630001Y1406237D01*
X630062Y1406723D01*
X630123Y1406784D01*
X630183Y1407331D01*
X630244Y1407392D01*
X630305Y1407879D01*
X630366Y1407940D01*
X630427Y1408426D01*
X630488Y1408487D01*
X630548Y1409035D01*
X630609Y1409095D01*
X630670Y1409582D01*
X630731Y1409643D01*
X630791Y1410190D01*
X630853Y1410251D01*
X630913Y1410859D01*
X630974Y1410920D01*
X631035Y1411589D01*
X631096Y1411650D01*
X631156Y1412623D01*
X631096Y1413353D01*
X631035Y1413413D01*
X630974Y1413718D01*
X630913Y1413778D01*
X630853Y1414022D01*
X630670Y1414265D01*
Y1414326D01*
X630244Y1414812D01*
X629818Y1415177D01*
X629454Y1415360D01*
X629210Y1415420D01*
X629149Y1415481D01*
X628724Y1415542D01*
X628663Y1415603D01*
X627690Y1415664D01*
X626960D01*
X626899Y1415603D01*
G37*
G36*
G01X612181Y1415116D02*
X611999Y1414873D01*
X611938Y1414691D01*
X611755Y1414447D01*
X611694Y1414265D01*
X611512Y1414022D01*
X611451Y1413839D01*
X611269Y1413596D01*
X611147Y1413292D01*
X610964Y1413049D01*
X610904Y1412866D01*
X610721Y1412623D01*
X610660Y1412440D01*
X610478Y1412197D01*
X610417Y1412014D01*
X610235Y1411771D01*
X610113Y1411467D01*
X609930Y1411224D01*
X609870Y1411042D01*
X609687Y1410798D01*
X609627Y1410616D01*
X609444Y1410372D01*
X609383Y1410190D01*
X609201Y1409947D01*
X609140Y1409764D01*
X608958Y1409521D01*
X608836Y1409217D01*
X608653Y1408973D01*
X608593Y1408791D01*
X608410Y1408548D01*
X608349Y1408366D01*
X608167Y1408122D01*
Y1408061D01*
X608045Y1407940D01*
X607984Y1408001D01*
X607923Y1408973D01*
X607863Y1409035D01*
X607802Y1410190D01*
X607741Y1410251D01*
X607680Y1411467D01*
X607619Y1411528D01*
X607559Y1412684D01*
X607498Y1412744D01*
X607437Y1413961D01*
X607376Y1414022D01*
X607316Y1415177D01*
X607254Y1415238D01*
Y1415360D01*
X602389D01*
X602450Y1415299D01*
X602511Y1414691D01*
X602571Y1414630D01*
X602632Y1414022D01*
X602693Y1413961D01*
X602754Y1413413D01*
X602815Y1413353D01*
X602876Y1412744D01*
X602936Y1412684D01*
X602997Y1412075D01*
X603058Y1412014D01*
X603119Y1411467D01*
X603180Y1411407D01*
X603240Y1410798D01*
X603301Y1410737D01*
X603362Y1410129D01*
X603423Y1410068D01*
X603484Y1409521D01*
X603545Y1409460D01*
X603605Y1408852D01*
X603666Y1408791D01*
X603727Y1408183D01*
X603788Y1408122D01*
X603849Y1407575D01*
X603910Y1407514D01*
X603970Y1406906D01*
X604031Y1406845D01*
X604092Y1406237D01*
X604153Y1406176D01*
X604214Y1405629D01*
X604275Y1405568D01*
X604335Y1404960D01*
X604396Y1404899D01*
X604457Y1404290D01*
X604517Y1404230D01*
X604579Y1403683D01*
X604639Y1403622D01*
X604700Y1403013D01*
X604761Y1402953D01*
X604822Y1402344D01*
X604882Y1402283D01*
X604761Y1402040D01*
X604579Y1401797D01*
X604457Y1401493D01*
X604275Y1401249D01*
X604214Y1401067D01*
X604031Y1400824D01*
X603970Y1400642D01*
X603788Y1400398D01*
X603727Y1400216D01*
X603545Y1399972D01*
X603423Y1399668D01*
X603240Y1399425D01*
X603180Y1399242D01*
X602997Y1398999D01*
X602936Y1398817D01*
X602754Y1398573D01*
X602693Y1398391D01*
X602511Y1398148D01*
X602389Y1397844D01*
X602206Y1397600D01*
X602146Y1397418D01*
X601963Y1397175D01*
X601903Y1396992D01*
X601720Y1396749D01*
X601659Y1396566D01*
X601477Y1396323D01*
X601355Y1396019D01*
X601234Y1395897D01*
X606342D01*
X606403Y1396080D01*
X606586Y1396323D01*
X606646Y1396506D01*
X606829Y1396749D01*
X606890Y1396931D01*
X607072Y1397175D01*
X607194Y1397479D01*
X607376Y1397722D01*
X607437Y1397905D01*
X607619Y1398148D01*
X607680Y1398330D01*
X607863Y1398573D01*
X607923Y1398756D01*
X608106Y1398999D01*
X608228Y1399303D01*
X608410Y1399547D01*
X608471Y1399729D01*
X608653Y1399972D01*
X608714Y1400155D01*
X608897Y1400398D01*
X608958Y1400581D01*
X609140Y1400824D01*
X609201Y1401006D01*
X609383Y1401249D01*
X609505Y1401554D01*
X609687Y1401797D01*
X609748Y1401979D01*
X609930Y1402223D01*
X609991Y1402405D01*
X610174Y1402648D01*
X610235Y1402831D01*
X610417Y1403074D01*
X610539Y1403378D01*
X610721Y1403622D01*
X610782Y1403804D01*
X610964Y1404047D01*
X611025Y1404230D01*
X611208Y1404473D01*
X611269Y1404655D01*
X611451Y1404899D01*
X611573Y1405203D01*
X611755Y1405446D01*
X611816Y1405629D01*
X611999Y1405872D01*
X612059Y1406054D01*
X612242Y1406297D01*
X612303Y1406480D01*
X612485Y1406723D01*
X612546Y1406906D01*
X612728Y1407149D01*
X612850Y1407453D01*
X613032Y1407696D01*
X613093Y1407879D01*
X613276Y1408122D01*
X613336Y1408305D01*
X613519Y1408548D01*
X613580Y1408730D01*
X613762Y1408973D01*
X613884Y1409278D01*
X614066Y1409521D01*
X614127Y1409703D01*
X614310Y1409947D01*
X614370Y1410129D01*
X614553Y1410372D01*
X614614Y1410555D01*
X614796Y1410798D01*
X614918Y1411102D01*
X615100Y1411346D01*
X615161Y1411528D01*
X615343Y1411771D01*
X615404Y1411954D01*
X615587Y1412197D01*
X615647Y1412379D01*
X615830Y1412623D01*
X615952Y1412927D01*
X616134Y1413170D01*
X616195Y1413353D01*
X616377Y1413596D01*
X616438Y1413778D01*
X616621Y1414022D01*
X616682Y1414204D01*
X616864Y1414447D01*
X616925Y1414630D01*
X617107Y1414873D01*
X617229Y1415177D01*
X617351Y1415299D01*
Y1415420D01*
X612303D01*
X612181Y1415116D01*
G37*
G36*
G01X578001Y1414812D02*
X578061Y1414751D01*
X578122Y1413961D01*
X578183Y1413900D01*
X578244Y1413170D01*
X578304Y1413109D01*
X578366Y1412379D01*
X578426Y1412319D01*
X578487Y1411589D01*
X578548Y1411528D01*
X578609Y1410798D01*
X578669Y1410737D01*
X578730Y1410008D01*
X578791Y1409947D01*
X578852Y1409156D01*
X578913Y1409095D01*
X578974Y1408366D01*
X579034Y1408305D01*
X579095Y1407575D01*
X579156Y1407514D01*
X579217Y1406784D01*
X579278Y1406723D01*
X579338Y1405994D01*
X579399Y1405933D01*
X579460Y1405203D01*
X579521Y1405142D01*
X579582Y1404351D01*
X579643Y1404290D01*
X579703Y1403561D01*
X579764Y1403500D01*
X579825Y1402770D01*
X579886Y1402709D01*
Y1402405D01*
X584386D01*
X584508Y1402648D01*
X584691Y1402892D01*
X584812Y1403196D01*
X584995Y1403439D01*
X585116Y1403743D01*
X585299Y1403986D01*
X585421Y1404290D01*
X585603Y1404534D01*
X585725Y1404838D01*
X585907Y1405081D01*
X586029Y1405385D01*
X586211Y1405629D01*
X586272Y1405811D01*
X586454Y1406054D01*
X586576Y1406359D01*
X586758Y1406602D01*
X586880Y1406906D01*
X587063Y1407149D01*
X587184Y1407453D01*
X587367Y1407696D01*
X587488Y1408001D01*
X587671Y1408244D01*
X587792Y1408548D01*
X587975Y1408791D01*
X588036Y1408973D01*
X588218Y1409217D01*
X588340Y1409521D01*
X588522Y1409764D01*
X588705Y1410129D01*
X588766Y1410068D01*
X588826Y1409582D01*
X588887Y1408852D01*
X588948Y1408487D01*
X589009Y1407636D01*
X589069Y1407575D01*
X589130Y1406480D01*
X589191Y1406419D01*
X589252Y1405325D01*
X589313Y1405264D01*
X589374Y1404108D01*
X589434Y1404047D01*
X589495Y1402953D01*
X589556Y1402892D01*
Y1402405D01*
X593996D01*
X594117Y1402648D01*
X594300Y1402892D01*
X594361Y1403074D01*
X594543Y1403318D01*
X594604Y1403500D01*
X594787Y1403743D01*
X594847Y1403925D01*
X595030Y1404169D01*
X595091Y1404351D01*
X595273Y1404595D01*
X595334Y1404777D01*
X595516Y1405020D01*
X595577Y1405203D01*
X595760Y1405446D01*
X595821Y1405629D01*
X596003Y1405872D01*
X596064Y1406054D01*
X596246Y1406297D01*
X596368Y1406602D01*
X596551Y1406845D01*
X596611Y1407027D01*
X596793Y1407271D01*
X596854Y1407453D01*
X597037Y1407696D01*
X597098Y1407879D01*
X597280Y1408122D01*
X597341Y1408305D01*
X597523Y1408548D01*
X597584Y1408730D01*
X597767Y1408973D01*
X597828Y1409156D01*
X598010Y1409399D01*
X598071Y1409582D01*
X598253Y1409825D01*
X598314Y1410008D01*
X598497Y1410251D01*
X598557Y1410433D01*
X598740Y1410677D01*
X598862Y1410981D01*
X599044Y1411224D01*
X599105Y1411407D01*
X599287Y1411650D01*
X599348Y1411832D01*
X599530Y1412075D01*
X599591Y1412258D01*
X599774Y1412501D01*
X599834Y1412684D01*
X600017Y1412927D01*
X600078Y1413109D01*
X600260Y1413353D01*
X600321Y1413535D01*
X600504Y1413778D01*
X600564Y1413961D01*
X600747Y1414204D01*
X600808Y1414386D01*
X600990Y1414630D01*
X601112Y1414934D01*
X601294Y1415177D01*
X601355Y1415299D01*
Y1415360D01*
X596307D01*
X596064Y1414873D01*
X596003Y1414630D01*
X595821Y1414326D01*
X595760Y1414083D01*
X595638Y1413900D01*
X595577Y1413657D01*
X595395Y1413353D01*
X595334Y1413109D01*
X595151Y1412805D01*
X595091Y1412562D01*
X594969Y1412379D01*
X594908Y1412136D01*
X594726Y1411832D01*
X594665Y1411589D01*
X594482Y1411285D01*
X594422Y1411042D01*
X594300Y1410859D01*
X594239Y1410616D01*
X594057Y1410312D01*
X593996Y1410068D01*
X593814Y1409764D01*
X593753Y1409521D01*
X593631Y1409338D01*
X593570Y1409095D01*
X593388Y1408791D01*
X593327Y1408548D01*
X593145Y1408244D01*
X593084Y1408001D01*
X592962Y1407818D01*
X592901Y1407575D01*
X592719Y1407271D01*
X592658Y1407331D01*
X592597Y1408305D01*
X592536Y1408670D01*
X592475Y1409643D01*
X592415Y1410008D01*
X592354Y1410981D01*
X592293Y1411346D01*
X592232Y1412319D01*
X592171Y1412684D01*
X592110Y1413657D01*
X592050Y1414022D01*
X591989Y1414995D01*
X591928Y1415360D01*
X587427D01*
Y1415299D01*
X587245Y1415055D01*
X587063Y1414630D01*
X586880Y1414386D01*
X586698Y1413961D01*
X586515Y1413718D01*
X586333Y1413292D01*
X586150Y1413049D01*
X586029Y1412744D01*
X585846Y1412501D01*
X585664Y1412075D01*
X585481Y1411832D01*
X585299Y1411407D01*
X585116Y1411163D01*
X584934Y1410737D01*
X584751Y1410494D01*
X584630Y1410190D01*
X584447Y1409947D01*
X584265Y1409521D01*
X584082Y1409278D01*
X583900Y1408852D01*
X583717Y1408609D01*
X583535Y1408183D01*
X583353Y1407940D01*
X583231Y1407636D01*
X583049Y1407392D01*
X582927Y1407149D01*
X582866Y1407210D01*
X582805Y1408548D01*
X582744Y1409278D01*
X582684Y1410616D01*
X582623Y1411346D01*
X582562Y1412684D01*
X582501Y1413535D01*
X582440Y1414751D01*
X582380Y1415360D01*
X577940D01*
X578001Y1414812D01*
G37*
G36*
G01X575081Y1421807D02*
X574595Y1421746D01*
X574412Y1421624D01*
X574169Y1421563D01*
X573926Y1421442D01*
X573621Y1421198D01*
X573561D01*
X572892Y1420468D01*
Y1420408D01*
X572709Y1420164D01*
X572588Y1419921D01*
X572527Y1419617D01*
X572466Y1419556D01*
X572405Y1418948D01*
X572466Y1418157D01*
X572527Y1418096D01*
X572588Y1417853D01*
X572770Y1417610D01*
Y1417549D01*
X573317Y1417062D01*
X573378D01*
X573500Y1416941D01*
X573743Y1416880D01*
X573804Y1416819D01*
X574291Y1416759D01*
X574351Y1416697D01*
X575325Y1416759D01*
X575385Y1416819D01*
X575690Y1416880D01*
X575750Y1416941D01*
X575993Y1417002D01*
X576237Y1417123D01*
X576602Y1417427D01*
X576662D01*
X577332Y1418157D01*
X577392Y1418340D01*
X577575Y1418583D01*
X577636Y1418826D01*
X577697Y1418887D01*
X577757Y1419374D01*
X577818Y1419435D01*
X577757Y1420347D01*
X577697Y1420408D01*
X577636Y1420651D01*
X577514Y1420894D01*
X577088Y1421381D01*
X576845Y1421563D01*
X576480Y1421746D01*
X576054Y1421807D01*
X575993Y1421867D01*
X575142D01*
X575081Y1421807D01*
G37*
G36*
G01X571554Y1414995D02*
X571493Y1414934D01*
X571432Y1414447D01*
X571371Y1414386D01*
X571310Y1413900D01*
X571250Y1413839D01*
X571189Y1413292D01*
X571128Y1413231D01*
X571067Y1412744D01*
X571006Y1412684D01*
X570945Y1412197D01*
X570885Y1412136D01*
X570824Y1411589D01*
X570763Y1411528D01*
X570702Y1411042D01*
X570641Y1410981D01*
X570580Y1410494D01*
X570520Y1410433D01*
X570459Y1409886D01*
X570398Y1409825D01*
X570337Y1409338D01*
X570277Y1409278D01*
X570216Y1408791D01*
X570155Y1408730D01*
X570094Y1408183D01*
X570033Y1408122D01*
X569972Y1407636D01*
X569912Y1407575D01*
X569851Y1407088D01*
X569790Y1407027D01*
X569729Y1406480D01*
X569668Y1406419D01*
X569608Y1405933D01*
X569547Y1405872D01*
X569486Y1405385D01*
X569425Y1405325D01*
X569364Y1404777D01*
X569303Y1404716D01*
X569243Y1404230D01*
X569182Y1404169D01*
X569121Y1403683D01*
X569060Y1403622D01*
X568999Y1403074D01*
X568938Y1403013D01*
X568878Y1402527D01*
X568817Y1402466D01*
Y1402405D01*
X574169D01*
X574230Y1402770D01*
X574291Y1402831D01*
X574351Y1403318D01*
X574412Y1403378D01*
X574473Y1403925D01*
X574534Y1403986D01*
X574595Y1404473D01*
X574655Y1404534D01*
X574716Y1405020D01*
X574777Y1405081D01*
X574838Y1405629D01*
X574899Y1405689D01*
X574960Y1406176D01*
X575020Y1406237D01*
X575081Y1406723D01*
X575142Y1406784D01*
X575203Y1407331D01*
X575264Y1407392D01*
X575325Y1407879D01*
X575385Y1407940D01*
X575446Y1408426D01*
X575507Y1408487D01*
X575568Y1409035D01*
X575629Y1409095D01*
X575690Y1409582D01*
X575750Y1409643D01*
X575811Y1410129D01*
X575872Y1410190D01*
X575933Y1410677D01*
X575993Y1410737D01*
X576054Y1411285D01*
X576115Y1411346D01*
X576176Y1411832D01*
X576237Y1411893D01*
X576297Y1412379D01*
X576358Y1412440D01*
X576419Y1412988D01*
X576480Y1413049D01*
X576541Y1413535D01*
X576602Y1413596D01*
X576662Y1414083D01*
X576723Y1414143D01*
X576784Y1414691D01*
X576845Y1414751D01*
X576906Y1415238D01*
X576967Y1415299D01*
Y1415360D01*
X571614D01*
X571554Y1414995D01*
G37*
G36*
G01X649645Y1417853D02*
X649767Y1417610D01*
X649220D01*
X649159Y1417671D01*
X648977Y1418096D01*
X648794Y1418340D01*
Y1418461D01*
X648612Y1418522D01*
X648186Y1418583D01*
Y1417610D01*
X647760D01*
Y1419406D01*
X648186D01*
Y1418948D01*
X648490D01*
X649098Y1419009D01*
X649159Y1419191D01*
X649098Y1419556D01*
X648916D01*
X648855Y1419617D01*
X648186D01*
Y1419407D01*
X647760D01*
Y1419982D01*
X648916D01*
X649280Y1419921D01*
X649524Y1419738D01*
X649585Y1419496D01*
X649645Y1419435D01*
X649585Y1419070D01*
X649341Y1418766D01*
X649098Y1418705D01*
X649037Y1418644D01*
X649159Y1418522D01*
X649220D01*
X649280Y1418461D01*
X649402Y1418279D01*
X649463Y1418096D01*
X649645Y1417853D01*
G37*
G36*
G01X650132Y1417123D02*
X649828Y1416880D01*
X649585Y1416819D01*
X649402Y1416697D01*
X648368Y1416637D01*
X648308Y1416697D01*
X647943Y1416759D01*
X647578Y1416941D01*
X647334Y1417123D01*
X646909Y1417610D01*
X646666Y1418096D01*
X646604Y1419009D01*
X646605Y1419015D01*
X646990D01*
X646969Y1418826D01*
X647030Y1418218D01*
X647152Y1417975D01*
X647395Y1417671D01*
Y1417610D01*
X647821Y1417245D01*
X648064Y1417123D01*
X648490Y1417062D01*
X648551Y1417002D01*
X649280Y1417062D01*
X649341Y1417123D01*
X649585Y1417184D01*
X649950Y1417488D01*
X650375Y1417975D01*
X650436Y1418218D01*
X650497Y1418279D01*
X650558Y1418705D01*
X650497Y1419313D01*
X650436Y1419374D01*
X650375Y1419617D01*
X650071Y1419982D01*
Y1420103D01*
X649950D01*
X649585Y1420408D01*
X649463D01*
X649402Y1420468D01*
X649037Y1420529D01*
X648977Y1420590D01*
X648247Y1420529D01*
X648186Y1420468D01*
X647943Y1420408D01*
X647699Y1420225D01*
X647638D01*
X647213Y1419738D01*
X647030Y1419374D01*
X646990Y1419016D01*
X646605D01*
X646666Y1419496D01*
X646909Y1419982D01*
X647091Y1420225D01*
X647578Y1420651D01*
X647943Y1420833D01*
X648308Y1420894D01*
X648368Y1420955D01*
X649159D01*
X649220Y1420894D01*
X649585Y1420833D01*
X649828Y1420712D01*
X650132Y1420468D01*
X650193D01*
X650619Y1419982D01*
X650740Y1419738D01*
X650801Y1419496D01*
X650862Y1419435D01*
X650923Y1418340D01*
X650862Y1418279D01*
X650801Y1417975D01*
X650619Y1417610D01*
X650193Y1417123D01*
X650132D01*
G37*
G36*
G01X642347Y1415603D02*
X641617Y1415542D01*
X641556Y1415481D01*
X641131Y1415420D01*
X641070Y1415360D01*
X640766Y1415299D01*
X640584Y1415177D01*
X640340Y1415116D01*
X639732Y1414812D01*
X639428Y1414569D01*
X639367D01*
X639002Y1414265D01*
X638941D01*
X638029Y1413353D01*
X637968Y1413413D01*
X638029Y1413839D01*
X638090Y1413900D01*
X638151Y1414386D01*
X638212Y1414447D01*
X638272Y1414934D01*
X638333Y1414995D01*
X638394Y1415299D01*
Y1415360D01*
X633772D01*
X633711Y1415299D01*
X633650Y1414812D01*
X633589Y1414751D01*
X633529Y1414204D01*
X633467Y1414143D01*
X633407Y1413657D01*
X633346Y1413596D01*
X633285Y1413109D01*
X633224Y1413049D01*
X633164Y1412501D01*
X633103Y1412440D01*
X633042Y1411954D01*
X632981Y1411893D01*
X632920Y1411407D01*
X632859Y1411346D01*
X632799Y1410859D01*
X632738Y1410798D01*
X632677Y1410251D01*
X632616Y1410190D01*
X632555Y1409703D01*
X632495Y1409643D01*
X632434Y1409156D01*
X632373Y1409095D01*
X632312Y1408548D01*
X632251Y1408487D01*
X632190Y1408001D01*
X632130Y1407940D01*
X632069Y1407453D01*
X632008Y1407392D01*
X631947Y1406845D01*
X631886Y1406784D01*
X631825Y1406297D01*
X631765Y1406237D01*
X631704Y1405750D01*
X631643Y1405689D01*
X631582Y1405203D01*
X631521Y1405142D01*
X631460Y1404595D01*
X631400Y1404534D01*
X631339Y1404047D01*
X631278Y1403986D01*
X631217Y1403500D01*
X631156Y1403439D01*
X631096Y1402892D01*
X631035Y1402831D01*
X630974Y1402405D01*
X635961D01*
X636022Y1402770D01*
X636083Y1402831D01*
X636143Y1403378D01*
X636204Y1403439D01*
X636265Y1403925D01*
X636326Y1403986D01*
X636387Y1404473D01*
X636448Y1404534D01*
X636508Y1405020D01*
X636569Y1405081D01*
X636630Y1405568D01*
X636691Y1405629D01*
X636752Y1406176D01*
X636813Y1406237D01*
X636873Y1406723D01*
X636934Y1406784D01*
X636995Y1407271D01*
X637056Y1407331D01*
X637117Y1407818D01*
X637178Y1407879D01*
X637238Y1408366D01*
X637299Y1408426D01*
X637360Y1408852D01*
X637421Y1408913D01*
X637482Y1409217D01*
X637543Y1409278D01*
X637603Y1409521D01*
X637664Y1409582D01*
X637725Y1409825D01*
X637786Y1409886D01*
X637847Y1410129D01*
X638029Y1410372D01*
X638090Y1410555D01*
X638333Y1410859D01*
Y1410920D01*
X638759Y1411407D01*
X638820D01*
X639245Y1411771D01*
X639610Y1411954D01*
X640097Y1412014D01*
X640158Y1412075D01*
X640766Y1412014D01*
X641009Y1411832D01*
X641131D01*
Y1411710D01*
X641253Y1411589D01*
X641313Y1411224D01*
X641374Y1411163D01*
X641313Y1410433D01*
X641253Y1410372D01*
X641191Y1409764D01*
X641131Y1409703D01*
X641070Y1409156D01*
X641009Y1409095D01*
X640948Y1408609D01*
X640888Y1408548D01*
X640827Y1408001D01*
X640766Y1407940D01*
X640705Y1407453D01*
X640644Y1407392D01*
X640584Y1406906D01*
X640523Y1406845D01*
X640462Y1406297D01*
X640401Y1406237D01*
X640340Y1405750D01*
X640279Y1405689D01*
X640219Y1405142D01*
X640158Y1405081D01*
X640097Y1404595D01*
X640036Y1404534D01*
X639975Y1404047D01*
X639914Y1403986D01*
X639854Y1403439D01*
X639793Y1403378D01*
X639732Y1402892D01*
X639671Y1402831D01*
X639610Y1402405D01*
X644597D01*
X644658Y1402892D01*
X644719Y1402953D01*
X644780Y1403439D01*
X644841Y1403500D01*
X644902Y1404047D01*
X644962Y1404108D01*
X645023Y1404595D01*
X645084Y1404655D01*
X645145Y1405203D01*
X645206Y1405264D01*
X645267Y1405750D01*
X645327Y1405811D01*
X645388Y1406297D01*
X645449Y1406359D01*
X645510Y1406906D01*
X645571Y1406966D01*
X645631Y1407453D01*
X645692Y1407514D01*
X645753Y1408061D01*
X645814Y1408122D01*
X645875Y1408609D01*
X645936Y1408670D01*
X645996Y1409217D01*
X646057Y1409278D01*
X646118Y1409764D01*
X646179Y1409825D01*
X646240Y1410372D01*
X646301Y1410433D01*
X646361Y1411042D01*
X646422Y1411102D01*
X646483Y1411832D01*
X646544Y1411893D01*
X646483Y1413474D01*
X646422Y1413535D01*
X646361Y1413778D01*
X646301Y1413839D01*
Y1413961D01*
X646118Y1414204D01*
Y1414265D01*
X645692Y1414751D01*
X645206Y1415177D01*
X644719Y1415420D01*
X644415Y1415481D01*
X644354Y1415542D01*
X643746Y1415603D01*
X643685Y1415664D01*
X642408D01*
X642347Y1415603D01*
G37*
G36*
G01X741000Y1500300D02*
Y1502100D01*
X746400D01*
Y1500300D01*
X741000D01*
G37*
G36*
G01X752700D02*
Y1502100D01*
X758100D01*
Y1500300D01*
X752700D01*
G37*
G36*
G01X750900Y1492200D02*
Y1510200D01*
X752700D01*
Y1492200D01*
X750900D01*
G37*
G36*
G01X746400D02*
Y1510200D01*
X748200D01*
Y1492200D01*
X746400D01*
G37*
G36*
G01X739200D02*
Y1510200D01*
X741000D01*
Y1492200D01*
X739200D01*
G37*
G36*
G01X752700Y1508400D02*
Y1510200D01*
X759900D01*
Y1508400D01*
X752700D01*
G37*
G36*
G01X832740Y197463D02*
X824740D01*
Y188363D01*
X832740D01*
Y197463D01*
G37*
G36*
G01Y1811637D02*
X824740D01*
Y1802537D01*
X832740D01*
Y1811637D01*
G37*
G36*
G01X818039Y1932907D02*
X806839D01*
Y1950357D01*
X818039D01*
Y1932907D01*
G37*
G36*
G01X851100Y341300D02*
X839900D01*
Y358750D01*
X851100D01*
Y341300D01*
G37*
G36*
G01Y746800D02*
X839900D01*
Y764250D01*
X851100D01*
Y746800D01*
G37*
G36*
G01Y1152300D02*
X839900D01*
Y1169750D01*
X851100D01*
Y1152300D01*
G37*
G36*
G01Y1557800D02*
X839900D01*
Y1575250D01*
X851100D01*
Y1557800D01*
G37*
G36*
G01X903400Y1700100D02*
Y1705100D01*
X898400Y1700100D01*
X903400D01*
G37*
G36*
G01X994328Y1621176D02*
X992328Y1619176D01*
Y1623176D01*
X994328Y1621176D01*
G37*
G54D10*
G01X0Y39059D02*
Y8350D01*
G01Y282366D02*
Y251657D01*
G01Y525673D02*
Y494965D01*
G01Y1023787D02*
Y993079D01*
G01Y1961500D02*
Y1930791D01*
G01X1037402Y25827D02*
Y56535D01*
G01Y315591D02*
Y284882D01*
G01Y543937D02*
Y574646D01*
G01Y833701D02*
Y802992D01*
G01Y1062047D02*
Y1092756D01*
G01Y1351811D02*
Y1321102D01*
G01Y1767835D02*
Y1737126D01*
G01Y1987598D02*
Y1956890D01*
G01X1127953Y313461D02*
G03Y302989I0J-5236D01*
G01Y344957D02*
G03Y334484I0J-5236D01*
G01Y376452D02*
G03Y365979I0J-5236D01*
G01Y407947D02*
G03Y397474I0J-5236D01*
G01Y439442D02*
G03Y428969I0J-5236D01*
G01Y470937D02*
G03Y460465I0J-5236D01*
G54D11*
G01X-106883Y-224955D02*
Y-304955D01*
G01Y-260455D02*
X1019417D01*
G01X-106883Y-304955D02*
X1019417D01*
G01X-110883Y-208955D02*
G02I-12000J0D01*
G01X-116033D02*
G02I-6850J0D01*
G01X-122883Y-224955D02*
Y-192955D01*
G01X-106883Y-208955D02*
X-138883D01*
G01X-106883Y-224955D02*
X1019417D01*
G01X67135Y204468D02*
Y212068D01*
G01X87700Y344400D02*
X81700D01*
G01X67135Y609980D02*
Y617580D01*
G01X87700Y749900D02*
X81700D01*
G01X67135Y1015491D02*
Y1023091D01*
G01X87700Y1155800D02*
X81700D01*
G01X67135Y1421003D02*
Y1428603D01*
G01X117747Y1499126D02*
X110047D01*
G01X87000Y1551900D02*
X81000D01*
G01X67135Y1826515D02*
Y1834115D01*
G01X57500Y1935900D02*
X51500D01*
G01X165560Y158011D02*
Y165611D01*
G01X156400Y431200D02*
X162400D01*
G01X168928Y550307D02*
X161228D01*
G01X165560Y563523D02*
Y571123D01*
G01X156400Y836700D02*
X162400D01*
G01X165560Y969035D02*
Y976635D01*
G01X156700Y1242200D02*
X162700D01*
G01X165560Y1374546D02*
Y1382146D01*
G01X157900Y1647700D02*
X163900D01*
G01X165560Y1780058D02*
Y1787658D01*
G01X231917Y-224955D02*
Y-304955D01*
G01X205000Y57100D02*
X211000D01*
G01X284000Y1770500D02*
Y1778500D01*
G01X369417Y-224955D02*
Y-304955D01*
G01X351300Y92500D02*
Y84500D01*
G01X484417Y-224955D02*
Y-304955D01*
G01X491848Y1533082D02*
X702078D01*
Y1442822D01*
X491848D01*
Y1533082D01*
G01X651917Y-224955D02*
Y-304955D01*
G01X821917Y-224955D02*
Y-304955D01*
G01X824440Y199913D02*
X816740D01*
G01X816000Y344400D02*
X810000D01*
G01X816000Y749900D02*
X810000D01*
G01X816000Y1155400D02*
X810000D01*
G01X816000Y1560900D02*
X810000D01*
G01X838000Y1704000D02*
X833000D01*
G01X830000D02*
X825000D01*
G01X833000Y1731000D02*
X838000D01*
G01X825000D02*
X830000D01*
G01X824440Y1814087D02*
X816740D01*
G01X780839Y1934907D02*
X774839D01*
G01X893906Y158011D02*
Y165611D01*
G01Y563523D02*
Y571123D01*
G01Y969035D02*
Y976635D01*
G01Y1374546D02*
Y1382146D01*
G01Y1780058D02*
Y1787658D01*
G01X1019417Y-224955D02*
Y-304955D01*
G01X1047417Y-208955D02*
G02I-12000J0D01*
G01X1042267D02*
G02I-6850J0D01*
G01X1035417Y-224955D02*
Y-192955D01*
G01X1051417Y-208955D02*
X1019417D01*
G54D12*
G01X70685Y12647D02*
G02Y21447I0J4400D01*
G01D02*
X74985D01*
G01D02*
G02Y12647I0J-4400D01*
G01D02*
X70685D01*
G01Y185875D02*
G02Y194675I0J4400D01*
G01X74985D02*
G02Y185875I0J-4400D01*
G01D02*
X70685D01*
G01Y194675D02*
X74985D01*
G01X70685Y418159D02*
G02Y426959I0J4400D01*
G01D02*
X74985D01*
G01D02*
G02Y418159I0J-4400D01*
G01D02*
X70685D01*
G01Y591387D02*
G02Y600187I0J4400D01*
G01D02*
X74985D01*
G01D02*
G02Y591387I0J-4400D01*
G01D02*
X70685D01*
G01Y823671D02*
G02Y832471I0J4400D01*
G01D02*
X74985D01*
G01D02*
G02Y823671I0J-4400D01*
G01D02*
X70685D01*
G01Y996899D02*
G02Y1005699I0J4400D01*
G01D02*
X74985D01*
G01D02*
G02Y996899I0J-4400D01*
G01D02*
X70685D01*
G01Y1229183D02*
G02Y1237983I0J4400D01*
G01D02*
X74985D01*
G01D02*
G02Y1229183I0J-4400D01*
G01D02*
X70685D01*
G01Y1402411D02*
G02Y1411211I0J4400D01*
G01D02*
X74985D01*
G01D02*
G02Y1402411I0J-4400D01*
G01D02*
X70685D01*
G01Y1634695D02*
G02Y1643495I0J4400D01*
G01D02*
X74985D01*
G01D02*
G02Y1634695I0J-4400D01*
G01D02*
X70685D01*
G01Y1807923D02*
G02Y1816723I0J4400D01*
G01D02*
X74985D01*
G01D02*
G02Y1807923I0J-4400D01*
G01D02*
X70685D01*
G01X173410Y184203D02*
G02Y175403I0J-4400D01*
G01D02*
X169110D01*
G01D02*
G02Y184203I0J4400D01*
G01D02*
X173410D01*
G01Y357431D02*
G02Y348631I0J-4400D01*
G01D02*
X169110D01*
G01D02*
G02Y357431I0J4400D01*
G01D02*
X173410D01*
G01Y589715D02*
G02Y580915I0J-4400D01*
G01D02*
X169110D01*
G01D02*
G02Y589715I0J4400D01*
G01D02*
X173410D01*
G01Y762943D02*
G02Y754143I0J-4400D01*
G01D02*
X169110D01*
G01D02*
G02Y762943I0J4400D01*
G01D02*
X173410D01*
G01Y995227D02*
G02Y986427I0J-4400D01*
G01D02*
X169110D01*
G01D02*
G02Y995227I0J4400D01*
G01D02*
X173410D01*
G01Y1168455D02*
G02Y1159655I0J-4400D01*
G01D02*
X169110D01*
G01D02*
G02Y1168455I0J4400D01*
G01D02*
X173410D01*
G01Y1400739D02*
G02Y1391939I0J-4400D01*
G01D02*
X169110D01*
G01D02*
G02Y1400739I0J4400D01*
G01D02*
X173410D01*
G01Y1573967D02*
G02Y1565167I0J-4400D01*
G01D02*
X169110D01*
G01D02*
G02Y1573967I0J4400D01*
G01D02*
X173410D01*
G01Y1806251D02*
G02Y1797451I0J-4400D01*
G01D02*
X169110D01*
G01D02*
G02Y1806251I0J4400D01*
G01D02*
X173410D01*
G01Y1979479D02*
G02Y1970679I0J-4400D01*
G01D02*
X169110D01*
G01D02*
G02Y1979479I0J4400D01*
G01D02*
X173410D01*
G01X901756Y184203D02*
G02Y175403I0J-4400D01*
G01D02*
X897456D01*
G01D02*
G02Y184203I0J4400D01*
G01D02*
X901756D01*
G01Y357431D02*
G02Y348631I0J-4400D01*
G01D02*
X897456D01*
G01D02*
G02Y357431I0J4400D01*
G01D02*
X901756D01*
G01Y589715D02*
G02Y580915I0J-4400D01*
G01D02*
X897456D01*
G01D02*
G02Y589715I0J4400D01*
G01D02*
X901756D01*
G01Y762943D02*
G02Y754143I0J-4400D01*
G01D02*
X897456D01*
G01D02*
G02Y762943I0J4400D01*
G01D02*
X901756D01*
G01Y995227D02*
G02Y986427I0J-4400D01*
G01D02*
X897456D01*
G01D02*
G02Y995227I0J4400D01*
G01D02*
X901756D01*
G01Y1168455D02*
G02Y1159655I0J-4400D01*
G01D02*
X897456D01*
G01D02*
G02Y1168455I0J4400D01*
G01D02*
X901756D01*
G01Y1400739D02*
G02Y1391939I0J-4400D01*
G01D02*
X897456D01*
G01D02*
G02Y1400739I0J4400D01*
G01D02*
X901756D01*
G01Y1573967D02*
G02Y1565167I0J-4400D01*
G01D02*
X897456D01*
G01D02*
G02Y1573967I0J4400D01*
G01D02*
X901756D01*
G01Y1806251D02*
G02Y1797451I0J-4400D01*
G01D02*
X897456D01*
G01D02*
G02Y1806251I0J4400D01*
G01D02*
X901756D01*
G01Y1979479D02*
G02Y1970679I0J-4400D01*
G01D02*
X897456D01*
G01D02*
G02Y1979479I0J4400D01*
G01D02*
X901756D01*
G54D13*
G01X101581Y241823D02*
Y238973D01*
X98881D01*
G01X101581Y647335D02*
Y644485D01*
X98881D01*
G01X101581Y1052846D02*
Y1049996D01*
X98881D01*
G01X101581Y1458358D02*
Y1455508D01*
X98881D01*
G01X85600Y1843300D02*
X82750D01*
Y1846000D01*
G01X159054Y141053D02*
Y143903D01*
X161754D01*
G01X150900Y552900D02*
X148050D01*
Y555600D01*
G01X159054Y1356588D02*
Y1359438D01*
X161754D01*
G01X187400Y945900D02*
X184550D01*
Y948600D01*
G01X211446Y1769400D02*
Y1766550D01*
X208746D01*
G01X888400Y140053D02*
Y142903D01*
X891100D01*
G01X887400Y545565D02*
Y548415D01*
X890100D01*
G01X887400Y951077D02*
Y953927D01*
X890100D01*
G01X887400Y1356588D02*
Y1359438D01*
X890100D01*
G01X887400Y1762100D02*
Y1764950D01*
X890100D01*
G01X994278Y1621876D02*
Y1620376D01*
G54D14*
G01X103700Y360300D02*
X111400D01*
G01X103700Y765800D02*
X111400D01*
G01X103700Y1171700D02*
X111400D01*
G01X103200Y1571900D02*
X110900D01*
G01X76000Y1951800D02*
X83700D01*
G01X189000Y41200D02*
X181300D01*
G01X140400Y415300D02*
X132700D01*
G01X140400Y820800D02*
X132700D01*
G01X140700Y1226300D02*
X133000D01*
G01X141900Y1631800D02*
X134200D01*
G01X832000Y360300D02*
X839700D01*
G01X832000Y765800D02*
X839700D01*
G01X832000Y1171300D02*
X839700D01*
G01X832000Y1576800D02*
X839700D01*
G01X798939Y1951907D02*
X806639D01*
G54D15*
G01X765450Y1501200D02*
G03I-16350J0D01*
G54D16*
G01X561670Y1174590D02*
X561010D01*
G01X561110Y1174680D02*
X561770D01*
G01X561860Y1174790D02*
X561210D01*
G01X561310Y1174880D02*
X561960D01*
G01X562060Y1174990D02*
X561400D01*
G01X561500Y1175090D02*
X562150D01*
G01X562250Y1175180D02*
X561600D01*
G01X561690Y1175290D02*
X562350D01*
G01X562440Y1175380D02*
X561790D01*
G01X561880Y1175490D02*
X562540D01*
G01X562640Y1175590D02*
X561980D01*
G01X562080Y1175680D02*
X562730D01*
G01X562830Y1175790D02*
X562185D01*
G01X562180D02*
X562230D01*
G01X562270Y1175880D02*
X562310D01*
G01X562270D02*
X562920D01*
G01X563020Y1175990D02*
X562370D01*
G01X562470Y1176090D02*
X563120D01*
G01X563220Y1176180D02*
X562560D01*
G01X562660Y1176290D02*
X563310D01*
G01X563410Y1176380D02*
X562750D01*
G01X562850Y1176490D02*
X563510D01*
G01X563600Y1176590D02*
X562950D01*
G01X563050Y1176680D02*
X563700D01*
G01X563790Y1176790D02*
X563140D01*
G01X563240Y1176880D02*
X563890D01*
G01X563990Y1176990D02*
X563330D01*
G01X563430Y1177090D02*
X564090D01*
G01X564180Y1177180D02*
X563530D01*
G01X563620Y1177290D02*
X564280D01*
G01X564470Y1177490D02*
X563820D01*
G01X564010Y1177680D02*
X564660D01*
G01X559370Y1192100D02*
X559400Y1192120D01*
G01X559370Y1191560D02*
Y1192100D01*
G01X559380Y1191540D02*
X559370Y1191560D01*
G01X559430Y1191430D02*
X559380Y1191540D01*
G01X559440Y1191420D02*
X559430Y1191430D01*
G01X564620Y1185830D02*
X559440Y1191420D01*
G01X559370Y1192090D02*
X559430D01*
G01X559370Y1191990D02*
X559520D01*
G01X559610Y1191880D02*
X559370D01*
G01Y1191790D02*
X559710D01*
G01X559800Y1191680D02*
X559370D01*
G01Y1191590D02*
X559890D01*
G01X559990Y1191490D02*
X559400D01*
G01X559470Y1191380D02*
X560080D01*
G01X560170Y1191290D02*
X559560D01*
G01X559650Y1191180D02*
X560260D01*
G01X560360Y1191090D02*
X559750D01*
G01X559840Y1190990D02*
X560450D01*
G01X560540Y1190880D02*
X559930D01*
G01X560020Y1190790D02*
X560640D01*
G01X560730Y1190680D02*
X560120D01*
G01X560210Y1190590D02*
X560820D01*
G01X560920Y1190490D02*
X560300D01*
G01X560400Y1190380D02*
X561010D01*
G01X561100Y1190290D02*
X560490D01*
G01X560580Y1190180D02*
X561200D01*
G01X561290Y1190090D02*
X560680D01*
G01X560770Y1189990D02*
X561380D01*
G01X561480Y1189880D02*
X560860D01*
G01X560950Y1189790D02*
X561570D01*
G01X561660Y1189680D02*
X561050D01*
G01X561140Y1189590D02*
X561750D01*
G01X561850Y1189490D02*
X561230D01*
G01X561330Y1189380D02*
X561940D01*
G01X562030Y1189290D02*
X561420D01*
G01X561510Y1189180D02*
X562120D01*
G01X562220Y1189090D02*
X561610D01*
G01X561700Y1188990D02*
X562310D01*
G01X562400Y1188880D02*
X561790D01*
G01X561880Y1188790D02*
X562500D01*
G01X562590Y1188680D02*
X561980D01*
G01X562070Y1188590D02*
X562680D01*
G01X562780Y1188490D02*
X562160D01*
G01X562250Y1188380D02*
X562870D01*
G01X562960Y1188290D02*
X562350D01*
G01X562440Y1188180D02*
X563060D01*
G01X563150Y1188090D02*
X562530D01*
G01X562620Y1187990D02*
X563240D01*
G01X563340Y1187880D02*
X562720D01*
G01X562810Y1187790D02*
X563430D01*
G01X563520Y1187680D02*
X562900D01*
G01X562990Y1187590D02*
X563620D01*
G01X563710Y1187490D02*
X563090D01*
G01X563180Y1187380D02*
X563800D01*
G01X563890Y1187290D02*
X563270D01*
G01X563370Y1187180D02*
X563990D01*
G01X564080Y1187090D02*
X563460D01*
G01X563550Y1186990D02*
X564170D01*
G01X564270Y1186880D02*
X563650D01*
G01X563830Y1186680D02*
X565070D01*
G01X565080Y1186490D02*
X564020D01*
G01X563770Y1188780D02*
X564280D01*
G01X563730Y1188740D02*
X563770Y1188780D01*
G01X563730Y1188280D02*
Y1188740D01*
G01X563770Y1188240D02*
X563730Y1188280D01*
G01Y1188680D02*
X573980D01*
G01X573910Y1188490D02*
X563730D01*
G01Y1188290D02*
X573750D01*
G01X566380Y1189590D02*
X564950D01*
G01X564370Y1188850D02*
X564280Y1188780D01*
G01X564390Y1188900D02*
X564370Y1188850D01*
G01X564390Y1188910D02*
Y1188900D01*
G01X564510Y1189160D02*
X564390Y1188910D01*
G01X564530Y1189170D02*
X564510Y1189160D01*
G01X564960Y1189590D02*
X564530Y1189170D01*
G01X564290Y1188790D02*
X565020D01*
G01X565130Y1189120D02*
X565240Y1189190D01*
G01X564960Y1188950D02*
X565130Y1189120D01*
G01X564940Y1188840D02*
X564960Y1188950D01*
G01X565030Y1188780D02*
X564940Y1188840D01*
G01X565100Y1189090D02*
X564480D01*
G01X564430Y1188990D02*
X565000D01*
G01X564950Y1188880D02*
X564380D01*
G01X564640Y1189290D02*
X566320D01*
G01Y1189490D02*
X564850D01*
G01X565200Y1185890D02*
X568430Y1182410D01*
G01X565190Y1185890D02*
X565200D01*
G01X565150Y1185940D02*
X565190Y1185890D01*
G01X565120Y1186000D02*
X565150Y1185940D01*
G01X564940Y1188130D02*
X565120Y1186000D01*
G01X565040Y1188240D02*
X564940Y1188130D01*
G01X565460Y1182090D02*
X564990D01*
G01X564980Y1182290D02*
X565440D01*
G01X565420Y1182490D02*
X564960D01*
G01X564940Y1182680D02*
X565410D01*
G01X565390Y1182880D02*
X564920D01*
G01X564900Y1183090D02*
X565370D01*
G01X565360Y1183290D02*
X564890D01*
G01X564870Y1183490D02*
X565340D01*
G01X565320Y1183680D02*
X564850D01*
G01X564840Y1183880D02*
X565310D01*
G01X565290Y1184090D02*
X564820D01*
G01X564800Y1184290D02*
X565270D01*
G01X565250Y1184490D02*
X564790D01*
G01X564770Y1184680D02*
X565240D01*
G01X565220Y1184880D02*
X564750D01*
G01X564740Y1184990D02*
X565250D01*
G01X565750Y1185290D02*
X564720D01*
G01X564700Y1185490D02*
X565570D01*
G01X564640Y1185800D02*
X564620Y1185830D01*
G01X564680Y1185700D02*
X564640Y1185800D01*
G01X564680Y1185690D02*
Y1185700D01*
G01Y1185680D02*
Y1185690D01*
G01X565380Y1185680D02*
X564680D01*
G01X564580Y1185880D02*
X565200D01*
G01X565130Y1185990D02*
X564480D01*
G01X564390Y1186090D02*
X565120D01*
G01X565110Y1186180D02*
X564300D01*
G01X564200Y1186290D02*
X565100D01*
G01X565090Y1186380D02*
X564110D01*
G01X563920Y1186590D02*
X565070D01*
G01X565060Y1186790D02*
X564580D01*
G01X564370Y1188240D02*
X563770D01*
G01X564470Y1188150D02*
X564370Y1188240D01*
G01X564590Y1186800D02*
X564470Y1188150D01*
G01X564430Y1188180D02*
X564990D01*
G01X564940Y1188090D02*
X564480D01*
G01X564490Y1187990D02*
X564960D01*
G01Y1187880D02*
X564490D01*
G01X564500Y1187790D02*
X564970D01*
G01X564980Y1187680D02*
X564510D01*
G01X564520Y1187590D02*
X564990D01*
G01X565000Y1187490D02*
X564530D01*
G01X564540Y1187380D02*
X565010D01*
G01Y1187290D02*
X564550D01*
G01Y1187180D02*
X565020D01*
G01X565030Y1187090D02*
X564570D01*
G01Y1186990D02*
X565040D01*
G01X565050Y1186880D02*
X564580D01*
G01X564420Y1186730D02*
X559400Y1192120D01*
G01X564530Y1186700D02*
X564420Y1186730D01*
G01X564590Y1186800D02*
X564530Y1186700D01*
G01X563740Y1186790D02*
X564360D01*
G01X564680Y1185680D02*
X565120Y1180530D01*
G01X565130Y1180490D02*
X565600D01*
G01X565610Y1180290D02*
X565140D01*
G01X565160Y1180090D02*
X565630D01*
G01X565650Y1179880D02*
X565180D01*
G01X565200Y1179680D02*
X565670D01*
G01X565710Y1179590D02*
X565210D01*
G01X565220Y1178940D02*
X565120Y1178830D01*
G01X565250Y1179010D02*
X565220Y1178940D01*
G01X565070Y1178790D02*
X565760D01*
G01Y1178590D02*
X564880D01*
G01X564690Y1178380D02*
X565780D01*
G01X565140Y1178180D02*
X564490D01*
G01X564400Y1178090D02*
X565050D01*
G01X564950Y1177990D02*
X564300D01*
G01X564200Y1177880D02*
X564860D01*
G01X564760Y1177790D02*
X564110D01*
G01X563920Y1177590D02*
X564570D01*
G01X564370Y1177380D02*
X563720D01*
G01X565100Y1180790D02*
X565570D01*
G01X565550Y1180990D02*
X565090D01*
G01X565070Y1181180D02*
X565540D01*
G01X565520Y1181380D02*
X565050D01*
G01X565030Y1181590D02*
X565500D01*
G01X565490Y1181790D02*
X565020D01*
G01X565010Y1181880D02*
X565480D01*
G01X565470Y1181990D02*
X565000D01*
G01X564980Y1182180D02*
X565450D01*
G01X565440Y1182380D02*
X564970D01*
G01X564950Y1182590D02*
X565420D01*
G01X565400Y1182790D02*
X564930D01*
G01X564920Y1182990D02*
X565380D01*
G01X565360Y1183180D02*
X564900D01*
G01X564880Y1183380D02*
X565350D01*
G01X565330Y1183590D02*
X564860D01*
G01X564850Y1183790D02*
X565310D01*
G01X565300Y1183990D02*
X564830D01*
G01X564810Y1184180D02*
X565280D01*
G01X565260Y1184380D02*
X564790D01*
G01X564780Y1184590D02*
X565240D01*
G01X565230Y1184790D02*
X564760D01*
G01X565390Y1185010D02*
X568120Y1182070D01*
G01X565270Y1185030D02*
X565390Y1185010D01*
G01X565220Y1184930D02*
X565270Y1185030D01*
G01X565490Y1181680D02*
X565030D01*
G01X565040Y1181490D02*
X565510D01*
G01X565530Y1181290D02*
X565060D01*
G01X565080Y1181090D02*
X565550D01*
G01X565560Y1180880D02*
X565090D01*
G01X565110Y1180680D02*
X565580D01*
G01X565590Y1180590D02*
X565120D01*
G01X565250Y1179070D02*
Y1179010D01*
G01X565120Y1180530D02*
X565250Y1179070D01*
G01X565240Y1178990D02*
X565920D01*
G01X565770Y1178810D02*
X565750Y1178740D01*
G01X565820Y1178890D02*
X565770Y1178810D01*
G01X565750Y1178680D02*
X564980D01*
G01X564790Y1178490D02*
X565770D01*
G01X565790Y1178180D02*
X565290D01*
G01X565260Y1178220D02*
X565160Y1178200D01*
G01X565530Y1175780D02*
X565640D01*
G01X565530Y1175790D02*
Y1175780D01*
G01X565330Y1178140D02*
X565530Y1175790D01*
G01X565260Y1178220D02*
X565330Y1178140D01*
G01X565630Y1175880D02*
X565520D01*
G01X565525D02*
X571120D01*
G01X571185Y1175790D02*
X565530D01*
G01X565770Y1174740D02*
X566660D01*
G01X565730Y1174780D02*
X565770Y1174740D01*
G01X565730Y1175460D02*
Y1174780D01*
G01X565700Y1175530D02*
X565730Y1175460D01*
G01X565550Y1175690D02*
X565700Y1175530D01*
G01X565540Y1175710D02*
X565550Y1175690D01*
G01X565530Y1175770D02*
X565540Y1175710D01*
G01X566700Y1174790D02*
X565730D01*
G01Y1174990D02*
X566700D01*
G01Y1175180D02*
X565730D01*
G01Y1175380D02*
X566700D01*
G01X565980Y1176090D02*
X565510D01*
G01X565490Y1176180D02*
X565960D01*
G01X565950Y1176380D02*
X565480D01*
G01X565460Y1176590D02*
X565930D01*
G01X565910Y1176790D02*
X565440D01*
G01X565430Y1176990D02*
X565900D01*
G01X565880Y1177180D02*
X565410D01*
G01X565390Y1177380D02*
X565860D01*
G01X565850Y1177590D02*
X565380D01*
G01X565360Y1177790D02*
X565830D01*
G01X565810Y1177990D02*
X565350D01*
G01X565240Y1179180D02*
X566110D01*
G01X566300Y1179380D02*
X565220D01*
G01X565190Y1179790D02*
X565660D01*
G01X565670Y1179640D02*
X565220Y1184930D01*
G01X565410Y1184990D02*
X566030D01*
G01X566220Y1184790D02*
X565600D01*
G01X565780Y1184590D02*
X566400D01*
G01X565660Y1185380D02*
X564710D01*
G01X564690Y1185590D02*
X565480D01*
G01X565290Y1185790D02*
X564650D01*
G01X565350Y1189200D02*
X565240Y1189190D01*
G01X565400Y1189110D02*
X565350Y1189200D01*
G01X565400Y1188880D02*
Y1189110D01*
G01X565300Y1188780D02*
X565400Y1188880D01*
G01X565030Y1188780D02*
X565300D01*
G01X565230Y1189180D02*
X564540D01*
G01X565410Y1190170D02*
X565440Y1190190D01*
G01X565400Y1190140D02*
X565410Y1190170D01*
G01X565400Y1189940D02*
Y1190140D01*
G01X565390Y1189900D02*
X565400Y1189940D01*
G01X565370Y1189850D02*
X565390Y1189900D01*
G01X565320Y1189790D02*
X565370Y1189850D01*
G01X565230Y1189750D02*
X565320Y1189790D01*
G01X564960Y1189590D02*
X565230Y1189750D01*
G01X565440Y1190180D02*
X566270D01*
G01X565400Y1189990D02*
X568290D01*
G01X568280Y1189790D02*
X565300D01*
G01X565350Y1189180D02*
X566320D01*
G01Y1188990D02*
X565400D01*
G01X565310Y1188790D02*
X566420D01*
G01X565610Y1180380D02*
X565140D01*
G01X565150Y1180180D02*
X565620D01*
G01X565640Y1179990D02*
X565170D01*
G01X565740Y1179550D02*
X565840Y1179580D01*
G01X565670Y1179640D02*
X565740Y1179550D01*
G01X565650Y1175590D02*
X571430D01*
G01X565970Y1176160D02*
X565750Y1178740D01*
G01X565970Y1176090D02*
Y1176160D01*
G01X566070Y1176000D02*
X565970Y1176090D01*
G01X570170Y1176000D02*
X566070D01*
G01X565820Y1178880D02*
X565170D01*
G01X565250Y1179090D02*
X566010D01*
G01X565830Y1178890D02*
X565820D01*
G01X565830Y1178900D02*
Y1178890D01*
G01Y1178900D02*
X568420Y1181590D01*
G01X568230Y1181380D02*
X567590D01*
G01X567390Y1181180D02*
X568040D01*
G01X567850Y1180990D02*
X567200D01*
G01X567010Y1180790D02*
X567650D01*
G01X567560Y1180680D02*
X566910D01*
G01X566960Y1180740D02*
X565840Y1179580D01*
G01X565850Y1179590D02*
X566490D01*
G01X566400Y1179490D02*
X565220D01*
G01X565230Y1179290D02*
X566210D01*
G01X565950Y1179680D02*
X566590D01*
G01X566690Y1179790D02*
X566050D01*
G01X566140Y1179880D02*
X566790D01*
G01X566880Y1179990D02*
X566240D01*
G01X566330Y1180090D02*
X566980D01*
G01X567070Y1180180D02*
X566430D01*
G01X566530Y1180290D02*
X567170D01*
G01X567270Y1180380D02*
X566620D01*
G01X566720Y1180490D02*
X567360D01*
G01X567460Y1180590D02*
X566810D01*
G01X567640Y1182590D02*
X568270D01*
G01X568080Y1182790D02*
X567460D01*
G01X567270Y1182990D02*
X567890D01*
G01X567710Y1183180D02*
X567080D01*
G01X566990Y1183290D02*
X567610D01*
G01X567520Y1183380D02*
X566900D01*
G01X566810Y1183490D02*
X567430D01*
G01X567330Y1183590D02*
X566710D01*
G01X566620Y1183680D02*
X567240D01*
G01X567150Y1183790D02*
X566530D01*
G01X566430Y1183880D02*
X567060D01*
G01X566960Y1183990D02*
X566340D01*
G01X566250Y1184090D02*
X566870D01*
G01X566780Y1184180D02*
X566150D01*
G01X566060Y1184290D02*
X566680D01*
G01X566590Y1184380D02*
X565970D01*
G01X565880Y1184490D02*
X566500D01*
G01X566310Y1184680D02*
X565690D01*
G01X565500Y1184880D02*
X566120D01*
G01X565940Y1185090D02*
X564740D01*
G01X564730Y1185180D02*
X565850D01*
G01X567700Y1184460D02*
X567740Y1184420D01*
G01X566320Y1188880D02*
X565400D01*
G01X566420Y1188780D02*
X566320Y1188880D01*
G01X565400Y1189090D02*
X566320D01*
G01X567650Y1189790D02*
X567760Y1189680D01*
G01X567380Y1189760D02*
X567650Y1189790D01*
G01X567100Y1189730D02*
X567380Y1189760D01*
G01X566980Y1189720D02*
X567100Y1189730D01*
G01X566880Y1189700D02*
X566980Y1189720D01*
G01X566630Y1189660D02*
X566880Y1189700D01*
G01X566620Y1189660D02*
X566630D01*
G01X566530Y1189640D02*
X566620Y1189660D01*
G01X566520Y1189640D02*
X566530D01*
G01X566400Y1189620D02*
X566520Y1189640D01*
G01X566320Y1189520D02*
X566400Y1189620D01*
G01X566320Y1188880D02*
Y1189520D01*
G01X566260Y1190190D02*
X565440D01*
G01X566280Y1190180D02*
X566260Y1190190D01*
G01X566310Y1190170D02*
X566280Y1190180D01*
G01X566340Y1190150D02*
X566310Y1190170D01*
G01X566420Y1190130D02*
X566340Y1190150D01*
G01X566440Y1190140D02*
X566420Y1190130D01*
G01X566680Y1190180D02*
X566440Y1190140D01*
G01X567180Y1190250D02*
X566680Y1190180D01*
G01X567300Y1190260D02*
X567180Y1190250D01*
G01X567360Y1190260D02*
X567300D01*
G01X567520Y1190280D02*
X567360Y1190260D01*
G01X567660Y1190290D02*
X567520Y1190280D01*
G01X565120Y1189680D02*
X566770D01*
G01X566320Y1189380D02*
X564750D01*
G01X566420Y1188780D02*
X572260D01*
G01X570330Y1190290D02*
X567640D01*
G01X567660D02*
X567760Y1190390D01*
G01X565790Y1178290D02*
X564590D01*
G01X565330Y1178090D02*
X565800D01*
G01X565820Y1177880D02*
X565350D01*
G01X565370Y1177680D02*
X565840D01*
G01X565850Y1177490D02*
X565380D01*
G01X565400Y1177290D02*
X565870D01*
G01X565890Y1177090D02*
X565420D01*
G01X565440Y1176880D02*
X565900D01*
G01X565920Y1176680D02*
X565460D01*
G01X565470Y1176490D02*
X565940D01*
G01X565960Y1176290D02*
X565490D01*
G01X565720Y1175490D02*
X566770D01*
G01X566700Y1174780D02*
X566660Y1174740D01*
G01X566700Y1175420D02*
Y1174780D01*
G01X566800Y1175520D02*
X566700Y1175420D01*
G01Y1174880D02*
X565730D01*
G01Y1175090D02*
X566700D01*
G01Y1175290D02*
X565730D01*
G01X570270Y1176470D02*
Y1176480D01*
G01X570260Y1176400D02*
X570270Y1176470D01*
G01X570260Y1176140D02*
Y1176400D01*
G01X570270Y1176120D02*
X570260Y1176140D01*
G01X570170Y1176000D02*
X570270Y1176120D01*
G01Y1176490D02*
X571040D01*
G01X571000Y1176290D02*
X570260D01*
G01X570240Y1176090D02*
X571040D01*
G01X568880Y1181920D02*
Y1182060D01*
G01X571580Y1179020D02*
X568880Y1181920D01*
G01X568900Y1182090D02*
X568110D01*
G01X568120Y1181930D02*
X566960Y1180740D01*
G01X568120Y1182070D02*
Y1181930D01*
G01X567110Y1180880D02*
X567750D01*
G01X567940Y1181090D02*
X567300D01*
G01X567490Y1181290D02*
X568140D01*
G01X568330Y1181490D02*
X567680D01*
G01X568570Y1181590D02*
X570250Y1179770D01*
G01X568420Y1181590D02*
X568570D01*
G01X567780D02*
X568420D01*
G01X570240Y1179790D02*
X570870D01*
G01X570680Y1179990D02*
X570050D01*
G01X569870Y1180180D02*
X570500D01*
G01X570310Y1180380D02*
X569680D01*
G01X569590Y1180490D02*
X570220D01*
G01X570120Y1180590D02*
X569490D01*
G01X569400Y1180680D02*
X570030D01*
G01X569940Y1180790D02*
X569310D01*
G01X569220Y1180880D02*
X569850D01*
G01X569750Y1180990D02*
X569120D01*
G01X569030Y1181090D02*
X569660D01*
G01X569570Y1181180D02*
X568940D01*
G01X568850Y1181290D02*
X569480D01*
G01X569380Y1181380D02*
X568750D01*
G01X568660Y1181490D02*
X569290D01*
G01X569200Y1181590D02*
X568550D01*
G01X568920Y1181880D02*
X568070D01*
G01X568120Y1181990D02*
X568880D01*
G01X569000Y1182180D02*
X568010D01*
G01X567920Y1182290D02*
X569100D01*
G01X569200Y1182380D02*
X567830D01*
G01X567740Y1182490D02*
X568360D01*
G01X568570Y1182410D02*
X570000Y1183880D01*
G01X568430Y1182410D02*
X568570D01*
G01X569900Y1183790D02*
X570540D01*
G01X570350Y1183590D02*
X569710D01*
G01X569620Y1183490D02*
X570250D01*
G01X570160Y1183380D02*
X569520D01*
G01X569420Y1183290D02*
X570060D01*
G01X569970Y1183180D02*
X569330D01*
G01X569230Y1183090D02*
X569870D01*
G01X569770Y1182990D02*
X569130D01*
G01X569040Y1182880D02*
X569680D01*
G01X569580Y1182790D02*
X568940D01*
G01X568850Y1182680D02*
X569480D01*
G01X569390Y1182590D02*
X568750D01*
G01X568650Y1182490D02*
X569290D01*
G01X569010Y1181790D02*
X567980D01*
G01X567880Y1181680D02*
X569100D01*
G01X568170Y1182680D02*
X567550D01*
G01X567360Y1182880D02*
X567990D01*
G01X567800Y1183090D02*
X567180D01*
G01X567790Y1184420D02*
X570280D01*
G01X567740D02*
X567790D01*
G01X570290Y1184180D02*
X570930D01*
G01X570740Y1183990D02*
X570100D01*
G01X571220Y1184490D02*
X567700D01*
G01X567740Y1185450D02*
X567790D01*
G01X567700Y1185410D02*
X567740Y1185450D01*
G01X567700Y1184460D02*
Y1185410D01*
G01Y1185290D02*
X570960D01*
G01X570990Y1185090D02*
X567700D01*
G01Y1184880D02*
X571610D01*
G01X571410Y1184680D02*
X567700D01*
G01X567760Y1189340D02*
Y1189680D01*
G01X567800Y1189290D02*
X567760Y1189340D01*
G01X567750Y1189680D02*
X570380D01*
G01X570250Y1189290D02*
X567800D01*
G01X570300Y1189340D02*
X570250Y1189290D01*
G01X570300Y1189620D02*
Y1189340D01*
G01X567760Y1189380D02*
X570300D01*
G01Y1189490D02*
X567760D01*
G01Y1189590D02*
X570300D01*
G01X569850Y1189900D02*
Y1189860D01*
G01X569750Y1190000D02*
X569850Y1189900D01*
G01X568310Y1190000D02*
X569750D01*
G01X568210Y1189900D02*
X568310Y1190000D01*
G01X568210Y1189860D02*
Y1189900D01*
G01X568310Y1189750D02*
X568210Y1189860D01*
G01X569750Y1189750D02*
X568310D01*
G01X569850Y1189860D02*
X569750Y1189750D01*
G01X569850Y1189880D02*
X571820D01*
G01X571530Y1189990D02*
X569760D01*
G01X567760Y1190420D02*
Y1190390D01*
G01X567800Y1190460D02*
X567760Y1190420D01*
G01X570250Y1190460D02*
X567800D01*
G01X570300Y1190420D02*
X570250Y1190460D01*
G01X570300Y1190320D02*
Y1190420D01*
G01X567750Y1190380D02*
X570300D01*
G01X568210Y1189880D02*
X565380D01*
G01X565400Y1190090D02*
X571160D01*
G01X570380Y1190220D02*
X570300Y1190320D01*
G01X570430Y1190220D02*
X570380D01*
G01X570990Y1190130D02*
X570430Y1190220D01*
G01X571170Y1190090D02*
X570990Y1190130D01*
G01X570610Y1190180D02*
X566740D01*
G01X570810Y1189650D02*
X571220Y1189560D01*
G01X570520Y1189700D02*
X570810Y1189650D01*
G01X570490Y1189700D02*
X570520D01*
G01X570410Y1189720D02*
X570490Y1189700D01*
G01X570300Y1189620D02*
X570410Y1189720D01*
G01X570600Y1189680D02*
X572190D01*
G01X570910Y1185450D02*
X567790D01*
G01X567700Y1185380D02*
X570960D01*
G01X570950Y1185410D02*
X570910Y1185450D01*
G01X571130Y1185060D02*
X571330Y1185260D01*
G01X571020Y1185030D02*
X571130Y1185060D01*
G01X570960Y1185130D02*
X571020Y1185030D01*
G01X570960Y1185310D02*
Y1185130D01*
G01Y1185320D02*
Y1185310D01*
G01X570950Y1185410D02*
X570960Y1185320D01*
G01X571160Y1185090D02*
X571800D01*
G01X570960Y1185180D02*
X567700D01*
G01X569810Y1183680D02*
X570450D01*
G01X570370Y1184360D02*
X570280Y1184420D01*
G01X570350Y1184250D02*
X570370Y1184360D01*
G01X570000Y1183880D02*
X570350Y1184250D01*
G01X570640Y1183880D02*
X570000D01*
G01X570330Y1184380D02*
X571120D01*
G01X571030Y1184290D02*
X570360D01*
G01X570200Y1184090D02*
X570830D01*
G01X570400Y1180290D02*
X569770D01*
G01X569960Y1180090D02*
X570590D01*
G01X570770Y1179880D02*
X570140D01*
G01X570330Y1179680D02*
X570960D01*
G01X571050Y1179590D02*
X570420D01*
G01X570510Y1179490D02*
X571150D01*
G01X571240Y1179380D02*
X570610D01*
G01X570700Y1179290D02*
X571330D01*
G01X571520Y1179090D02*
X570890D01*
G01X571070Y1178880D02*
X572210D01*
G01X572200Y1178790D02*
X571170D01*
G01X570310Y1176660D02*
X570270Y1176480D01*
G01X570310Y1176670D02*
Y1176660D01*
G01X570420Y1176980D02*
X570310Y1176670D01*
G01X570430Y1176990D02*
X570420Y1176980D01*
G01X570640Y1177300D02*
X570430Y1176990D01*
G01X570650Y1177310D02*
X570640Y1177300D01*
G01X570890Y1177530D02*
X570650Y1177310D01*
G01X570900Y1177530D02*
X570890D01*
G01X571020Y1177610D02*
X570900Y1177530D01*
G01X571030Y1177620D02*
X571020Y1177610D01*
G01X571090Y1177650D02*
X571030Y1177620D01*
G01X571250Y1177720D02*
X571090Y1177650D01*
G01X570260Y1176380D02*
X571020D01*
G01X571060Y1175990D02*
X565510D01*
G01X571050Y1176010D02*
X571060Y1175990D01*
G01X571000Y1176270D02*
X571050Y1176010D01*
G01X571000Y1176280D02*
Y1176270D01*
G01Y1176300D02*
Y1176280D01*
G01X565550Y1175680D02*
X571290D01*
G01X571210Y1175750D02*
X571150Y1175840D01*
G01X571220Y1175740D02*
X571210Y1175750D01*
G01X571230Y1175730D02*
X571220Y1175740D01*
G01X571070Y1175980D02*
X571060Y1175990D01*
G01X571150Y1175850D02*
X571070Y1175980D01*
G01X571020Y1176180D02*
X570260D01*
G01X570290Y1176590D02*
X571060D01*
G01X571050Y1176560D02*
X571000Y1176300D01*
G01X571060Y1176580D02*
X571050Y1176560D01*
G01X571280Y1176310D02*
X571290Y1176330D01*
G01X571230Y1176840D02*
X571450Y1177000D01*
G01X571220Y1176830D02*
X571230Y1176840D01*
G01X571210Y1176810D02*
X571220Y1176830D01*
G01X571070Y1176600D02*
X571210Y1176810D01*
G01X571060Y1176580D02*
X571070Y1176600D01*
G01X571290Y1176880D02*
X570390D01*
G01X570350Y1176790D02*
X571190D01*
G01X571120Y1176680D02*
X570310D01*
G01X570490Y1177090D02*
X571750D01*
G01X571160Y1177680D02*
X572830D01*
G01X572920Y1177590D02*
X570980D01*
G01X570740Y1177380D02*
X573110D01*
G01X573290Y1177180D02*
X570570D01*
G01X571150Y1175790D02*
X571190D01*
G01X571230Y1175730D02*
X571450Y1175570D01*
G01X571020Y1174990D02*
X572570D01*
G01X572730Y1175090D02*
X570840D01*
G01X570400Y1175520D02*
X566800D01*
G01X570480Y1175490D02*
X570400Y1175520D01*
G01X570490Y1175480D02*
X570480Y1175490D01*
G01X570490Y1175470D02*
Y1175480D01*
G01X570530Y1175400D02*
X570490Y1175470D01*
G01X570540Y1175400D02*
X570530D01*
G01X570550Y1175390D02*
X570540Y1175400D01*
G01X570620Y1175290D02*
X570550Y1175390D01*
G01X570630Y1175280D02*
X570620Y1175290D01*
G01X570860Y1175060D02*
X570630Y1175280D01*
G01Y1175290D02*
X572970D01*
G01X570880Y1175050D02*
X570860Y1175060D01*
G01X571680Y1174750D02*
X572020Y1174760D01*
G01X571670Y1174750D02*
X571680D01*
G01X571660D02*
X571670D01*
G01X571500Y1174770D02*
X571660Y1174750D01*
G01X571480Y1174770D02*
X571500D01*
G01X570880Y1175050D02*
X571480Y1174770D01*
G01X572130Y1174790D02*
X571460D01*
G01Y1175560D02*
X571450Y1175570D01*
G01X571480Y1175560D02*
X571460D01*
G01X571650Y1175500D02*
X571480Y1175560D01*
G01X571870Y1175490D02*
X571890D01*
G01X571740D02*
X571870D01*
G01X571670Y1175500D02*
X571740Y1175490D01*
G01X571650Y1175500D02*
X571670D01*
G01X571310Y1176120D02*
X571280Y1176310D01*
G01X571320Y1176090D02*
X571310Y1176120D01*
G01X571490Y1175870D02*
X571320Y1176090D01*
G01X571510Y1175860D02*
X571490Y1175870D01*
G01X571680Y1175780D02*
X571510Y1175860D01*
G01X571690Y1175780D02*
X571680D01*
G01X571730Y1175770D02*
X571690Y1175780D01*
G01X571790Y1175770D02*
X571730D01*
G01X571810D02*
X571790D01*
G01X571840Y1176800D02*
X571850D01*
G01X571750D02*
X571840D01*
G01X571730Y1176790D02*
X571750Y1176800D01*
G01X571420Y1176630D02*
X571730Y1176790D01*
G01X571400Y1176610D02*
X571420Y1176630D01*
G01X571290Y1176330D02*
X571400Y1176610D01*
G01X571460Y1177010D02*
X571450Y1177000D01*
G01X571480Y1177010D02*
X571460D01*
G01X571650Y1177070D02*
X571480Y1177010D01*
G01X571670Y1177070D02*
X571650D01*
G01X571740Y1177080D02*
X571670Y1177070D01*
G01X571760Y1177090D02*
X571740Y1177080D01*
G01X571820Y1177090D02*
X571760D01*
G01X571850Y1177080D02*
X571820Y1177090D01*
G01X571430Y1176990D02*
X570430D01*
G01X571340Y1176470D02*
X572280D01*
G01X572300Y1176270D02*
X571290D01*
G01X571340Y1176070D02*
X572250D01*
G01X572070Y1175870D02*
X571500D01*
G01X571810Y1175770D02*
X571940Y1175790D01*
G01X572140Y1176660D02*
X571490D01*
G01X571890Y1177080D02*
X572090Y1177030D01*
G01X571850Y1177080D02*
X571890D01*
G01X571340Y1177750D02*
X571250Y1177720D01*
G01X571350Y1177760D02*
X571340Y1177750D01*
G01X571490Y1177790D02*
X571350Y1177760D01*
G01X571570Y1177810D02*
X571490Y1177790D01*
G01X571350Y1178590D02*
X570250Y1179770D01*
G01X571610Y1178310D02*
X571350Y1178590D01*
G01X571640Y1178260D02*
X571610Y1178310D01*
G01X571670Y1178110D02*
X571640Y1178260D01*
G01X571680Y1178090D02*
X571670Y1178110D01*
G01X571680Y1178070D02*
Y1178090D01*
G01X571660Y1177900D02*
X571680Y1178070D01*
G01X571660Y1177890D02*
Y1177900D01*
G01X571570Y1177810D02*
X571660Y1177890D01*
G01X570790Y1179180D02*
X571430D01*
G01X571750Y1179080D02*
X572260Y1185310D01*
G01X571690Y1179000D02*
X571750Y1179080D01*
G01X571580Y1179020D02*
X571690Y1179000D01*
G01X571350Y1185290D02*
X571330Y1185260D01*
G01X571990Y1185290D02*
X571350D01*
G01D02*
X572160Y1186130D01*
G01X571740Y1185680D02*
X574000D01*
G01Y1185490D02*
X571550D01*
G01X571250Y1185180D02*
X571890D01*
G01X571700Y1184990D02*
X567700D01*
G01Y1184790D02*
X571510D01*
G01X571310Y1184590D02*
X567700D01*
G01X571920Y1181090D02*
X572380D01*
G01X572370Y1180880D02*
X571900D01*
G01X571880Y1180680D02*
X572350D01*
G01X572340Y1180490D02*
X571870D01*
G01X571850Y1180290D02*
X572320D01*
G01X572310Y1180090D02*
X571840D01*
G01X571820Y1179880D02*
X572290D01*
G01X572270Y1179680D02*
X571810D01*
G01X571790Y1179490D02*
X572250D01*
G01X572240Y1179290D02*
X571770D01*
G01X571750Y1179090D02*
X572220D01*
G01X572180Y1178590D02*
X571350D01*
G01X571540Y1178380D02*
X572180D01*
G01X572360Y1178180D02*
X571660D01*
G01X571670Y1177990D02*
X572550D01*
G01X571500Y1189480D02*
X571220Y1189560D01*
G01X571510Y1189470D02*
X571500Y1189480D01*
G01X571620Y1189440D02*
X571510Y1189470D01*
G01X571620Y1189430D02*
Y1189440D01*
G01X571730Y1189390D02*
X571620Y1189430D01*
G01X571740Y1189380D02*
X571730Y1189390D01*
G01X572600Y1189380D02*
X571740D01*
G01X571460Y1189490D02*
X572490D01*
G01X571290Y1190050D02*
X571170Y1190090D01*
G01X571400Y1190030D02*
X571290Y1190050D01*
G01X571640Y1189950D02*
X571400Y1190030D01*
G01X571750Y1189910D02*
X571640Y1189950D01*
G01X571810Y1189890D02*
X571750Y1189910D01*
G01X571100Y1189590D02*
X572350D01*
G01X572030Y1189790D02*
X569780D01*
G01X572350Y1188830D02*
X572260Y1188780D01*
G01X572340Y1188930D02*
X572350Y1188830D01*
G01X572270Y1189040D02*
X572340Y1188930D01*
G01X572250Y1189060D02*
X572270Y1189040D01*
G01X571950Y1189280D02*
X572250Y1189060D01*
G01X571940Y1189290D02*
X571950Y1189280D01*
G01X571930Y1189290D02*
X571940D01*
G01X571740Y1189380D02*
X571930Y1189290D01*
G01X572270Y1188790D02*
X573990D01*
G01X573970Y1188990D02*
X572310D01*
G01X572080Y1189180D02*
X573890D01*
G01X574000Y1187180D02*
X572220D01*
G01X572190Y1186160D02*
X572160Y1186130D01*
G01X572220Y1186220D02*
X572190Y1186160D01*
G01X572220Y1187240D02*
Y1186220D01*
G01X572120Y1186090D02*
X572790D01*
G01X572960Y1186290D02*
X572220D01*
G01Y1186490D02*
X573150D01*
G01X573340Y1186680D02*
X572220D01*
G01Y1186790D02*
X574000D01*
G01Y1186990D02*
X572220D01*
G01X572330Y1187320D02*
X572430Y1187420D01*
G01X572260Y1187320D02*
X572330D01*
G01X572220Y1187280D02*
X572260Y1187320D01*
G01X572220Y1187240D02*
Y1187280D01*
G01X571930Y1185880D02*
X574000D01*
G01X572720Y1185180D02*
X572250D01*
G01X572090Y1185390D02*
X568880Y1182060D01*
G01X572200Y1185410D02*
X572090Y1185390D01*
G01X572260Y1185310D02*
X572200Y1185410D01*
G01X571980Y1181880D02*
X572450D01*
G01X572460Y1181990D02*
X571990D01*
G01X572010Y1182180D02*
X572480D01*
G01X572490Y1182380D02*
X572030D01*
G01X572040Y1182590D02*
X572510D01*
G01X572520Y1182790D02*
X572060D01*
G01X572070Y1182990D02*
X572540D01*
G01X572560Y1183180D02*
X572090D01*
G01X572110Y1183380D02*
X572570D01*
G01X572590Y1183590D02*
X572120D01*
G01X572140Y1183790D02*
X572610D01*
G01X572620Y1183990D02*
X572160D01*
G01X572170Y1184180D02*
X572640D01*
G01X572650Y1184380D02*
X572190D01*
G01X572200Y1184590D02*
X572670D01*
G01X572690Y1184790D02*
X572220D01*
G01X572240Y1184990D02*
X572700D01*
G01X572090Y1185380D02*
X571450D01*
G01X571970Y1181680D02*
X572440D01*
G01X572420Y1181490D02*
X571950D01*
G01X571940Y1181290D02*
X572400D01*
G01X572390Y1181180D02*
X571930D01*
G01X571910Y1180990D02*
X572380D01*
G01X572360Y1180790D02*
X571890D01*
G01X571880Y1180590D02*
X572350D01*
G01X572330Y1180380D02*
X571860D01*
G01X571850Y1180180D02*
X572310D01*
G01X572300Y1179990D02*
X571830D01*
G01X571810Y1179790D02*
X572280D01*
G01X572260Y1179590D02*
X571800D01*
G01X571780Y1179380D02*
X572250D01*
G01X572230Y1179180D02*
X571760D01*
G01X572220Y1178990D02*
X570980D01*
G01X571260Y1178680D02*
X572190D01*
G01X572180Y1178490D02*
X571450D01*
G01X571620Y1178290D02*
X572260D01*
G01X572200Y1178350D02*
X573160Y1177330D01*
G01X573480Y1176990D02*
X572150D01*
G01X572130Y1177010D02*
X572090Y1177030D01*
G01X572130Y1177010D02*
X572440Y1176750D01*
G01X572210Y1176570D02*
X571380D01*
G01X571300Y1176370D02*
X572290D01*
G01X572100Y1176700D02*
X571850Y1176800D01*
G01X572120Y1176690D02*
X572100Y1176700D01*
G01X572270Y1176490D02*
X572120Y1176690D01*
G01X572280Y1176460D02*
X572270Y1176490D01*
G01X571940Y1176770D02*
X571670D01*
G01X571960Y1175790D02*
X571940D01*
G01X572180Y1175930D02*
X571960Y1175790D01*
G01X572190Y1175950D02*
X572180Y1175930D01*
G01X572300Y1176180D02*
X572190Y1175950D01*
G01X572310Y1176200D02*
X572300Y1176180D01*
G01X572280Y1176460D02*
X572310Y1176200D01*
G01X572150Y1175590D02*
X573170D01*
G01X572030Y1174760D02*
X572020D01*
G01X572320Y1174830D02*
X572030Y1174760D01*
G01X572330Y1174840D02*
X572320Y1174830D01*
G01X572840Y1175150D02*
X572330Y1174840D01*
G01X572090Y1175540D02*
X572130Y1175560D01*
G01X571890Y1175490D02*
X572090Y1175540D01*
G01X572200Y1175970D02*
X571420D01*
G01X571300Y1176160D02*
X572300D01*
G01X572190Y1178370D02*
X572170Y1178440D01*
G01X572200Y1178360D02*
X572190Y1178370D01*
G01X572200Y1178350D02*
Y1178360D01*
G01X571960Y1189830D02*
X571810Y1189890D01*
G01X571970Y1189820D02*
X571960Y1189830D01*
G01X573220Y1189540D02*
X573280Y1189550D01*
G01X573210Y1189540D02*
X573220D01*
G01X573100Y1189510D02*
X573210Y1189540D01*
G01X573090Y1189510D02*
X573100D01*
G01X572960Y1189460D02*
X573090Y1189510D01*
G01X572960Y1189450D02*
Y1189460D01*
G01X572900Y1189420D02*
X572960Y1189450D01*
G01X572880Y1189400D02*
X572900Y1189420D01*
G01X572820Y1189350D02*
X572880Y1189400D01*
G01X572800Y1189330D02*
X572820Y1189350D01*
G01X572660Y1189330D02*
X572800D01*
G01X572480Y1189500D02*
X572660Y1189330D01*
G01X572470Y1189510D02*
X572480Y1189500D01*
G01X571970Y1189820D02*
X572470Y1189510D01*
G01X573030Y1189490D02*
X573550D01*
G01X573600Y1188180D02*
X572440D01*
G01X572490Y1188130D02*
X572430Y1187420D01*
G01X572400Y1187380D02*
X572950D01*
G01X573240Y1188110D02*
X573270Y1188100D01*
G01X573160Y1188120D02*
X573240Y1188110D01*
G01X573090Y1188140D02*
X573160Y1188120D01*
G01X573080Y1188140D02*
X573090D01*
G01X572950Y1188050D02*
X573080Y1188140D01*
G01X572900Y1187440D02*
X572950Y1188050D01*
G01X573000Y1187330D02*
X572900Y1187440D01*
G01X573000Y1188090D02*
X572490D01*
G01X572390Y1188240D02*
X565040D01*
G01X572490Y1188130D02*
X572390Y1188240D01*
G01X572030Y1185990D02*
X572850D01*
G01X572820Y1186140D02*
X573370Y1186720D01*
G01X572790Y1186090D02*
X572820Y1186140D01*
G01X572790Y1186050D02*
Y1186090D01*
G01X572890Y1185940D02*
X572790Y1186050D01*
G01X573250Y1186590D02*
X572220D01*
G01Y1186380D02*
X573050D01*
G01X572860Y1186180D02*
X572200D01*
G01X572220Y1185380D02*
X572750D01*
G01X572740Y1185370D02*
X572170Y1178440D01*
G01X572450Y1178090D02*
X571680D01*
G01X571650Y1177880D02*
X572640D01*
G01X572730Y1177790D02*
X571460D01*
G01X570850Y1177490D02*
X573010D01*
G01X573200Y1177290D02*
X570630D01*
G01X570480Y1175490D02*
X573110D01*
G01X572930Y1175240D02*
X572840Y1175150D01*
G01X572990Y1175310D02*
X572930Y1175240D01*
G01X573120Y1175500D02*
X572990Y1175310D01*
G01X572880Y1175180D02*
X570730D01*
G01X570550Y1175380D02*
X573040D01*
G01X573240Y1175750D02*
X573300Y1175920D01*
G01X573200Y1175650D02*
X573240Y1175750D01*
G01X573200Y1175640D02*
Y1175650D01*
G01X573130Y1175510D02*
X573200Y1175640D01*
G01X573120Y1175500D02*
X573130Y1175510D01*
G01X573290Y1175880D02*
X572475D01*
G01X572480D02*
X572540D01*
G01X572440Y1175820D02*
X572130Y1175560D01*
G01X572470Y1175870D02*
X572440Y1175820D01*
G01X572270Y1175680D02*
X573220D01*
G01X573250Y1175790D02*
X572460D01*
G01X573220D02*
X573250D01*
G01X572470Y1176700D02*
X572440Y1176750D01*
G01X572590Y1176310D02*
X572470Y1176700D01*
G01X572590Y1176250D02*
Y1176310D01*
G01X572470Y1175870D02*
X572590Y1176250D01*
G01X572400Y1176790D02*
X573660D01*
G01X573850Y1176590D02*
X572510D01*
G01X572570Y1176380D02*
X574030D01*
G01X573330Y1176180D02*
X572570D01*
G01X572510Y1175990D02*
X573310D01*
G01X572400Y1174880D02*
X571240D01*
G01X571940Y1181380D02*
X572410D01*
G01X572430Y1181590D02*
X571960D01*
G01X571980Y1181790D02*
X572440D01*
G01X572470Y1182090D02*
X572000D01*
G01X572010Y1182290D02*
X572480D01*
G01X572500Y1182490D02*
X572030D01*
G01X572050Y1182680D02*
X572510D01*
G01X572530Y1182880D02*
X572070D01*
G01X572080Y1183090D02*
X572550D01*
G01X572570Y1183290D02*
X572100D01*
G01X572110Y1183490D02*
X572580D01*
G01X572600Y1183680D02*
X572130D01*
G01X572150Y1183880D02*
X572610D01*
G01X572630Y1184090D02*
X572160D01*
G01X572180Y1184290D02*
X572640D01*
G01X572660Y1184490D02*
X572200D01*
G01X572210Y1184680D02*
X572680D01*
G01X572700Y1184880D02*
X572230D01*
G01X572240Y1185090D02*
X572710D01*
G01X572730Y1185290D02*
X572260D01*
G01X572740Y1185370D02*
X572830Y1185460D01*
G01X573160Y1187320D02*
X573280D01*
G01X573000Y1187330D02*
X573160Y1187320D01*
G01X572910Y1187490D02*
X572440D01*
G01X572450Y1187590D02*
X572920D01*
G01Y1187680D02*
X572460D01*
G01Y1187790D02*
X572930D01*
G01X572940Y1187880D02*
X572470D01*
G01X572480Y1187990D02*
X572950D01*
G01X573350Y1189550D02*
X573280D01*
G01X573360Y1189540D02*
X573350Y1189550D01*
G01X573620Y1189470D02*
X573360Y1189540D01*
G01X573630Y1189460D02*
X573620Y1189470D01*
G01X573830Y1189290D02*
X573630Y1189460D01*
G01X573840Y1189280D02*
X573830Y1189290D01*
G01X573960Y1189050D02*
X573840Y1189280D01*
G01X573970Y1189030D02*
X573960Y1189050D01*
G01X573990Y1188750D02*
X573970Y1189030D01*
G01X573990Y1188740D02*
Y1188750D01*
G01X573910Y1188480D02*
X573990Y1188740D01*
G01X573900Y1188470D02*
X573910Y1188480D01*
G01X573740Y1188270D02*
X573900Y1188470D01*
G01X573730Y1188250D02*
X573740Y1188270D01*
G01X573500Y1188130D02*
X573730Y1188250D01*
G01X573480Y1188130D02*
X573500D01*
G01X573360Y1188110D02*
X573480Y1188130D01*
G01X573350Y1188110D02*
X573360D01*
G01X573290Y1188100D02*
X573350Y1188110D01*
G01X573270Y1188100D02*
X573290D01*
G01X572860Y1189380D02*
X573720D01*
G01X573830Y1189290D02*
X571940D01*
G01X572220Y1189090D02*
X573940D01*
G01X573980Y1188880D02*
X572350D01*
G01X573840Y1188380D02*
X563730D01*
G01Y1188590D02*
X573940D01*
G01X574250Y1188290D02*
X574880D01*
G01X574980Y1188380D02*
X574350D01*
G01X574440Y1188490D02*
X575080D01*
G01X575170Y1188590D02*
X574540D01*
G01X574640Y1188680D02*
X575270D01*
G01X575360Y1188790D02*
X574740D01*
G01X574830Y1188880D02*
X575460D01*
G01X575560Y1188990D02*
X574930D01*
G01X575030Y1189090D02*
X575660D01*
G01X575850Y1189290D02*
X575220D01*
G01X575410Y1189490D02*
X576040D01*
G01X574790Y1188180D02*
X574160D01*
G01X574060Y1188090D02*
X574690D01*
G01X574590Y1187990D02*
X573960D01*
G01X573860Y1187880D02*
X574500D01*
G01X574400Y1187790D02*
X573770D01*
G01X573670Y1187680D02*
X574310D01*
G01X574210Y1187590D02*
X573580D01*
G01X573480Y1187490D02*
X574110D01*
G01X573960Y1185460D02*
X572830D01*
G01X574000Y1185480D02*
X573960Y1185460D01*
G01X574000Y1185490D02*
Y1185480D01*
G01Y1187310D02*
Y1185490D01*
G01Y1187320D02*
Y1187310D01*
G01X574030Y1187400D02*
X574000Y1187320D01*
G01X573480Y1186740D02*
X573370Y1186720D01*
G01X573540Y1186640D02*
X573480Y1186740D01*
G01X573540Y1186040D02*
Y1186640D01*
G01X573440Y1185940D02*
X573540Y1186040D01*
G01X572890Y1185940D02*
X573440D01*
G01X573510Y1186680D02*
X574000D01*
G01Y1186590D02*
X573540D01*
G01Y1186490D02*
X574000D01*
G01Y1186380D02*
X573540D01*
G01Y1186290D02*
X574000D01*
G01Y1186180D02*
X573540D01*
G01Y1186090D02*
X574000D01*
G01Y1185990D02*
X573490D01*
G01X574000Y1185790D02*
X571830D01*
G01X571640Y1185590D02*
X574000D01*
G01Y1186880D02*
X572220D01*
G01Y1187090D02*
X574000D01*
G01Y1187290D02*
X572220D01*
G01X573280Y1187320D02*
X573350Y1187350D01*
G01X573380Y1187380D02*
X574020D01*
G01X573380Y1177090D02*
X571830D01*
G01X572270Y1176880D02*
X573570D01*
G01X573750Y1176680D02*
X572480D01*
G01X572530Y1176490D02*
X573940D01*
G01X574130Y1176290D02*
X573440D01*
G01X573300Y1175940D02*
Y1175920D01*
G01X573340Y1176210D02*
X573300Y1175940D01*
G01X573400Y1176290D02*
X573340Y1176210D01*
G01X573320Y1176090D02*
X572540D01*
G01X573400Y1176290D02*
X573510Y1176270D01*
G01X572590Y1176290D02*
X573400D01*
G01X573590Y1176180D02*
X574220D01*
G01X574310Y1176090D02*
X573680D01*
G01X573770Y1175990D02*
X574410D01*
G01X574460Y1175880D02*
X574500D01*
G01X574510D02*
X573870D01*
G01X573960Y1175790D02*
X574595D01*
G01X574590D02*
X574540D01*
G01X574695Y1175680D02*
X574050D01*
G01X574140Y1175590D02*
X574780D01*
G01X574870Y1175490D02*
X574235D01*
G01X574335Y1175380D02*
X574970D01*
G01X575060Y1175290D02*
X574420D01*
G01X574525Y1175180D02*
X575150D01*
G01X575250Y1175090D02*
X574610D01*
G01X574700Y1174990D02*
X575340D01*
G01X575430Y1174880D02*
X574790D01*
G01X574880Y1174790D02*
X575530D01*
G01X575710Y1174590D02*
X575070D01*
G01X574980Y1174680D02*
X575620D01*
G01X575800Y1174490D02*
X575160D01*
G01X575260Y1174380D02*
X575900D01*
G01X575990Y1174290D02*
X575350D01*
G01X575440Y1174180D02*
X576080D01*
G01X576180Y1174090D02*
X575530D01*
G01X575630Y1173990D02*
X576270D01*
G01X576360Y1173880D02*
X575720D01*
G01X575810Y1173790D02*
X576460D01*
G01X576550Y1173680D02*
X575910D01*
G01X576000Y1173590D02*
X576640D01*
G01X576830Y1173380D02*
X576190D01*
G01X576370Y1173180D02*
X576980D01*
G01X576970Y1173240D02*
X573160Y1177330D01*
G01X576640Y1172900D02*
X576660Y1172880D01*
G01X573510Y1176270D02*
X576640Y1172900D01*
G01X576560Y1172990D02*
X576780D01*
G01X559700Y1173220D02*
X565120Y1178830D01*
G01X559670Y1173190D02*
X559700Y1173220D01*
G01X559680Y1173170D02*
X559670Y1173190D01*
G01X559990Y1172900D02*
X559680Y1173170D01*
G01X560020Y1172890D02*
X559990Y1172900D01*
G01X560040D02*
X560020Y1172890D01*
G01X565160Y1178200D02*
X560040Y1172900D01*
G01X560120Y1172990D02*
X559890D01*
G01X559770Y1173090D02*
X560220D01*
G01X560320Y1173180D02*
X559670D01*
G01X559760Y1173290D02*
X560420D01*
G01X560510Y1173380D02*
X559860D01*
G01X559950Y1173490D02*
X560610D01*
G01X560700Y1173590D02*
X560050D01*
G01X560140Y1173680D02*
X560800D01*
G01X560900Y1173790D02*
X560240D01*
G01X560340Y1173880D02*
X560990D01*
G01X561090Y1173990D02*
X560440D01*
G01X560530Y1174090D02*
X561190D01*
G01X561280Y1174180D02*
X560630D01*
G01X560730Y1174290D02*
X561380D01*
G01X561480Y1174380D02*
X560820D01*
G01X560920Y1174490D02*
X561570D01*
G01X573350Y1187350D02*
X577930Y1192090D01*
G01X577960Y1191480D02*
X574030Y1187400D01*
G01X575120Y1189180D02*
X575750D01*
G01X575940Y1189380D02*
X575310D01*
G01X575510Y1189590D02*
X576140D01*
G01X576240Y1189680D02*
X575610D01*
G01X575700Y1189790D02*
X576330D01*
G01X576430Y1189880D02*
X575800D01*
G01X575900Y1189990D02*
X576520D01*
G01X576620Y1190090D02*
X575990D01*
G01X576180Y1190290D02*
X576810D01*
G01X577010Y1190490D02*
X576380D01*
G01X576570Y1190680D02*
X577200D01*
G01X577100Y1190590D02*
X576480D01*
G01X576670Y1190790D02*
X577290D01*
G01X577390Y1190880D02*
X576760D01*
G01X576860Y1190990D02*
X577490D01*
G01X577590Y1191090D02*
X576960D01*
G01X577050Y1191180D02*
X577680D01*
G01X577780Y1191290D02*
X577150D01*
G01X577250Y1191380D02*
X577870D01*
G01X577980Y1191590D02*
X577440D01*
G01X577970Y1191510D02*
X577980Y1191590D01*
G01X577960Y1191480D02*
X577970Y1191510D01*
G01X577350Y1191490D02*
X577960D01*
G01X577980Y1192080D02*
X577930Y1192090D01*
G01X577980Y1191590D02*
Y1192080D01*
G01X577920Y1192090D02*
X577960D01*
G01X577980Y1191990D02*
X577830D01*
G01X577730Y1191880D02*
X577980D01*
G01Y1191790D02*
X577630D01*
G01X577540Y1191680D02*
X577980D01*
G01X576910Y1190380D02*
X576280D01*
G01X576090Y1190180D02*
X576720D01*
G01X576740Y1173490D02*
X576090D01*
G01X576280Y1173290D02*
X576920D01*
G01X576690Y1172900D02*
X576660Y1172880D01*
G01X576980Y1173190D02*
X576690Y1172900D01*
G01X576990Y1173210D02*
X576980Y1173190D01*
G01Y1173220D02*
X576990Y1173210D01*
G01X576970Y1173240D02*
X576980Y1173220D01*
G01X576460Y1173090D02*
X576880D01*
G54D17*
G01X-90900Y-277455D02*
Y-294955D01*
X-82166D01*
G01X-69033Y-283289D02*
Y-294955D01*
G01Y-278622D02*
X-69470Y-278330D01*
Y-277747D01*
X-69033Y-277455D01*
X-68596Y-277747D01*
Y-278330D01*
X-69033Y-278622D01*
G01X-54590Y-299330D02*
X-53061Y-300497D01*
X-51315Y-300788D01*
X-49787Y-300497D01*
X-48476Y-299039D01*
X-47603Y-296997D01*
Y-283289D01*
G01Y-285622D02*
X-48476Y-284455D01*
X-49787Y-283580D01*
X-51315Y-283289D01*
X-53061Y-283872D01*
X-54153Y-285038D01*
X-55027Y-287080D01*
X-55463Y-289122D01*
X-55245Y-290872D01*
X-54371Y-292914D01*
X-53061Y-294372D01*
X-51315Y-294955D01*
X-50005Y-294663D01*
X-48476Y-293497D01*
X-47603Y-292331D01*
G01X-37745Y-294955D02*
Y-277455D01*
G01Y-285913D02*
X-36653Y-284455D01*
X-35561Y-283580D01*
X-33815Y-283289D01*
X-32505Y-283580D01*
X-30976Y-284747D01*
X-30321Y-286497D01*
Y-294955D01*
G01X-16533Y-277455D02*
Y-294955D01*
G01X-19590Y-283289D02*
X-13476D01*
G01X-2745Y-294955D02*
Y-283289D01*
G01Y-286205D02*
X-1871Y-284747D01*
X-561Y-283580D01*
X1185Y-283289D01*
X2713Y-283580D01*
X4024Y-284747D01*
X4679Y-286788D01*
Y-294955D01*
G01X18467Y-283289D02*
Y-294955D01*
G01Y-278622D02*
X18030Y-278330D01*
Y-277747D01*
X18467Y-277455D01*
X18904Y-277747D01*
Y-278330D01*
X18467Y-278622D01*
G01X32255Y-294955D02*
Y-283289D01*
G01Y-286205D02*
X33129Y-284747D01*
X34439Y-283580D01*
X36185Y-283289D01*
X37713Y-283580D01*
X39024Y-284747D01*
X39679Y-286788D01*
Y-294955D01*
G01X50410Y-299330D02*
X51939Y-300497D01*
X53685Y-300788D01*
X55213Y-300497D01*
X56524Y-299039D01*
X57397Y-296997D01*
Y-283289D01*
G01Y-285622D02*
X56524Y-284455D01*
X55213Y-283580D01*
X53685Y-283289D01*
X51939Y-283872D01*
X50847Y-285038D01*
X49973Y-287080D01*
X49537Y-289122D01*
X49755Y-290872D01*
X50629Y-292914D01*
X51939Y-294372D01*
X53685Y-294955D01*
X54995Y-294663D01*
X56524Y-293497D01*
X57397Y-292331D01*
G01X84100Y-294955D02*
Y-277455D01*
X89340D01*
X91087Y-278330D01*
X92397Y-280372D01*
X92834Y-282705D01*
X92397Y-285038D01*
X91305Y-286788D01*
X89340Y-287664D01*
X84100D01*
G01X101164Y-294955D02*
Y-277455D01*
X105530D01*
X107277Y-278330D01*
X108587Y-279497D01*
X109679Y-281246D01*
X110552Y-283289D01*
X110770Y-286205D01*
X110552Y-289122D01*
X109679Y-291164D01*
X108587Y-292914D01*
X107277Y-294080D01*
X105530Y-294955D01*
X101164D01*
G01X119100D02*
Y-277455D01*
X124340D01*
X126087Y-278330D01*
X127397Y-280372D01*
X127834Y-282705D01*
X127397Y-285038D01*
X126305Y-286788D01*
X124340Y-287664D01*
X119100D01*
G01X142713Y-285622D02*
X143587Y-284747D01*
X144242Y-283289D01*
X144679Y-281246D01*
X144242Y-279497D01*
X143369Y-278330D01*
X141840Y-277455D01*
X135945D01*
Y-294955D01*
X143150D01*
X144679Y-293789D01*
X145552Y-292038D01*
X145989Y-289997D01*
X145552Y-287955D01*
X144242Y-286205D01*
X142713Y-285622D01*
X135945D01*
G01X171600Y-294955D02*
Y-277455D01*
X176840D01*
X178587Y-278330D01*
X179897Y-280372D01*
X180334Y-282705D01*
X179897Y-285038D01*
X178805Y-286788D01*
X176840Y-287664D01*
X171600D01*
G01X188008Y-277455D02*
X193467Y-294955D01*
X198926Y-277455D01*
G01X210967D02*
Y-294955D01*
G01X205945Y-277455D02*
X215989D01*
G01X21540Y-249955D02*
Y-232455D01*
X27217Y-247038D01*
X32894Y-232455D01*
Y-249955D01*
G01X44717D02*
X43407Y-249663D01*
X42097Y-248497D01*
X41223Y-246455D01*
X40787Y-244122D01*
X41223Y-241788D01*
X42097Y-239747D01*
X43407Y-238580D01*
X44717Y-238289D01*
X46027Y-238580D01*
X47337Y-239747D01*
X48210Y-241788D01*
X48429Y-244122D01*
X48210Y-246455D01*
X47337Y-248497D01*
X46027Y-249663D01*
X44717Y-249955D01*
G01X66147Y-232455D02*
Y-249955D01*
G01Y-247331D02*
X65274Y-248789D01*
X63963Y-249663D01*
X62435Y-249955D01*
X60689Y-249372D01*
X59379Y-247914D01*
X58505Y-246164D01*
X58287Y-244122D01*
X58505Y-242080D01*
X59379Y-240330D01*
X60689Y-238872D01*
X62435Y-238289D01*
X63963Y-238580D01*
X65055Y-239164D01*
X66147Y-240330D01*
G01X76442Y-242080D02*
X83429D01*
X82774Y-240038D01*
X81682Y-238872D01*
X80154Y-238289D01*
X78625Y-238580D01*
X77315Y-239455D01*
X76442Y-241497D01*
X76005Y-243247D01*
Y-244997D01*
X76442Y-246747D01*
X77534Y-248497D01*
X78844Y-249663D01*
X80372Y-249955D01*
X81900Y-249372D01*
X83429Y-247622D01*
G01X97217Y-249955D02*
Y-232455D01*
G01X252500Y-249955D02*
Y-232455D01*
X257740D01*
X259487Y-233330D01*
X260797Y-235372D01*
X261234Y-237705D01*
X260797Y-240038D01*
X259705Y-241788D01*
X257740Y-242664D01*
X252500D01*
G01X279170Y-233914D02*
X277860Y-233038D01*
X276332Y-232455D01*
X274585D01*
X272620Y-233330D01*
X271092Y-234788D01*
X270000Y-236539D01*
X269127Y-239455D01*
X268908Y-242080D01*
X269345Y-244705D01*
X270000Y-246455D01*
X271310Y-248205D01*
X272839Y-249372D01*
X274367Y-249955D01*
X275895D01*
X277424Y-249372D01*
X278734Y-248497D01*
X279826Y-247331D01*
G01X293613Y-240622D02*
X294487Y-239747D01*
X295142Y-238289D01*
X295579Y-236246D01*
X295142Y-234497D01*
X294269Y-233330D01*
X292740Y-232455D01*
X286845D01*
Y-249955D01*
X294050D01*
X295579Y-248789D01*
X296452Y-247038D01*
X296889Y-244997D01*
X296452Y-242955D01*
X295142Y-241205D01*
X293613Y-240622D01*
X286845D01*
G01X302817Y-255788D02*
X315917D01*
G01X321845Y-249955D02*
Y-232455D01*
X331889Y-249955D01*
Y-232455D01*
G01X344367Y-249955D02*
X342620Y-249663D01*
X341092Y-248497D01*
X339782Y-246747D01*
X338908Y-244705D01*
X338472Y-242372D01*
Y-240038D01*
X338908Y-237705D01*
X339782Y-235663D01*
X341092Y-233914D01*
X342620Y-232747D01*
X344367Y-232455D01*
X346113Y-232747D01*
X347642Y-233914D01*
X348952Y-235663D01*
X349826Y-237705D01*
X350262Y-240038D01*
Y-242372D01*
X349826Y-244705D01*
X348952Y-246747D01*
X347642Y-248497D01*
X346113Y-249663D01*
X344367Y-249955D01*
G01X197200Y562500D02*
Y566500D01*
X189800D01*
G01X265617Y-294955D02*
Y-277455D01*
X262997Y-280955D01*
G01Y-294955D02*
X268237D01*
G01X278314Y-292331D02*
X279623Y-293789D01*
X281152Y-294663D01*
X283117Y-294955D01*
X285082Y-294372D01*
X286610Y-293205D01*
X287702Y-291164D01*
X287920Y-288830D01*
X287484Y-286497D01*
X286392Y-285038D01*
X284863Y-283872D01*
X283335Y-283580D01*
X281807Y-283872D01*
X279842Y-285038D01*
X280497Y-277455D01*
X286392D01*
G01X296469Y-287664D02*
X297997Y-285622D01*
X299307Y-284455D01*
X301054Y-283872D01*
X302582Y-284455D01*
X303674Y-285622D01*
X304547Y-287372D01*
X304765Y-289413D01*
X304547Y-291164D01*
X303674Y-292914D01*
X302363Y-294372D01*
X300835Y-294955D01*
X299089Y-294372D01*
X297560Y-292622D01*
X296687Y-289997D01*
X296469Y-287080D01*
X296905Y-283289D01*
X297560Y-281246D01*
X298652Y-279205D01*
X300180Y-277747D01*
X301709Y-277455D01*
X303237Y-278038D01*
X304329Y-279497D01*
G01X313969Y-287664D02*
X315497Y-285622D01*
X316807Y-284455D01*
X318554Y-283872D01*
X320082Y-284455D01*
X321174Y-285622D01*
X322047Y-287372D01*
X322265Y-289413D01*
X322047Y-291164D01*
X321174Y-292914D01*
X319863Y-294372D01*
X318335Y-294955D01*
X316589Y-294372D01*
X315060Y-292622D01*
X314187Y-289997D01*
X313969Y-287080D01*
X314405Y-283289D01*
X315060Y-281246D01*
X316152Y-279205D01*
X317680Y-277747D01*
X319209Y-277455D01*
X320737Y-278038D01*
X321829Y-279497D01*
G01X331905Y-292914D02*
X333434Y-294372D01*
X335180Y-294955D01*
X336927Y-294372D01*
X338455Y-292622D01*
X339547Y-289997D01*
X339984Y-287372D01*
Y-284164D01*
X339547Y-281539D01*
X338455Y-279205D01*
X337145Y-278038D01*
X335617Y-277455D01*
X333870Y-278038D01*
X332560Y-279205D01*
X331687Y-280955D01*
X331250Y-283289D01*
X331687Y-285330D01*
X332779Y-287372D01*
X334089Y-288539D01*
X335617Y-288830D01*
X337363Y-288247D01*
X338674Y-286788D01*
X339984Y-284164D01*
G01X395208Y-232455D02*
X400667Y-249955D01*
X406126Y-232455D01*
G01X422534Y-249955D02*
X413800D01*
Y-232455D01*
X422534D01*
G01X419040Y-240913D02*
X413800D01*
G01X431300Y-249955D02*
Y-232455D01*
X436759D01*
X438505Y-233330D01*
X439597Y-234497D01*
X440034Y-236830D01*
X439597Y-239164D01*
X438287Y-240622D01*
X436759Y-241497D01*
X431300D01*
G01X436759D02*
X440034Y-249955D01*
G01X453167Y-250538D02*
X452730Y-250247D01*
Y-249663D01*
X453167Y-249372D01*
X453604Y-249663D01*
Y-250247D01*
X453167Y-250538D01*
G01X426917Y-294955D02*
Y-277455D01*
X424297Y-280955D01*
G01Y-294955D02*
X429537D01*
G01X528750Y-232455D02*
Y-249955D01*
X537484D01*
G01X554547D02*
Y-238289D01*
G01Y-240330D02*
X553674Y-239164D01*
X552363Y-238580D01*
X550835Y-238289D01*
X549307Y-238872D01*
X547997Y-240038D01*
X547123Y-241788D01*
X546687Y-244122D01*
X547123Y-246455D01*
X547997Y-248205D01*
X549307Y-249372D01*
X550835Y-249955D01*
X552363Y-249663D01*
X553674Y-248789D01*
X554547Y-247622D01*
G01X563532Y-255205D02*
X564842Y-255788D01*
X566589Y-255205D01*
X567680Y-254039D01*
X568554Y-252580D01*
X569863Y-247914D01*
X572702Y-238289D01*
G01X565715D02*
X569863Y-247914D01*
G01X582342Y-242080D02*
X589329D01*
X588674Y-240038D01*
X587582Y-238872D01*
X586054Y-238289D01*
X584525Y-238580D01*
X583215Y-239455D01*
X582342Y-241497D01*
X581905Y-243247D01*
Y-244997D01*
X582342Y-246747D01*
X583434Y-248497D01*
X584744Y-249663D01*
X586272Y-249955D01*
X587800Y-249372D01*
X589329Y-247622D01*
G01X600060Y-249955D02*
Y-238289D01*
G01Y-240622D02*
X601152Y-239455D01*
X602244Y-238580D01*
X603772Y-238289D01*
X604863Y-238580D01*
X606174Y-239455D01*
G01X533117Y-277455D02*
Y-294955D01*
G01X528095Y-277455D02*
X538139D01*
G01X546032Y-292622D02*
X547779Y-294080D01*
X549744Y-294955D01*
X551490D01*
X553237Y-294080D01*
X554547Y-292622D01*
X555202Y-290580D01*
X554765Y-288539D01*
X553674Y-286788D01*
X551709Y-285622D01*
X549089Y-285038D01*
X547560Y-283872D01*
X546905Y-281830D01*
X547342Y-279788D01*
X548434Y-278330D01*
X549962Y-277455D01*
X551490D01*
X553019Y-278038D01*
X554329Y-279497D01*
G01X565497Y-277455D02*
X570737D01*
G01X568117D02*
Y-294955D01*
G01X565497D02*
X570737D01*
G01X581250Y-277455D02*
Y-294955D01*
X589984D01*
G01X598314D02*
Y-277455D01*
G01X606610D02*
X598314Y-288247D01*
G01X607920Y-294955D02*
X602025Y-283289D01*
G01X670864Y-249955D02*
Y-232455D01*
X675230D01*
X676977Y-233330D01*
X678287Y-234497D01*
X679379Y-236246D01*
X680252Y-238289D01*
X680470Y-241205D01*
X680252Y-244122D01*
X679379Y-246164D01*
X678287Y-247914D01*
X676977Y-249080D01*
X675230Y-249955D01*
X670864D01*
G01X689892Y-242080D02*
X696879D01*
X696224Y-240038D01*
X695132Y-238872D01*
X693604Y-238289D01*
X692075Y-238580D01*
X690765Y-239455D01*
X689892Y-241497D01*
X689455Y-243247D01*
Y-244997D01*
X689892Y-246747D01*
X690984Y-248497D01*
X692294Y-249663D01*
X693822Y-249955D01*
X695350Y-249372D01*
X696879Y-247622D01*
G01X707392Y-247914D02*
X708484Y-249080D01*
X710012Y-249955D01*
X711322D01*
X712632Y-249372D01*
X713505Y-248497D01*
X713942Y-247331D01*
X713724Y-245580D01*
X712850Y-244705D01*
X708920Y-242955D01*
X708047Y-240913D01*
X708484Y-239455D01*
X709357Y-238580D01*
X710667Y-238289D01*
X711977Y-238580D01*
X713287Y-239455D01*
G01X728167Y-238289D02*
Y-249955D01*
G01Y-233622D02*
X727730Y-233330D01*
Y-232747D01*
X728167Y-232455D01*
X728604Y-232747D01*
Y-233330D01*
X728167Y-233622D01*
G01X742610Y-254330D02*
X744139Y-255497D01*
X745885Y-255788D01*
X747413Y-255497D01*
X748724Y-254039D01*
X749597Y-251997D01*
Y-238289D01*
G01Y-240622D02*
X748724Y-239455D01*
X747413Y-238580D01*
X745885Y-238289D01*
X744139Y-238872D01*
X743047Y-240038D01*
X742173Y-242080D01*
X741737Y-244122D01*
X741955Y-245872D01*
X742829Y-247914D01*
X744139Y-249372D01*
X745885Y-249955D01*
X747195Y-249663D01*
X748724Y-248497D01*
X749597Y-247331D01*
G01X759455Y-249955D02*
Y-238289D01*
G01Y-241205D02*
X760329Y-239747D01*
X761639Y-238580D01*
X763385Y-238289D01*
X764913Y-238580D01*
X766224Y-239747D01*
X766879Y-241788D01*
Y-249955D01*
G01X777392Y-242080D02*
X784379D01*
X783724Y-240038D01*
X782632Y-238872D01*
X781104Y-238289D01*
X779575Y-238580D01*
X778265Y-239455D01*
X777392Y-241497D01*
X776955Y-243247D01*
Y-244997D01*
X777392Y-246747D01*
X778484Y-248497D01*
X779794Y-249663D01*
X781322Y-249955D01*
X782850Y-249372D01*
X784379Y-247622D01*
G01X795110Y-249955D02*
Y-238289D01*
G01Y-240622D02*
X796202Y-239455D01*
X797294Y-238580D01*
X798822Y-238289D01*
X799913Y-238580D01*
X801224Y-239455D01*
G01X660367Y-277455D02*
X663423Y-294955D01*
X666917Y-277455D01*
X670410Y-294955D01*
X673467Y-277455D01*
G01X680050Y-294955D02*
Y-277455D01*
X685290D01*
X687037Y-278330D01*
X688347Y-280372D01*
X688784Y-282705D01*
X688347Y-285038D01*
X687255Y-286788D01*
X685290Y-287664D01*
X680050D01*
G01X697332Y-294955D02*
Y-277455D01*
G01X706502D02*
Y-294955D01*
G01Y-286205D02*
X697332D01*
G01X716579Y-289122D02*
X722255D01*
G01X732769Y-294955D02*
Y-277455D01*
X741065D01*
G01X738009Y-285913D02*
X732769D01*
G01X750050Y-277455D02*
Y-294955D01*
X758784D01*
G01X771917D02*
X770170Y-294663D01*
X768642Y-293497D01*
X767332Y-291747D01*
X766458Y-289705D01*
X766022Y-287372D01*
Y-285038D01*
X766458Y-282705D01*
X767332Y-280663D01*
X768642Y-278914D01*
X770170Y-277747D01*
X771917Y-277455D01*
X773663Y-277747D01*
X775192Y-278914D01*
X776502Y-280663D01*
X777376Y-282705D01*
X777812Y-285038D01*
Y-287372D01*
X777376Y-289705D01*
X776502Y-291747D01*
X775192Y-293497D01*
X773663Y-294663D01*
X771917Y-294955D01*
G01X785050D02*
Y-277455D01*
X790509D01*
X792255Y-278330D01*
X793347Y-279497D01*
X793784Y-281830D01*
X793347Y-284164D01*
X792037Y-285622D01*
X790509Y-286497D01*
X785050D01*
G01X790509D02*
X793784Y-294955D01*
G01X801458D02*
X806917Y-277455D01*
X812376Y-294955D01*
G01X810410Y-288830D02*
X803423D01*
G01X841867Y-294955D02*
Y-277455D01*
X839247Y-280955D01*
G01Y-294955D02*
X844487D01*
G01X859367D02*
Y-277455D01*
X856747Y-280955D01*
G01Y-294955D02*
X861987D01*
G01X872937Y-295538D02*
X880797Y-277455D01*
G01X894367Y-294955D02*
Y-277455D01*
X891747Y-280955D01*
G01Y-294955D02*
X896987D01*
G01X907719Y-287664D02*
X909247Y-285622D01*
X910557Y-284455D01*
X912304Y-283872D01*
X913832Y-284455D01*
X914924Y-285622D01*
X915797Y-287372D01*
X916015Y-289413D01*
X915797Y-291164D01*
X914924Y-292914D01*
X913613Y-294372D01*
X912085Y-294955D01*
X910339Y-294372D01*
X908810Y-292622D01*
X907937Y-289997D01*
X907719Y-287080D01*
X908155Y-283289D01*
X908810Y-281246D01*
X909902Y-279205D01*
X911430Y-277747D01*
X912959Y-277455D01*
X914487Y-278038D01*
X915579Y-279497D01*
G01X925437Y-295538D02*
X933297Y-277455D01*
G01X942719Y-280372D02*
X944029Y-278622D01*
X945557Y-277747D01*
X947304Y-277455D01*
X949487Y-278038D01*
X951015Y-279497D01*
X951452Y-281246D01*
X951234Y-282997D01*
X950360Y-284455D01*
X945994Y-287372D01*
X944029Y-289413D01*
X942719Y-292331D01*
X942282Y-294955D01*
X951452D01*
G01X964367Y-277455D02*
X962620Y-278038D01*
X961310Y-279497D01*
X960437Y-281246D01*
X959782Y-283580D01*
X959564Y-286205D01*
X959782Y-288830D01*
X960437Y-291164D01*
X961310Y-292914D01*
X962620Y-294372D01*
X964367Y-294955D01*
X966113Y-294372D01*
X967424Y-292914D01*
X968297Y-291164D01*
X968952Y-288830D01*
X969170Y-286205D01*
X968952Y-283580D01*
X968297Y-281246D01*
X967424Y-279497D01*
X966113Y-278038D01*
X964367Y-277455D01*
G01X981867Y-294955D02*
Y-277455D01*
X979247Y-280955D01*
G01Y-294955D02*
X984487D01*
G01X995219Y-287664D02*
X996747Y-285622D01*
X998057Y-284455D01*
X999804Y-283872D01*
X1001332Y-284455D01*
X1002424Y-285622D01*
X1003297Y-287372D01*
X1003515Y-289413D01*
X1003297Y-291164D01*
X1002424Y-292914D01*
X1001113Y-294372D01*
X999585Y-294955D01*
X997839Y-294372D01*
X996310Y-292622D01*
X995437Y-289997D01*
X995219Y-287080D01*
X995655Y-283289D01*
X996310Y-281246D01*
X997402Y-279205D01*
X998930Y-277747D01*
X1000459Y-277455D01*
X1001987Y-278038D01*
X1003079Y-279497D01*
G01X889564Y-249955D02*
Y-232455D01*
X893930D01*
X895677Y-233330D01*
X896987Y-234497D01*
X898079Y-236246D01*
X898952Y-238289D01*
X899170Y-241205D01*
X898952Y-244122D01*
X898079Y-246164D01*
X896987Y-247914D01*
X895677Y-249080D01*
X893930Y-249955D01*
X889564D01*
G01X915797D02*
Y-238289D01*
G01Y-240330D02*
X914924Y-239164D01*
X913613Y-238580D01*
X912085Y-238289D01*
X910557Y-238872D01*
X909247Y-240038D01*
X908373Y-241788D01*
X907937Y-244122D01*
X908373Y-246455D01*
X909247Y-248205D01*
X910557Y-249372D01*
X912085Y-249955D01*
X913613Y-249663D01*
X914924Y-248789D01*
X915797Y-247622D01*
G01X929367Y-232455D02*
Y-249955D01*
G01X926310Y-238289D02*
X932424D01*
G01X943592Y-242080D02*
X950579D01*
X949924Y-240038D01*
X948832Y-238872D01*
X947304Y-238289D01*
X945775Y-238580D01*
X944465Y-239455D01*
X943592Y-241497D01*
X943155Y-243247D01*
Y-244997D01*
X943592Y-246747D01*
X944684Y-248497D01*
X945994Y-249663D01*
X947522Y-249955D01*
X949050Y-249372D01*
X950579Y-247622D01*
G01X34787Y184261D02*
X63687D01*
Y197161D01*
X81987D01*
Y184261D01*
X95487D01*
Y23061D01*
X81987D01*
Y10161D01*
X63687D01*
Y23061D01*
X34787D01*
Y33411D01*
X41487D01*
Y173911D01*
X34787D01*
Y184261D01*
G01X32475Y303667D02*
Y306167D01*
G01X34225D02*
Y303667D01*
G01Y304917D02*
X32475D01*
G01X35742Y303959D02*
X36033Y303750D01*
X36367Y303667D01*
X36700Y303750D01*
X36992Y304000D01*
X37200Y304375D01*
X37283Y304750D01*
Y305209D01*
X37200Y305584D01*
X36992Y305917D01*
X36742Y306084D01*
X36450Y306167D01*
X36117Y306084D01*
X35867Y305917D01*
X35700Y305667D01*
X35617Y305334D01*
X35700Y305042D01*
X35908Y304750D01*
X36158Y304584D01*
X36450Y304542D01*
X36783Y304625D01*
X37033Y304834D01*
X37283Y305209D01*
G01X34787Y589773D02*
X63687D01*
Y602673D01*
X81987D01*
Y589773D01*
X95487D01*
Y428573D01*
X81987D01*
Y415673D01*
X63687D01*
Y428573D01*
X34787D01*
Y438923D01*
X41487D01*
Y579423D01*
X34787D01*
Y589773D01*
G01X17323Y745835D02*
X1969D01*
X0Y747804D01*
Y964152D01*
X23411D01*
Y556652D01*
G01X17323Y737174D02*
X1969D01*
X0Y735205D01*
Y556652D01*
X23411D01*
G01X29611Y649019D02*
X29861Y649227D01*
X30028Y649477D01*
X30111Y649769D01*
X30028Y650102D01*
X29861Y650352D01*
X29611Y650602D01*
X29278Y650685D01*
X27611D01*
G01X30111Y652952D02*
X27611D01*
X28111Y652452D01*
G01X30111D02*
Y653452D01*
G01X29819Y655344D02*
X30028Y655635D01*
X30111Y655969D01*
X30028Y656302D01*
X29778Y656594D01*
X29403Y656802D01*
X29028Y656885D01*
X28569D01*
X28194Y656802D01*
X27861Y656594D01*
X27694Y656344D01*
X27611Y656052D01*
X27694Y655719D01*
X27861Y655469D01*
X28111Y655302D01*
X28444Y655219D01*
X28736Y655302D01*
X29028Y655510D01*
X29194Y655760D01*
X29236Y656052D01*
X29153Y656385D01*
X28944Y656635D01*
X28569Y656885D01*
G01X17323Y745835D02*
G02Y737173I0J-4331D01*
G01X34787Y995285D02*
X63687D01*
Y1008185D01*
X81987D01*
Y995285D01*
X95487D01*
Y834085D01*
X81987D01*
Y821185D01*
X63687D01*
Y834085D01*
X34787D01*
Y844435D01*
X41487D01*
Y984935D01*
X34787D01*
Y995285D01*
G01X-12822Y801202D02*
X-12489Y801735D01*
X-12289Y802335D01*
Y802869D01*
X-12489Y803402D01*
X-12822Y803802D01*
X-13289Y804002D01*
X-13756Y803869D01*
X-14156Y803535D01*
X-14422Y802935D01*
X-14556Y802135D01*
X-14822Y801669D01*
X-15289Y801469D01*
X-15756Y801602D01*
X-16089Y801935D01*
X-16289Y802402D01*
Y802869D01*
X-16156Y803335D01*
X-15822Y803735D01*
G01X-12289Y807202D02*
X-16289D01*
G01X-14956Y811802D02*
X-12289D01*
G01X-16022D02*
X-16089Y811669D01*
X-16222D01*
X-16289Y811802D01*
X-16222Y811935D01*
X-16089D01*
X-16022Y811802D01*
G01X-16289Y816402D02*
X-12289D01*
G01X-14956Y815469D02*
Y817335D01*
G01X38207Y1059041D02*
Y1085041D01*
G01X25207Y1059041D02*
X38207D01*
G01X25207Y1085041D02*
Y1059041D01*
G01X31575Y1005500D02*
Y1008000D01*
G01X33325D02*
Y1005500D01*
G01Y1006750D02*
X31575D01*
G01X34758Y1006542D02*
X35050Y1006833D01*
X35300Y1007000D01*
X35633Y1007083D01*
X35925Y1007000D01*
X36133Y1006833D01*
X36300Y1006583D01*
X36342Y1006292D01*
X36300Y1006042D01*
X36133Y1005792D01*
X35883Y1005583D01*
X35592Y1005500D01*
X35258Y1005583D01*
X34967Y1005833D01*
X34800Y1006208D01*
X34758Y1006625D01*
X34842Y1007167D01*
X34967Y1007458D01*
X35175Y1007750D01*
X35467Y1007958D01*
X35758Y1008000D01*
X36050Y1007917D01*
X36258Y1007708D01*
G01X17323Y1241898D02*
X1969D01*
X0Y1243867D01*
Y1460215D01*
X23411D01*
Y1052715D01*
G01X17323Y1233237D02*
X1969D01*
X0Y1231268D01*
Y1052715D01*
X23411D01*
G01X38207Y1085041D02*
X25207D01*
G01X32500Y1176067D02*
X32750Y1176275D01*
X32917Y1176525D01*
X33000Y1176817D01*
X32917Y1177150D01*
X32750Y1177400D01*
X32500Y1177650D01*
X32167Y1177733D01*
X30500D01*
G01X33000Y1180000D02*
X30500D01*
X31000Y1179500D01*
G01X33000D02*
Y1180500D01*
G01Y1183100D02*
X32958Y1183392D01*
X32833Y1183725D01*
X32625Y1183933D01*
X32333Y1184017D01*
X32042Y1183933D01*
X31792Y1183683D01*
X31667Y1183308D01*
Y1182892D01*
X31583Y1182642D01*
X31375Y1182433D01*
X31083Y1182350D01*
X30792Y1182475D01*
X30583Y1182767D01*
X30500Y1183100D01*
X30583Y1183433D01*
X30792Y1183725D01*
X31083Y1183850D01*
X31375Y1183767D01*
X31583Y1183558D01*
X31667Y1183308D01*
Y1182892D01*
X31792Y1182517D01*
X32042Y1182267D01*
X32333Y1182183D01*
X32625Y1182267D01*
X32833Y1182475D01*
X32958Y1182808D01*
X33000Y1183100D01*
G01X34787Y1400797D02*
X63687D01*
Y1413697D01*
X81987D01*
Y1400797D01*
X95487D01*
Y1239597D01*
X81987D01*
Y1226697D01*
X63687D01*
Y1239597D01*
X34787D01*
Y1249947D01*
X41487D01*
Y1390447D01*
X34787D01*
Y1400797D01*
G01X17323Y1241898D02*
G02Y1233236I0J-4331D01*
G01X-12822Y1297265D02*
X-12489Y1297798D01*
X-12289Y1298398D01*
Y1298932D01*
X-12489Y1299465D01*
X-12822Y1299865D01*
X-13289Y1300065D01*
X-13756Y1299932D01*
X-14156Y1299598D01*
X-14422Y1298998D01*
X-14556Y1298198D01*
X-14822Y1297732D01*
X-15289Y1297532D01*
X-15756Y1297665D01*
X-16089Y1297998D01*
X-16289Y1298465D01*
Y1298932D01*
X-16156Y1299398D01*
X-15822Y1299798D01*
G01X-12289Y1303265D02*
X-16289D01*
G01X-14956Y1307865D02*
X-12289D01*
G01X-16022D02*
X-16089Y1307732D01*
X-16222D01*
X-16289Y1307865D01*
X-16222Y1307998D01*
X-16089D01*
X-16022Y1307865D01*
G01X-16289Y1312465D02*
X-12289D01*
G01X-14956Y1311532D02*
Y1313398D01*
G01X17323Y1659220D02*
X1969D01*
X0Y1661189D01*
Y1877537D01*
X23411D01*
Y1470037D01*
G01X17323Y1650559D02*
X1969D01*
X0Y1648590D01*
Y1470037D01*
X23411D01*
G01X29811Y1569804D02*
X30061Y1570012D01*
X30228Y1570262D01*
X30311Y1570554D01*
X30228Y1570887D01*
X30061Y1571137D01*
X29811Y1571387D01*
X29478Y1571470D01*
X27811D01*
G01X30311Y1573737D02*
X27811D01*
X28311Y1573237D01*
G01X30311D02*
Y1574237D01*
G01Y1576754D02*
X29769Y1576837D01*
X29311Y1576962D01*
X28894Y1577129D01*
X28436Y1577337D01*
X27811Y1577670D01*
Y1576004D01*
G01X34787Y1806309D02*
X63687D01*
Y1819209D01*
X81987D01*
Y1806309D01*
X95487D01*
Y1645109D01*
X81987D01*
Y1632209D01*
X63687D01*
Y1645109D01*
X34787D01*
Y1655459D01*
X41487D01*
Y1795959D01*
X34787D01*
Y1806309D01*
G01X34517Y1603500D02*
Y1606000D01*
X35558D01*
X35892Y1605875D01*
X36100Y1605708D01*
X36183Y1605375D01*
X36100Y1605042D01*
X35850Y1604833D01*
X35558Y1604708D01*
X34517D01*
G01X35558D02*
X36183Y1603500D01*
G01X37533Y1603875D02*
X37783Y1603667D01*
X38075Y1603542D01*
X38450Y1603500D01*
X38825Y1603583D01*
X39117Y1603750D01*
X39325Y1604042D01*
X39367Y1604375D01*
X39283Y1604708D01*
X39075Y1604917D01*
X38783Y1605083D01*
X38492Y1605125D01*
X38200Y1605083D01*
X37825Y1604917D01*
X37950Y1606000D01*
X39075D01*
G01X41467Y1603500D02*
X41550Y1604042D01*
X41675Y1604500D01*
X41842Y1604917D01*
X42050Y1605375D01*
X42383Y1606000D01*
X40717D01*
G01X43942Y1603792D02*
X44233Y1603583D01*
X44567Y1603500D01*
X44900Y1603583D01*
X45192Y1603833D01*
X45400Y1604208D01*
X45483Y1604583D01*
Y1605042D01*
X45400Y1605417D01*
X45192Y1605750D01*
X44942Y1605917D01*
X44650Y1606000D01*
X44317Y1605917D01*
X44067Y1605750D01*
X43900Y1605500D01*
X43817Y1605167D01*
X43900Y1604875D01*
X44108Y1604583D01*
X44358Y1604417D01*
X44650Y1604375D01*
X44983Y1604458D01*
X45233Y1604667D01*
X45483Y1605042D01*
G01X34600Y1611400D02*
X47600D01*
G01X34600Y1637400D02*
Y1611400D01*
G01X47600Y1637400D02*
X34600D01*
G01X32906Y1672547D02*
X32781Y1672297D01*
X32698Y1672005D01*
Y1671672D01*
X32823Y1671297D01*
X33031Y1671005D01*
X33281Y1670797D01*
X33698Y1670630D01*
X34073Y1670588D01*
X34448Y1670672D01*
X34698Y1670797D01*
X34948Y1671047D01*
X35115Y1671338D01*
X35198Y1671630D01*
Y1671922D01*
X35115Y1672213D01*
X34990Y1672463D01*
X34823Y1672672D01*
G01X34906Y1674022D02*
X35115Y1674313D01*
X35198Y1674647D01*
X35115Y1674980D01*
X34865Y1675272D01*
X34490Y1675480D01*
X34115Y1675563D01*
X33656D01*
X33281Y1675480D01*
X32948Y1675272D01*
X32781Y1675022D01*
X32698Y1674730D01*
X32781Y1674397D01*
X32948Y1674147D01*
X33198Y1673980D01*
X33531Y1673897D01*
X33823Y1673980D01*
X34115Y1674188D01*
X34281Y1674438D01*
X34323Y1674730D01*
X34240Y1675063D01*
X34031Y1675313D01*
X33656Y1675563D01*
G01X34823Y1676913D02*
X35031Y1677163D01*
X35156Y1677455D01*
X35198Y1677830D01*
X35115Y1678205D01*
X34948Y1678497D01*
X34656Y1678705D01*
X34323Y1678747D01*
X33990Y1678663D01*
X33781Y1678455D01*
X33615Y1678163D01*
X33573Y1677872D01*
X33615Y1677580D01*
X33781Y1677205D01*
X32698Y1677330D01*
Y1678455D01*
G01X34698Y1680013D02*
X34990Y1680263D01*
X35156Y1680597D01*
X35198Y1680972D01*
X35156Y1681305D01*
X34948Y1681638D01*
X34698Y1681847D01*
X34448Y1681888D01*
X34156Y1681805D01*
X33948Y1681513D01*
X33865Y1681222D01*
Y1680847D01*
G01Y1681222D02*
X33740Y1681472D01*
X33531Y1681680D01*
X33281Y1681763D01*
X33031Y1681680D01*
X32823Y1681472D01*
X32698Y1681097D01*
X32740Y1680722D01*
X32906Y1680347D01*
G01X34906Y1683322D02*
X35115Y1683613D01*
X35198Y1683947D01*
X35115Y1684280D01*
X34865Y1684572D01*
X34490Y1684780D01*
X34115Y1684863D01*
X33656D01*
X33281Y1684780D01*
X32948Y1684572D01*
X32781Y1684322D01*
X32698Y1684030D01*
X32781Y1683697D01*
X32948Y1683447D01*
X33198Y1683280D01*
X33531Y1683197D01*
X33823Y1683280D01*
X34115Y1683488D01*
X34281Y1683738D01*
X34323Y1684030D01*
X34240Y1684363D01*
X34031Y1684613D01*
X33656Y1684863D01*
G01X37043Y1672694D02*
X36918Y1672444D01*
X36835Y1672152D01*
Y1671819D01*
X36960Y1671444D01*
X37168Y1671152D01*
X37418Y1670944D01*
X37835Y1670777D01*
X38210Y1670735D01*
X38585Y1670819D01*
X38835Y1670944D01*
X39085Y1671194D01*
X39252Y1671485D01*
X39335Y1671777D01*
Y1672069D01*
X39252Y1672360D01*
X39127Y1672610D01*
X38960Y1672819D01*
G01X39043Y1674169D02*
X39252Y1674460D01*
X39335Y1674794D01*
X39252Y1675127D01*
X39002Y1675419D01*
X38627Y1675627D01*
X38252Y1675710D01*
X37793D01*
X37418Y1675627D01*
X37085Y1675419D01*
X36918Y1675169D01*
X36835Y1674877D01*
X36918Y1674544D01*
X37085Y1674294D01*
X37335Y1674127D01*
X37668Y1674044D01*
X37960Y1674127D01*
X38252Y1674335D01*
X38418Y1674585D01*
X38460Y1674877D01*
X38377Y1675210D01*
X38168Y1675460D01*
X37793Y1675710D01*
G01X38960Y1677060D02*
X39168Y1677310D01*
X39293Y1677602D01*
X39335Y1677977D01*
X39252Y1678352D01*
X39085Y1678644D01*
X38793Y1678852D01*
X38460Y1678894D01*
X38127Y1678810D01*
X37918Y1678602D01*
X37752Y1678310D01*
X37710Y1678019D01*
X37752Y1677727D01*
X37918Y1677352D01*
X36835Y1677477D01*
Y1678602D01*
G01X38835Y1680160D02*
X39127Y1680410D01*
X39293Y1680744D01*
X39335Y1681119D01*
X39293Y1681452D01*
X39085Y1681785D01*
X38835Y1681994D01*
X38585Y1682035D01*
X38293Y1681952D01*
X38085Y1681660D01*
X38002Y1681369D01*
Y1680994D01*
G01Y1681369D02*
X37877Y1681619D01*
X37668Y1681827D01*
X37418Y1681910D01*
X37168Y1681827D01*
X36960Y1681619D01*
X36835Y1681244D01*
X36877Y1680869D01*
X37043Y1680494D01*
G01X39335Y1684177D02*
X39293Y1684469D01*
X39168Y1684802D01*
X38960Y1685010D01*
X38668Y1685094D01*
X38377Y1685010D01*
X38127Y1684760D01*
X38002Y1684385D01*
Y1683969D01*
X37918Y1683719D01*
X37710Y1683510D01*
X37418Y1683427D01*
X37127Y1683552D01*
X36918Y1683844D01*
X36835Y1684177D01*
X36918Y1684510D01*
X37127Y1684802D01*
X37418Y1684927D01*
X37710Y1684844D01*
X37918Y1684635D01*
X38002Y1684385D01*
Y1683969D01*
X38127Y1683594D01*
X38377Y1683344D01*
X38668Y1683260D01*
X38960Y1683344D01*
X39168Y1683552D01*
X39293Y1683885D01*
X39335Y1684177D01*
G01X-12822Y1714587D02*
X-12489Y1715120D01*
X-12289Y1715720D01*
Y1716254D01*
X-12489Y1716787D01*
X-12822Y1717187D01*
X-13289Y1717387D01*
X-13756Y1717254D01*
X-14156Y1716920D01*
X-14422Y1716320D01*
X-14556Y1715520D01*
X-14822Y1715054D01*
X-15289Y1714854D01*
X-15756Y1714987D01*
X-16089Y1715320D01*
X-16289Y1715787D01*
Y1716254D01*
X-16156Y1716720D01*
X-15822Y1717120D01*
G01X-12289Y1720587D02*
X-16289D01*
G01X-14956Y1725187D02*
X-12289D01*
G01X-16022D02*
X-16089Y1725054D01*
X-16222D01*
X-16289Y1725187D01*
X-16222Y1725320D01*
X-16089D01*
X-16022Y1725187D01*
G01X-16289Y1729787D02*
X-12289D01*
G01X-14956Y1728854D02*
Y1730720D01*
G01X17323Y1659220D02*
G02Y1650558I0J-4331D01*
G01X27017Y1790342D02*
X26767Y1790467D01*
X26475Y1790550D01*
X26142D01*
X25767Y1790425D01*
X25475Y1790217D01*
X25267Y1789967D01*
X25100Y1789550D01*
X25058Y1789175D01*
X25142Y1788800D01*
X25267Y1788550D01*
X25517Y1788300D01*
X25808Y1788133D01*
X26100Y1788050D01*
X26392D01*
X26683Y1788133D01*
X26933Y1788258D01*
X27142Y1788425D01*
G01X28492Y1788342D02*
X28783Y1788133D01*
X29117Y1788050D01*
X29450Y1788133D01*
X29742Y1788383D01*
X29950Y1788758D01*
X30033Y1789133D01*
Y1789592D01*
X29950Y1789967D01*
X29742Y1790300D01*
X29492Y1790467D01*
X29200Y1790550D01*
X28867Y1790467D01*
X28617Y1790300D01*
X28450Y1790050D01*
X28367Y1789717D01*
X28450Y1789425D01*
X28658Y1789133D01*
X28908Y1788967D01*
X29200Y1788925D01*
X29533Y1789008D01*
X29783Y1789217D01*
X30033Y1789592D01*
G01X31383Y1788425D02*
X31633Y1788217D01*
X31925Y1788092D01*
X32300Y1788050D01*
X32675Y1788133D01*
X32967Y1788300D01*
X33175Y1788592D01*
X33217Y1788925D01*
X33133Y1789258D01*
X32925Y1789467D01*
X32633Y1789633D01*
X32342Y1789675D01*
X32050Y1789633D01*
X31675Y1789467D01*
X31800Y1790550D01*
X32925D01*
G01X35900Y1788050D02*
Y1790550D01*
X34358Y1788758D01*
X36442D01*
G01X38500Y1788050D02*
Y1790550D01*
X38000Y1790050D01*
G01Y1788050D02*
X39000D01*
G01X27017Y1785842D02*
X26767Y1785967D01*
X26475Y1786050D01*
X26142D01*
X25767Y1785925D01*
X25475Y1785717D01*
X25267Y1785467D01*
X25100Y1785050D01*
X25058Y1784675D01*
X25142Y1784300D01*
X25267Y1784050D01*
X25517Y1783800D01*
X25808Y1783633D01*
X26100Y1783550D01*
X26392D01*
X26683Y1783633D01*
X26933Y1783758D01*
X27142Y1783925D01*
G01X28492Y1783842D02*
X28783Y1783633D01*
X29117Y1783550D01*
X29450Y1783633D01*
X29742Y1783883D01*
X29950Y1784258D01*
X30033Y1784633D01*
Y1785092D01*
X29950Y1785467D01*
X29742Y1785800D01*
X29492Y1785967D01*
X29200Y1786050D01*
X28867Y1785967D01*
X28617Y1785800D01*
X28450Y1785550D01*
X28367Y1785217D01*
X28450Y1784925D01*
X28658Y1784633D01*
X28908Y1784467D01*
X29200Y1784425D01*
X29533Y1784508D01*
X29783Y1784717D01*
X30033Y1785092D01*
G01X31383Y1783925D02*
X31633Y1783717D01*
X31925Y1783592D01*
X32300Y1783550D01*
X32675Y1783633D01*
X32967Y1783800D01*
X33175Y1784092D01*
X33217Y1784425D01*
X33133Y1784758D01*
X32925Y1784967D01*
X32633Y1785133D01*
X32342Y1785175D01*
X32050Y1785133D01*
X31675Y1784967D01*
X31800Y1786050D01*
X32925D01*
G01X35900Y1783550D02*
Y1786050D01*
X34358Y1784258D01*
X36442D01*
G01X38500Y1786050D02*
X38167Y1785967D01*
X37917Y1785758D01*
X37750Y1785508D01*
X37625Y1785175D01*
X37583Y1784800D01*
X37625Y1784425D01*
X37750Y1784092D01*
X37917Y1783842D01*
X38167Y1783633D01*
X38500Y1783550D01*
X38833Y1783633D01*
X39083Y1783842D01*
X39250Y1784092D01*
X39375Y1784425D01*
X39417Y1784800D01*
X39375Y1785175D01*
X39250Y1785508D01*
X39083Y1785758D01*
X38833Y1785967D01*
X38500Y1786050D01*
G01X44050Y1860050D02*
X25350D01*
Y1870350D01*
X44050D01*
Y1860050D01*
G01Y1847750D02*
X25350D01*
Y1858050D01*
X44050D01*
Y1847750D01*
G01Y1835450D02*
X25350D01*
Y1845750D01*
X44050D01*
Y1835450D01*
G01Y1872350D02*
X25350D01*
Y1882650D01*
X44050D01*
Y1872350D01*
G01X36900Y1942767D02*
X34400D01*
Y1943808D01*
X34525Y1944142D01*
X34692Y1944350D01*
X35025Y1944433D01*
X35358Y1944350D01*
X35567Y1944100D01*
X35692Y1943808D01*
Y1942767D01*
G01Y1943808D02*
X36900Y1944433D01*
G01X36608Y1945992D02*
X36817Y1946283D01*
X36900Y1946617D01*
X36817Y1946950D01*
X36567Y1947242D01*
X36192Y1947450D01*
X35817Y1947533D01*
X35358D01*
X34983Y1947450D01*
X34650Y1947242D01*
X34483Y1946992D01*
X34400Y1946700D01*
X34483Y1946367D01*
X34650Y1946117D01*
X34900Y1945950D01*
X35233Y1945867D01*
X35525Y1945950D01*
X35817Y1946158D01*
X35983Y1946408D01*
X36025Y1946700D01*
X35942Y1947033D01*
X35733Y1947283D01*
X35358Y1947533D01*
G01X36525Y1948883D02*
X36733Y1949133D01*
X36858Y1949425D01*
X36900Y1949800D01*
X36817Y1950175D01*
X36650Y1950467D01*
X36358Y1950675D01*
X36025Y1950717D01*
X35692Y1950633D01*
X35483Y1950425D01*
X35317Y1950133D01*
X35275Y1949842D01*
X35317Y1949550D01*
X35483Y1949175D01*
X34400Y1949300D01*
Y1950425D01*
G01Y1952900D02*
X34483Y1952567D01*
X34692Y1952317D01*
X34942Y1952150D01*
X35275Y1952025D01*
X35650Y1951983D01*
X36025Y1952025D01*
X36358Y1952150D01*
X36608Y1952317D01*
X36817Y1952567D01*
X36900Y1952900D01*
X36817Y1953233D01*
X36608Y1953483D01*
X36358Y1953650D01*
X36025Y1953775D01*
X35650Y1953817D01*
X35275Y1953775D01*
X34942Y1953650D01*
X34692Y1953483D01*
X34483Y1953233D01*
X34400Y1952900D01*
G01X36900Y1956000D02*
X36858Y1956292D01*
X36733Y1956625D01*
X36525Y1956833D01*
X36233Y1956917D01*
X35942Y1956833D01*
X35692Y1956583D01*
X35567Y1956208D01*
Y1955792D01*
X35483Y1955542D01*
X35275Y1955333D01*
X34983Y1955250D01*
X34692Y1955375D01*
X34483Y1955667D01*
X34400Y1956000D01*
X34483Y1956333D01*
X34692Y1956625D01*
X34983Y1956750D01*
X35275Y1956667D01*
X35483Y1956458D01*
X35567Y1956208D01*
Y1955792D01*
X35692Y1955417D01*
X35942Y1955167D01*
X36233Y1955083D01*
X36525Y1955167D01*
X36733Y1955375D01*
X36858Y1955708D01*
X36900Y1956000D01*
G01X35300Y1958600D02*
X39300D01*
Y1966000D01*
G01X40900Y1942767D02*
X38400D01*
Y1943808D01*
X38525Y1944142D01*
X38692Y1944350D01*
X39025Y1944433D01*
X39358Y1944350D01*
X39567Y1944100D01*
X39692Y1943808D01*
Y1942767D01*
G01Y1943808D02*
X40900Y1944433D01*
G01X40608Y1945992D02*
X40817Y1946283D01*
X40900Y1946617D01*
X40817Y1946950D01*
X40567Y1947242D01*
X40192Y1947450D01*
X39817Y1947533D01*
X39358D01*
X38983Y1947450D01*
X38650Y1947242D01*
X38483Y1946992D01*
X38400Y1946700D01*
X38483Y1946367D01*
X38650Y1946117D01*
X38900Y1945950D01*
X39233Y1945867D01*
X39525Y1945950D01*
X39817Y1946158D01*
X39983Y1946408D01*
X40025Y1946700D01*
X39942Y1947033D01*
X39733Y1947283D01*
X39358Y1947533D01*
G01X40900Y1949717D02*
X40358Y1949800D01*
X39900Y1949925D01*
X39483Y1950092D01*
X39025Y1950300D01*
X38400Y1950633D01*
Y1948967D01*
G01X39858Y1952108D02*
X39567Y1952400D01*
X39400Y1952650D01*
X39317Y1952983D01*
X39400Y1953275D01*
X39567Y1953483D01*
X39817Y1953650D01*
X40108Y1953692D01*
X40358Y1953650D01*
X40608Y1953483D01*
X40817Y1953233D01*
X40900Y1952942D01*
X40817Y1952608D01*
X40567Y1952317D01*
X40192Y1952150D01*
X39775Y1952108D01*
X39233Y1952192D01*
X38942Y1952317D01*
X38650Y1952525D01*
X38442Y1952817D01*
X38400Y1953108D01*
X38483Y1953400D01*
X38692Y1953608D01*
G01X40525Y1955083D02*
X40733Y1955333D01*
X40858Y1955625D01*
X40900Y1956000D01*
X40817Y1956375D01*
X40650Y1956667D01*
X40358Y1956875D01*
X40025Y1956917D01*
X39692Y1956833D01*
X39483Y1956625D01*
X39317Y1956333D01*
X39275Y1956042D01*
X39317Y1955750D01*
X39483Y1955375D01*
X38400Y1955500D01*
Y1956625D01*
G01X25967Y1975000D02*
Y1977500D01*
X27008D01*
X27342Y1977375D01*
X27550Y1977208D01*
X27633Y1976875D01*
X27550Y1976542D01*
X27300Y1976333D01*
X27008Y1976208D01*
X25967D01*
G01X27008D02*
X27633Y1975000D01*
G01X29192Y1975292D02*
X29483Y1975083D01*
X29817Y1975000D01*
X30150Y1975083D01*
X30442Y1975333D01*
X30650Y1975708D01*
X30733Y1976083D01*
Y1976542D01*
X30650Y1976917D01*
X30442Y1977250D01*
X30192Y1977417D01*
X29900Y1977500D01*
X29567Y1977417D01*
X29317Y1977250D01*
X29150Y1977000D01*
X29067Y1976667D01*
X29150Y1976375D01*
X29358Y1976083D01*
X29608Y1975917D01*
X29900Y1975875D01*
X30233Y1975958D01*
X30483Y1976167D01*
X30733Y1976542D01*
G01X33000Y1975000D02*
X33292Y1975042D01*
X33625Y1975167D01*
X33833Y1975375D01*
X33917Y1975667D01*
X33833Y1975958D01*
X33583Y1976208D01*
X33208Y1976333D01*
X32792D01*
X32542Y1976417D01*
X32333Y1976625D01*
X32250Y1976917D01*
X32375Y1977208D01*
X32667Y1977417D01*
X33000Y1977500D01*
X33333Y1977417D01*
X33625Y1977208D01*
X33750Y1976917D01*
X33667Y1976625D01*
X33458Y1976417D01*
X33208Y1976333D01*
X32792D01*
X32417Y1976208D01*
X32167Y1975958D01*
X32083Y1975667D01*
X32167Y1975375D01*
X32375Y1975167D01*
X32708Y1975042D01*
X33000Y1975000D01*
G01X36100D02*
Y1977500D01*
X35600Y1977000D01*
G01Y1975000D02*
X36600D01*
G01X38283Y1975500D02*
X38533Y1975208D01*
X38867Y1975042D01*
X39242Y1975000D01*
X39575Y1975042D01*
X39908Y1975250D01*
X40117Y1975500D01*
X40158Y1975750D01*
X40075Y1976042D01*
X39783Y1976250D01*
X39492Y1976333D01*
X39117D01*
G01X39492D02*
X39742Y1976458D01*
X39950Y1976667D01*
X40033Y1976917D01*
X39950Y1977167D01*
X39742Y1977375D01*
X39367Y1977500D01*
X38992Y1977458D01*
X38617Y1977292D01*
G01X31375Y1972275D02*
Y1968275D01*
X38775D01*
G01X11675Y1945167D02*
Y1947667D01*
G01X13425D02*
Y1945167D01*
G01Y1946417D02*
X11675D01*
G01X15650Y1945167D02*
Y1947667D01*
X15150Y1947167D01*
G01Y1945167D02*
X16150D01*
G01X94567Y9400D02*
Y11900D01*
X95567D01*
X95900Y11775D01*
X96150Y11483D01*
X96233Y11150D01*
X96150Y10817D01*
X95942Y10567D01*
X95567Y10442D01*
X94567D01*
G01X99417Y11692D02*
X99167Y11817D01*
X98875Y11900D01*
X98542D01*
X98167Y11775D01*
X97875Y11567D01*
X97667Y11317D01*
X97500Y10900D01*
X97458Y10525D01*
X97542Y10150D01*
X97667Y9900D01*
X97917Y9650D01*
X98208Y9483D01*
X98500Y9400D01*
X98792D01*
X99083Y9483D01*
X99333Y9608D01*
X99542Y9775D01*
G01X101600Y9400D02*
Y11900D01*
X101100Y11400D01*
G01Y9400D02*
X102100D01*
G01X103908Y11483D02*
X104158Y11733D01*
X104450Y11858D01*
X104783Y11900D01*
X105200Y11817D01*
X105492Y11608D01*
X105575Y11358D01*
X105533Y11108D01*
X105367Y10900D01*
X104533Y10483D01*
X104158Y10192D01*
X103908Y9775D01*
X103825Y9400D01*
X105575D01*
G01X106883Y9900D02*
X107133Y9608D01*
X107467Y9442D01*
X107842Y9400D01*
X108175Y9442D01*
X108508Y9650D01*
X108717Y9900D01*
X108758Y10150D01*
X108675Y10442D01*
X108383Y10650D01*
X108092Y10733D01*
X107717D01*
G01X108092D02*
X108342Y10858D01*
X108550Y11067D01*
X108633Y11317D01*
X108550Y11567D01*
X108342Y11775D01*
X107967Y11900D01*
X107592Y11858D01*
X107217Y11692D01*
G01X109983Y9900D02*
X110233Y9608D01*
X110567Y9442D01*
X110942Y9400D01*
X111275Y9442D01*
X111608Y9650D01*
X111817Y9900D01*
X111858Y10150D01*
X111775Y10442D01*
X111483Y10650D01*
X111192Y10733D01*
X110817D01*
G01X111192D02*
X111442Y10858D01*
X111650Y11067D01*
X111733Y11317D01*
X111650Y11567D01*
X111442Y11775D01*
X111067Y11900D01*
X110692Y11858D01*
X110317Y11692D01*
G01X95167Y16400D02*
Y18900D01*
X96208D01*
X96542Y18775D01*
X96750Y18608D01*
X96833Y18275D01*
X96750Y17942D01*
X96500Y17733D01*
X96208Y17608D01*
X95167D01*
G01X96208D02*
X96833Y16400D01*
G01X98392Y16692D02*
X98683Y16483D01*
X99017Y16400D01*
X99350Y16483D01*
X99642Y16733D01*
X99850Y17108D01*
X99933Y17483D01*
Y17942D01*
X99850Y18317D01*
X99642Y18650D01*
X99392Y18817D01*
X99100Y18900D01*
X98767Y18817D01*
X98517Y18650D01*
X98350Y18400D01*
X98267Y18067D01*
X98350Y17775D01*
X98558Y17483D01*
X98808Y17317D01*
X99100Y17275D01*
X99433Y17358D01*
X99683Y17567D01*
X99933Y17942D01*
G01X101408Y18483D02*
X101658Y18733D01*
X101950Y18858D01*
X102283Y18900D01*
X102700Y18817D01*
X102992Y18608D01*
X103075Y18358D01*
X103033Y18108D01*
X102867Y17900D01*
X102033Y17483D01*
X101658Y17192D01*
X101408Y16775D01*
X101325Y16400D01*
X103075D01*
G01X105800D02*
Y18900D01*
X104258Y17108D01*
X106342D01*
G01X107692Y16692D02*
X107983Y16483D01*
X108317Y16400D01*
X108650Y16483D01*
X108942Y16733D01*
X109150Y17108D01*
X109233Y17483D01*
Y17942D01*
X109150Y18317D01*
X108942Y18650D01*
X108692Y18817D01*
X108400Y18900D01*
X108067Y18817D01*
X107817Y18650D01*
X107650Y18400D01*
X107567Y18067D01*
X107650Y17775D01*
X107858Y17483D01*
X108108Y17317D01*
X108400Y17275D01*
X108733Y17358D01*
X108983Y17567D01*
X109233Y17942D01*
G01X98900Y20100D02*
X111900D01*
G01X98900Y46100D02*
Y20100D01*
G01X111900Y46100D02*
X98900D01*
G01X101900Y106167D02*
X102150Y106375D01*
X102317Y106625D01*
X102400Y106917D01*
X102317Y107250D01*
X102150Y107500D01*
X101900Y107750D01*
X101567Y107833D01*
X99900D01*
G01X102400Y110100D02*
X99900D01*
X100400Y109600D01*
G01X102400D02*
Y110600D01*
G01Y113700D02*
X99900D01*
X101692Y112158D01*
Y114242D01*
G01X104400Y69117D02*
X101900D01*
Y70158D01*
X102025Y70492D01*
X102192Y70700D01*
X102525Y70783D01*
X102858Y70700D01*
X103067Y70450D01*
X103192Y70158D01*
Y69117D01*
G01Y70158D02*
X104400Y70783D01*
G01Y73550D02*
X101900D01*
X103692Y72008D01*
Y74092D01*
G01X104400Y76150D02*
X101900D01*
X102400Y75650D01*
G01X104400D02*
Y76650D01*
G01Y79167D02*
X103858Y79250D01*
X103400Y79375D01*
X102983Y79542D01*
X102525Y79750D01*
X101900Y80083D01*
Y78417D01*
G01X108400Y69117D02*
X105900D01*
Y70158D01*
X106025Y70492D01*
X106192Y70700D01*
X106525Y70783D01*
X106858Y70700D01*
X107067Y70450D01*
X107192Y70158D01*
Y69117D01*
G01Y70158D02*
X108400Y70783D01*
G01Y73550D02*
X105900D01*
X107692Y72008D01*
Y74092D01*
G01X108400Y76150D02*
X105900D01*
X106400Y75650D01*
G01X108400D02*
Y76650D01*
G01Y79250D02*
X108358Y79542D01*
X108233Y79875D01*
X108025Y80083D01*
X107733Y80167D01*
X107442Y80083D01*
X107192Y79833D01*
X107067Y79458D01*
Y79042D01*
X106983Y78792D01*
X106775Y78583D01*
X106483Y78500D01*
X106192Y78625D01*
X105983Y78917D01*
X105900Y79250D01*
X105983Y79583D01*
X106192Y79875D01*
X106483Y80000D01*
X106775Y79917D01*
X106983Y79708D01*
X107067Y79458D01*
Y79042D01*
X107192Y78667D01*
X107442Y78417D01*
X107733Y78333D01*
X108025Y78417D01*
X108233Y78625D01*
X108358Y78958D01*
X108400Y79250D01*
G01X88375Y189833D02*
X88708Y189625D01*
X89083Y189500D01*
X89417D01*
X89750Y189625D01*
X90000Y189833D01*
X90125Y190125D01*
X90042Y190417D01*
X89833Y190667D01*
X89458Y190833D01*
X88958Y190917D01*
X88667Y191083D01*
X88542Y191375D01*
X88625Y191667D01*
X88833Y191875D01*
X89125Y192000D01*
X89417D01*
X89708Y191917D01*
X89958Y191708D01*
G01X91433Y189500D02*
Y192000D01*
X92267D01*
X92600Y191875D01*
X92850Y191708D01*
X93058Y191458D01*
X93225Y191167D01*
X93267Y190750D01*
X93225Y190333D01*
X93058Y190042D01*
X92850Y189792D01*
X92600Y189625D01*
X92267Y189500D01*
X91433D01*
G01X94533D02*
Y192000D01*
X95367D01*
X95700Y191875D01*
X95950Y191708D01*
X96158Y191458D01*
X96325Y191167D01*
X96367Y190750D01*
X96325Y190333D01*
X96158Y190042D01*
X95950Y189792D01*
X95700Y189625D01*
X95367Y189500D01*
X94533D01*
G01X100608D02*
X101650Y192000D01*
X102692Y189500D01*
G01X102317Y190375D02*
X100983D01*
G01X105667Y191792D02*
X105417Y191917D01*
X105125Y192000D01*
X104792D01*
X104417Y191875D01*
X104125Y191667D01*
X103917Y191417D01*
X103750Y191000D01*
X103708Y190625D01*
X103792Y190250D01*
X103917Y190000D01*
X104167Y189750D01*
X104458Y189583D01*
X104750Y189500D01*
X105042D01*
X105333Y189583D01*
X105583Y189708D01*
X105792Y189875D01*
G01X107850Y192000D02*
Y189500D01*
G01X106892Y192000D02*
X108808D01*
G01X110950Y189500D02*
Y192000D01*
X110450Y191500D01*
G01Y189500D02*
X111450D01*
G01X114550D02*
Y192000D01*
X113008Y190208D01*
X115092D01*
G01X115902Y185001D02*
X115069Y183668D01*
X114569Y182168D01*
Y180834D01*
X115069Y179501D01*
X115902Y178501D01*
X117069Y178001D01*
X118235Y178334D01*
X119236Y179168D01*
X119902Y180668D01*
X120236Y182668D01*
X120902Y183834D01*
X122069Y184334D01*
X123236Y184001D01*
X124069Y183168D01*
X124569Y182001D01*
Y180834D01*
X124236Y179668D01*
X123402Y178668D01*
G01X115902Y174401D02*
X115069Y173068D01*
X114569Y171568D01*
Y170234D01*
X115069Y168901D01*
X115902Y167901D01*
X117069Y167401D01*
X118235Y167734D01*
X119236Y168568D01*
X119902Y170068D01*
X120236Y172068D01*
X120902Y173234D01*
X122069Y173734D01*
X123236Y173401D01*
X124069Y172568D01*
X124569Y171401D01*
Y170234D01*
X124236Y169068D01*
X123402Y168068D01*
G01X114569Y163968D02*
X124569D01*
Y160634D01*
X124069Y159301D01*
X123402Y158301D01*
X122402Y157468D01*
X121235Y156801D01*
X119569Y156634D01*
X117902Y156801D01*
X116736Y157468D01*
X115735Y158301D01*
X115069Y159301D01*
X114569Y160634D01*
Y163968D01*
G01Y149701D02*
X124569D01*
X122569Y151701D01*
G01X114569D02*
Y147701D01*
G01Y137101D02*
X124569D01*
X117402Y143268D01*
Y134934D01*
G01X106000Y128417D02*
X103500D01*
Y129417D01*
X103625Y129750D01*
X103917Y130000D01*
X104250Y130083D01*
X104583Y130000D01*
X104833Y129792D01*
X104958Y129417D01*
Y128417D01*
G01X103708Y133267D02*
X103583Y133017D01*
X103500Y132725D01*
Y132392D01*
X103625Y132017D01*
X103833Y131725D01*
X104083Y131517D01*
X104500Y131350D01*
X104875Y131308D01*
X105250Y131392D01*
X105500Y131517D01*
X105750Y131767D01*
X105917Y132058D01*
X106000Y132350D01*
Y132642D01*
X105917Y132933D01*
X105792Y133183D01*
X105625Y133392D01*
G01X106000Y135450D02*
X103500D01*
X104000Y134950D01*
G01X106000D02*
Y135950D01*
G01X103917Y137758D02*
X103667Y138008D01*
X103542Y138300D01*
X103500Y138633D01*
X103583Y139050D01*
X103792Y139342D01*
X104042Y139425D01*
X104292Y139383D01*
X104500Y139217D01*
X104917Y138383D01*
X105208Y138008D01*
X105625Y137758D01*
X106000Y137675D01*
Y139425D01*
G01X105500Y140733D02*
X105792Y140983D01*
X105958Y141317D01*
X106000Y141692D01*
X105958Y142025D01*
X105750Y142358D01*
X105500Y142567D01*
X105250Y142608D01*
X104958Y142525D01*
X104750Y142233D01*
X104667Y141942D01*
Y141567D01*
G01Y141942D02*
X104542Y142192D01*
X104333Y142400D01*
X104083Y142483D01*
X103833Y142400D01*
X103625Y142192D01*
X103500Y141817D01*
X103542Y141442D01*
X103708Y141067D01*
G01X106000Y145250D02*
X103500D01*
X105292Y143708D01*
Y145792D01*
G01X89317Y194800D02*
Y197300D01*
X90317D01*
X90650Y197175D01*
X90900Y196883D01*
X90983Y196550D01*
X90900Y196217D01*
X90692Y195967D01*
X90317Y195842D01*
X89317D01*
G01X94083Y194800D02*
X92417D01*
Y197300D01*
X94083D01*
G01X93417Y196092D02*
X92417D01*
G01X96683Y196133D02*
X96850Y196258D01*
X96975Y196467D01*
X97058Y196758D01*
X96975Y197008D01*
X96808Y197175D01*
X96517Y197300D01*
X95392D01*
Y194800D01*
X96767D01*
X97058Y194967D01*
X97225Y195217D01*
X97308Y195508D01*
X97225Y195800D01*
X96975Y196050D01*
X96683Y196133D01*
X95392D01*
G01X101508Y194800D02*
X102550Y197300D01*
X103592Y194800D01*
G01X103217Y195675D02*
X101883D01*
G01X105650Y197300D02*
Y194800D01*
G01X104692Y197300D02*
X106608D01*
G01X108750D02*
Y194800D01*
G01X107792Y197300D02*
X109708D01*
G01X110892Y194800D02*
Y197300D01*
X112808Y194800D01*
Y197300D01*
G01X114950Y194800D02*
Y197300D01*
X114450Y196800D01*
G01Y194800D02*
X115450D01*
G01X118550D02*
Y197300D01*
X117008Y195508D01*
X119092D01*
G01X63467Y202500D02*
Y200000D01*
X65133D01*
G01X68233D02*
X66567D01*
Y202500D01*
X68233D01*
G01X67567Y201292D02*
X66567D01*
G01X69583Y200000D02*
Y202500D01*
X70417D01*
X70750Y202375D01*
X71000Y202208D01*
X71208Y201958D01*
X71375Y201667D01*
X71417Y201250D01*
X71375Y200833D01*
X71208Y200542D01*
X71000Y200292D01*
X70750Y200125D01*
X70417Y200000D01*
X69583D01*
G01X73600D02*
Y202500D01*
X73100Y202000D01*
G01Y200000D02*
X74100D01*
G01X77200D02*
Y202500D01*
X75658Y200708D01*
X77742D01*
G01X67135Y204468D02*
Y212068D01*
X78535D01*
Y204468D01*
X67135D01*
G01X78217Y267292D02*
X77967Y267417D01*
X77675Y267500D01*
X77342D01*
X76967Y267375D01*
X76675Y267167D01*
X76467Y266917D01*
X76300Y266500D01*
X76258Y266125D01*
X76342Y265750D01*
X76467Y265500D01*
X76717Y265250D01*
X77008Y265083D01*
X77300Y265000D01*
X77592D01*
X77883Y265083D01*
X78133Y265208D01*
X78342Y265375D01*
G01X79692Y265292D02*
X79983Y265083D01*
X80317Y265000D01*
X80650Y265083D01*
X80942Y265333D01*
X81150Y265708D01*
X81233Y266083D01*
Y266542D01*
X81150Y266917D01*
X80942Y267250D01*
X80692Y267417D01*
X80400Y267500D01*
X80067Y267417D01*
X79817Y267250D01*
X79650Y267000D01*
X79567Y266667D01*
X79650Y266375D01*
X79858Y266083D01*
X80108Y265917D01*
X80400Y265875D01*
X80733Y265958D01*
X80983Y266167D01*
X81233Y266542D01*
G01X82583Y265375D02*
X82833Y265167D01*
X83125Y265042D01*
X83500Y265000D01*
X83875Y265083D01*
X84167Y265250D01*
X84375Y265542D01*
X84417Y265875D01*
X84333Y266208D01*
X84125Y266417D01*
X83833Y266583D01*
X83542Y266625D01*
X83250Y266583D01*
X82875Y266417D01*
X83000Y267500D01*
X84125D01*
G01X85683Y265500D02*
X85933Y265208D01*
X86267Y265042D01*
X86642Y265000D01*
X86975Y265042D01*
X87308Y265250D01*
X87517Y265500D01*
X87558Y265750D01*
X87475Y266042D01*
X87183Y266250D01*
X86892Y266333D01*
X86517D01*
G01X86892D02*
X87142Y266458D01*
X87350Y266667D01*
X87433Y266917D01*
X87350Y267167D01*
X87142Y267375D01*
X86767Y267500D01*
X86392Y267458D01*
X86017Y267292D01*
G01X88908Y267083D02*
X89158Y267333D01*
X89450Y267458D01*
X89783Y267500D01*
X90200Y267417D01*
X90492Y267208D01*
X90575Y266958D01*
X90533Y266708D01*
X90367Y266500D01*
X89533Y266083D01*
X89158Y265792D01*
X88908Y265375D01*
X88825Y265000D01*
X90575D01*
G01X69000Y215850D02*
X68958Y215517D01*
X68792Y215225D01*
X68542Y214975D01*
X68250Y214808D01*
X67917Y214725D01*
X67583D01*
X67250Y214808D01*
X66958Y214975D01*
X66708Y215225D01*
X66542Y215517D01*
X66500Y215850D01*
X66542Y216183D01*
X66708Y216475D01*
X66958Y216725D01*
X67250Y216892D01*
X67583Y216975D01*
X67917D01*
X68250Y216892D01*
X68542Y216725D01*
X68792Y216475D01*
X68958Y216183D01*
X69000Y215850D01*
G01X68333Y216183D02*
X69000Y216683D01*
G01Y218950D02*
X66500D01*
X67000Y218450D01*
G01X69000D02*
Y219450D01*
G01X66500Y222050D02*
X66583Y221717D01*
X66792Y221467D01*
X67042Y221300D01*
X67375Y221175D01*
X67750Y221133D01*
X68125Y221175D01*
X68458Y221300D01*
X68708Y221467D01*
X68917Y221717D01*
X69000Y222050D01*
X68917Y222383D01*
X68708Y222633D01*
X68458Y222800D01*
X68125Y222925D01*
X67750Y222967D01*
X67375Y222925D01*
X67042Y222800D01*
X66792Y222633D01*
X66583Y222383D01*
X66500Y222050D01*
G01Y225150D02*
X66583Y224817D01*
X66792Y224567D01*
X67042Y224400D01*
X67375Y224275D01*
X67750Y224233D01*
X68125Y224275D01*
X68458Y224400D01*
X68708Y224567D01*
X68917Y224817D01*
X69000Y225150D01*
X68917Y225483D01*
X68708Y225733D01*
X68458Y225900D01*
X68125Y226025D01*
X67750Y226067D01*
X67375Y226025D01*
X67042Y225900D01*
X66792Y225733D01*
X66583Y225483D01*
X66500Y225150D01*
G01X69958Y213984D02*
X83958D01*
G01X69958Y226984D02*
Y213984D01*
G01X83958Y226984D02*
X69958D01*
G01X83958Y213984D02*
Y226984D01*
G01X57400Y250000D02*
X57067Y250042D01*
X56775Y250208D01*
X56525Y250458D01*
X56358Y250750D01*
X56275Y251083D01*
Y251417D01*
X56358Y251750D01*
X56525Y252042D01*
X56775Y252292D01*
X57067Y252458D01*
X57400Y252500D01*
X57733Y252458D01*
X58025Y252292D01*
X58275Y252042D01*
X58442Y251750D01*
X58525Y251417D01*
Y251083D01*
X58442Y250750D01*
X58275Y250458D01*
X58025Y250208D01*
X57733Y250042D01*
X57400Y250000D01*
G01X57733Y250667D02*
X58233Y250000D01*
G01X59792Y250292D02*
X60083Y250083D01*
X60417Y250000D01*
X60750Y250083D01*
X61042Y250333D01*
X61250Y250708D01*
X61333Y251083D01*
Y251542D01*
X61250Y251917D01*
X61042Y252250D01*
X60792Y252417D01*
X60500Y252500D01*
X60167Y252417D01*
X59917Y252250D01*
X59750Y252000D01*
X59667Y251667D01*
X59750Y251375D01*
X59958Y251083D01*
X60208Y250917D01*
X60500Y250875D01*
X60833Y250958D01*
X61083Y251167D01*
X61333Y251542D01*
G01X63600Y250000D02*
X63892Y250042D01*
X64225Y250167D01*
X64433Y250375D01*
X64517Y250667D01*
X64433Y250958D01*
X64183Y251208D01*
X63808Y251333D01*
X63392D01*
X63142Y251417D01*
X62933Y251625D01*
X62850Y251917D01*
X62975Y252208D01*
X63267Y252417D01*
X63600Y252500D01*
X63933Y252417D01*
X64225Y252208D01*
X64350Y251917D01*
X64267Y251625D01*
X64058Y251417D01*
X63808Y251333D01*
X63392D01*
X63017Y251208D01*
X62767Y250958D01*
X62683Y250667D01*
X62767Y250375D01*
X62975Y250167D01*
X63308Y250042D01*
X63600Y250000D01*
G01X57000Y248465D02*
Y234465D01*
G01X70000Y248465D02*
X57000D01*
G01X70000Y234465D02*
Y248465D01*
G01X57000Y234465D02*
X70000D01*
G01X109834Y220400D02*
X109792Y220067D01*
X109626Y219775D01*
X109376Y219525D01*
X109084Y219358D01*
X108751Y219275D01*
X108417D01*
X108084Y219358D01*
X107792Y219525D01*
X107542Y219775D01*
X107376Y220067D01*
X107334Y220400D01*
X107376Y220733D01*
X107542Y221025D01*
X107792Y221275D01*
X108084Y221442D01*
X108417Y221525D01*
X108751D01*
X109084Y221442D01*
X109376Y221275D01*
X109626Y221025D01*
X109792Y220733D01*
X109834Y220400D01*
G01X109167Y220733D02*
X109834Y221233D01*
G01X109542Y222792D02*
X109751Y223083D01*
X109834Y223417D01*
X109751Y223750D01*
X109501Y224042D01*
X109126Y224250D01*
X108751Y224333D01*
X108292D01*
X107917Y224250D01*
X107584Y224042D01*
X107417Y223792D01*
X107334Y223500D01*
X107417Y223167D01*
X107584Y222917D01*
X107834Y222750D01*
X108167Y222667D01*
X108459Y222750D01*
X108751Y222958D01*
X108917Y223208D01*
X108959Y223500D01*
X108876Y223833D01*
X108667Y224083D01*
X108292Y224333D01*
G01X109542Y225892D02*
X109751Y226183D01*
X109834Y226517D01*
X109751Y226850D01*
X109501Y227142D01*
X109126Y227350D01*
X108751Y227433D01*
X108292D01*
X107917Y227350D01*
X107584Y227142D01*
X107417Y226892D01*
X107334Y226600D01*
X107417Y226267D01*
X107584Y226017D01*
X107834Y225850D01*
X108167Y225767D01*
X108459Y225850D01*
X108751Y226058D01*
X108917Y226308D01*
X108959Y226600D01*
X108876Y226933D01*
X108667Y227183D01*
X108292Y227433D01*
G01X91000Y217465D02*
X105000D01*
G01X91000Y230465D02*
Y217465D01*
G01X105000Y230465D02*
X91000D01*
G01X105000Y217465D02*
Y230465D01*
G01X101917Y208200D02*
Y210700D01*
X102958D01*
X103292Y210575D01*
X103500Y210408D01*
X103583Y210075D01*
X103500Y209742D01*
X103250Y209533D01*
X102958Y209408D01*
X101917D01*
G01X102958D02*
X103583Y208200D01*
G01X105142Y208492D02*
X105433Y208283D01*
X105767Y208200D01*
X106100Y208283D01*
X106392Y208533D01*
X106600Y208908D01*
X106683Y209283D01*
Y209742D01*
X106600Y210117D01*
X106392Y210450D01*
X106142Y210617D01*
X105850Y210700D01*
X105517Y210617D01*
X105267Y210450D01*
X105100Y210200D01*
X105017Y209867D01*
X105100Y209575D01*
X105308Y209283D01*
X105558Y209117D01*
X105850Y209075D01*
X106183Y209158D01*
X106433Y209367D01*
X106683Y209742D01*
G01X109450Y208200D02*
Y210700D01*
X107908Y208908D01*
X109992D01*
G01X111133Y208575D02*
X111383Y208367D01*
X111675Y208242D01*
X112050Y208200D01*
X112425Y208283D01*
X112717Y208450D01*
X112925Y208742D01*
X112967Y209075D01*
X112883Y209408D01*
X112675Y209617D01*
X112383Y209783D01*
X112092Y209825D01*
X111800Y209783D01*
X111425Y209617D01*
X111550Y210700D01*
X112675D01*
G01X114358Y209242D02*
X114650Y209533D01*
X114900Y209700D01*
X115233Y209783D01*
X115525Y209700D01*
X115733Y209533D01*
X115900Y209283D01*
X115942Y208992D01*
X115900Y208742D01*
X115733Y208492D01*
X115483Y208283D01*
X115192Y208200D01*
X114858Y208283D01*
X114567Y208533D01*
X114400Y208908D01*
X114358Y209325D01*
X114442Y209867D01*
X114567Y210158D01*
X114775Y210450D01*
X115067Y210658D01*
X115358Y210700D01*
X115650Y210617D01*
X115858Y210408D01*
G01X98200Y208000D02*
Y212000D01*
X90800D01*
G01X82700Y251465D02*
Y255465D01*
X75300D01*
G01X55300Y230267D02*
X52800D01*
Y231308D01*
X52925Y231642D01*
X53092Y231850D01*
X53425Y231933D01*
X53758Y231850D01*
X53967Y231600D01*
X54092Y231308D01*
Y230267D01*
G01Y231308D02*
X55300Y231933D01*
G01X55008Y233492D02*
X55217Y233783D01*
X55300Y234117D01*
X55217Y234450D01*
X54967Y234742D01*
X54592Y234950D01*
X54217Y235033D01*
X53758D01*
X53383Y234950D01*
X53050Y234742D01*
X52883Y234492D01*
X52800Y234200D01*
X52883Y233867D01*
X53050Y233617D01*
X53300Y233450D01*
X53633Y233367D01*
X53925Y233450D01*
X54217Y233658D01*
X54383Y233908D01*
X54425Y234200D01*
X54342Y234533D01*
X54133Y234783D01*
X53758Y235033D01*
G01X55300Y237300D02*
X55258Y237592D01*
X55133Y237925D01*
X54925Y238133D01*
X54633Y238217D01*
X54342Y238133D01*
X54092Y237883D01*
X53967Y237508D01*
Y237092D01*
X53883Y236842D01*
X53675Y236633D01*
X53383Y236550D01*
X53092Y236675D01*
X52883Y236967D01*
X52800Y237300D01*
X52883Y237633D01*
X53092Y237925D01*
X53383Y238050D01*
X53675Y237967D01*
X53883Y237758D01*
X53967Y237508D01*
Y237092D01*
X54092Y236717D01*
X54342Y236467D01*
X54633Y236383D01*
X54925Y236467D01*
X55133Y236675D01*
X55258Y237008D01*
X55300Y237300D01*
G01Y240317D02*
X54758Y240400D01*
X54300Y240525D01*
X53883Y240692D01*
X53425Y240900D01*
X52800Y241233D01*
Y239567D01*
G01X55300Y244000D02*
X52800D01*
X54592Y242458D01*
Y244542D01*
G01X85589Y229015D02*
X89589D01*
Y236415D01*
G01X47100Y230067D02*
X44600D01*
Y231108D01*
X44725Y231442D01*
X44892Y231650D01*
X45225Y231733D01*
X45558Y231650D01*
X45767Y231400D01*
X45892Y231108D01*
Y230067D01*
G01Y231108D02*
X47100Y231733D01*
G01X46808Y233292D02*
X47017Y233583D01*
X47100Y233917D01*
X47017Y234250D01*
X46767Y234542D01*
X46392Y234750D01*
X46017Y234833D01*
X45558D01*
X45183Y234750D01*
X44850Y234542D01*
X44683Y234292D01*
X44600Y234000D01*
X44683Y233667D01*
X44850Y233417D01*
X45100Y233250D01*
X45433Y233167D01*
X45725Y233250D01*
X46017Y233458D01*
X46183Y233708D01*
X46225Y234000D01*
X46142Y234333D01*
X45933Y234583D01*
X45558Y234833D01*
G01X47100Y237100D02*
X47058Y237392D01*
X46933Y237725D01*
X46725Y237933D01*
X46433Y238017D01*
X46142Y237933D01*
X45892Y237683D01*
X45767Y237308D01*
Y236892D01*
X45683Y236642D01*
X45475Y236433D01*
X45183Y236350D01*
X44892Y236475D01*
X44683Y236767D01*
X44600Y237100D01*
X44683Y237433D01*
X44892Y237725D01*
X45183Y237850D01*
X45475Y237767D01*
X45683Y237558D01*
X45767Y237308D01*
Y236892D01*
X45892Y236517D01*
X46142Y236267D01*
X46433Y236183D01*
X46725Y236267D01*
X46933Y236475D01*
X47058Y236808D01*
X47100Y237100D01*
G01Y240117D02*
X46558Y240200D01*
X46100Y240325D01*
X45683Y240492D01*
X45225Y240700D01*
X44600Y241033D01*
Y239367D01*
G01X46725Y242383D02*
X46933Y242633D01*
X47058Y242925D01*
X47100Y243300D01*
X47017Y243675D01*
X46850Y243967D01*
X46558Y244175D01*
X46225Y244217D01*
X45892Y244133D01*
X45683Y243925D01*
X45517Y243633D01*
X45475Y243342D01*
X45517Y243050D01*
X45683Y242675D01*
X44600Y242800D01*
Y243925D01*
G01X74750Y228872D02*
X78750D01*
Y236272D01*
G01X101875Y212533D02*
X102208Y212325D01*
X102583Y212200D01*
X102917D01*
X103250Y212325D01*
X103500Y212533D01*
X103625Y212825D01*
X103542Y213117D01*
X103333Y213367D01*
X102958Y213533D01*
X102458Y213617D01*
X102167Y213783D01*
X102042Y214075D01*
X102125Y214367D01*
X102333Y214575D01*
X102625Y214700D01*
X102917D01*
X103208Y214617D01*
X103458Y214408D01*
G01X105017Y212200D02*
Y214700D01*
X106058D01*
X106392Y214575D01*
X106600Y214408D01*
X106683Y214075D01*
X106600Y213742D01*
X106350Y213533D01*
X106058Y213408D01*
X105017D01*
G01X106058D02*
X106683Y212200D01*
G01X108950D02*
Y214700D01*
X108450Y214200D01*
G01Y212200D02*
X109450D01*
G01X112050D02*
Y214700D01*
X111550Y214200D01*
G01Y212200D02*
X112550D01*
G01X115650D02*
Y214700D01*
X114108Y212908D01*
X116192D01*
G01X117542Y212492D02*
X117833Y212283D01*
X118167Y212200D01*
X118500Y212283D01*
X118792Y212533D01*
X119000Y212908D01*
X119083Y213283D01*
Y213742D01*
X119000Y214117D01*
X118792Y214450D01*
X118542Y214617D01*
X118250Y214700D01*
X117917Y214617D01*
X117667Y214450D01*
X117500Y214200D01*
X117417Y213867D01*
X117500Y213575D01*
X117708Y213283D01*
X117958Y213117D01*
X118250Y213075D01*
X118583Y213158D01*
X118833Y213367D01*
X119083Y213742D01*
G01X98200Y212465D02*
Y216465D01*
X90800D01*
G01X73375Y261333D02*
X73708Y261125D01*
X74083Y261000D01*
X74417D01*
X74750Y261125D01*
X75000Y261333D01*
X75125Y261625D01*
X75042Y261917D01*
X74833Y262167D01*
X74458Y262333D01*
X73958Y262417D01*
X73667Y262583D01*
X73542Y262875D01*
X73625Y263167D01*
X73833Y263375D01*
X74125Y263500D01*
X74417D01*
X74708Y263417D01*
X74958Y263208D01*
G01X76517Y261000D02*
Y263500D01*
X77558D01*
X77892Y263375D01*
X78100Y263208D01*
X78183Y262875D01*
X78100Y262542D01*
X77850Y262333D01*
X77558Y262208D01*
X76517D01*
G01X77558D02*
X78183Y261000D01*
G01X80450D02*
Y263500D01*
X79950Y263000D01*
G01Y261000D02*
X80950D01*
G01X83550D02*
Y263500D01*
X83050Y263000D01*
G01Y261000D02*
X84050D01*
G01X85733Y261375D02*
X85983Y261167D01*
X86275Y261042D01*
X86650Y261000D01*
X87025Y261083D01*
X87317Y261250D01*
X87525Y261542D01*
X87567Y261875D01*
X87483Y262208D01*
X87275Y262417D01*
X86983Y262583D01*
X86692Y262625D01*
X86400Y262583D01*
X86025Y262417D01*
X86150Y263500D01*
X87275D01*
G01X89750D02*
X89417Y263417D01*
X89167Y263208D01*
X89000Y262958D01*
X88875Y262625D01*
X88833Y262250D01*
X88875Y261875D01*
X89000Y261542D01*
X89167Y261292D01*
X89417Y261083D01*
X89750Y261000D01*
X90083Y261083D01*
X90333Y261292D01*
X90500Y261542D01*
X90625Y261875D01*
X90667Y262250D01*
X90625Y262625D01*
X90500Y262958D01*
X90333Y263208D01*
X90083Y263417D01*
X89750Y263500D01*
G01X83950Y237715D02*
Y241715D01*
X76550D01*
G01X101917Y200200D02*
Y202700D01*
X102958D01*
X103292Y202575D01*
X103500Y202408D01*
X103583Y202075D01*
X103500Y201742D01*
X103250Y201533D01*
X102958Y201408D01*
X101917D01*
G01X102958D02*
X103583Y200200D01*
G01X105142Y200492D02*
X105433Y200283D01*
X105767Y200200D01*
X106100Y200283D01*
X106392Y200533D01*
X106600Y200908D01*
X106683Y201283D01*
Y201742D01*
X106600Y202117D01*
X106392Y202450D01*
X106142Y202617D01*
X105850Y202700D01*
X105517Y202617D01*
X105267Y202450D01*
X105100Y202200D01*
X105017Y201867D01*
X105100Y201575D01*
X105308Y201283D01*
X105558Y201117D01*
X105850Y201075D01*
X106183Y201158D01*
X106433Y201367D01*
X106683Y201742D01*
G01X108242Y200492D02*
X108533Y200283D01*
X108867Y200200D01*
X109200Y200283D01*
X109492Y200533D01*
X109700Y200908D01*
X109783Y201283D01*
Y201742D01*
X109700Y202117D01*
X109492Y202450D01*
X109242Y202617D01*
X108950Y202700D01*
X108617Y202617D01*
X108367Y202450D01*
X108200Y202200D01*
X108117Y201867D01*
X108200Y201575D01*
X108408Y201283D01*
X108658Y201117D01*
X108950Y201075D01*
X109283Y201158D01*
X109533Y201367D01*
X109783Y201742D01*
G01X112050Y202700D02*
X111717Y202617D01*
X111467Y202408D01*
X111300Y202158D01*
X111175Y201825D01*
X111133Y201450D01*
X111175Y201075D01*
X111300Y200742D01*
X111467Y200492D01*
X111717Y200283D01*
X112050Y200200D01*
X112383Y200283D01*
X112633Y200492D01*
X112800Y200742D01*
X112925Y201075D01*
X112967Y201450D01*
X112925Y201825D01*
X112800Y202158D01*
X112633Y202408D01*
X112383Y202617D01*
X112050Y202700D01*
G01X114358Y201242D02*
X114650Y201533D01*
X114900Y201700D01*
X115233Y201783D01*
X115525Y201700D01*
X115733Y201533D01*
X115900Y201283D01*
X115942Y200992D01*
X115900Y200742D01*
X115733Y200492D01*
X115483Y200283D01*
X115192Y200200D01*
X114858Y200283D01*
X114567Y200533D01*
X114400Y200908D01*
X114358Y201325D01*
X114442Y201867D01*
X114567Y202158D01*
X114775Y202450D01*
X115067Y202658D01*
X115358Y202700D01*
X115650Y202617D01*
X115858Y202408D01*
G01X98200Y199000D02*
Y203000D01*
X90800D01*
G01X51300Y230267D02*
X48800D01*
Y231308D01*
X48925Y231642D01*
X49092Y231850D01*
X49425Y231933D01*
X49758Y231850D01*
X49967Y231600D01*
X50092Y231308D01*
Y230267D01*
G01Y231308D02*
X51300Y231933D01*
G01X51008Y233492D02*
X51217Y233783D01*
X51300Y234117D01*
X51217Y234450D01*
X50967Y234742D01*
X50592Y234950D01*
X50217Y235033D01*
X49758D01*
X49383Y234950D01*
X49050Y234742D01*
X48883Y234492D01*
X48800Y234200D01*
X48883Y233867D01*
X49050Y233617D01*
X49300Y233450D01*
X49633Y233367D01*
X49925Y233450D01*
X50217Y233658D01*
X50383Y233908D01*
X50425Y234200D01*
X50342Y234533D01*
X50133Y234783D01*
X49758Y235033D01*
G01X51008Y236592D02*
X51217Y236883D01*
X51300Y237217D01*
X51217Y237550D01*
X50967Y237842D01*
X50592Y238050D01*
X50217Y238133D01*
X49758D01*
X49383Y238050D01*
X49050Y237842D01*
X48883Y237592D01*
X48800Y237300D01*
X48883Y236967D01*
X49050Y236717D01*
X49300Y236550D01*
X49633Y236467D01*
X49925Y236550D01*
X50217Y236758D01*
X50383Y237008D01*
X50425Y237300D01*
X50342Y237633D01*
X50133Y237883D01*
X49758Y238133D01*
G01X49217Y239608D02*
X48967Y239858D01*
X48842Y240150D01*
X48800Y240483D01*
X48883Y240900D01*
X49092Y241192D01*
X49342Y241275D01*
X49592Y241233D01*
X49800Y241067D01*
X50217Y240233D01*
X50508Y239858D01*
X50925Y239608D01*
X51300Y239525D01*
Y241275D01*
G01X50258Y242708D02*
X49967Y243000D01*
X49800Y243250D01*
X49717Y243583D01*
X49800Y243875D01*
X49967Y244083D01*
X50217Y244250D01*
X50508Y244292D01*
X50758Y244250D01*
X51008Y244083D01*
X51217Y243833D01*
X51300Y243542D01*
X51217Y243208D01*
X50967Y242917D01*
X50592Y242750D01*
X50175Y242708D01*
X49633Y242792D01*
X49342Y242917D01*
X49050Y243125D01*
X48842Y243417D01*
X48800Y243708D01*
X48883Y244000D01*
X49092Y244208D01*
G01X81589Y229015D02*
X85589D01*
Y236415D01*
G01X53834Y202967D02*
X51334D01*
Y204008D01*
X51459Y204342D01*
X51626Y204550D01*
X51959Y204633D01*
X52292Y204550D01*
X52501Y204300D01*
X52626Y204008D01*
Y202967D01*
G01Y204008D02*
X53834Y204633D01*
G01X53542Y206192D02*
X53751Y206483D01*
X53834Y206817D01*
X53751Y207150D01*
X53501Y207442D01*
X53126Y207650D01*
X52751Y207733D01*
X52292D01*
X51917Y207650D01*
X51584Y207442D01*
X51417Y207192D01*
X51334Y206900D01*
X51417Y206567D01*
X51584Y206317D01*
X51834Y206150D01*
X52167Y206067D01*
X52459Y206150D01*
X52751Y206358D01*
X52917Y206608D01*
X52959Y206900D01*
X52876Y207233D01*
X52667Y207483D01*
X52292Y207733D01*
G01X53542Y209292D02*
X53751Y209583D01*
X53834Y209917D01*
X53751Y210250D01*
X53501Y210542D01*
X53126Y210750D01*
X52751Y210833D01*
X52292D01*
X51917Y210750D01*
X51584Y210542D01*
X51417Y210292D01*
X51334Y210000D01*
X51417Y209667D01*
X51584Y209417D01*
X51834Y209250D01*
X52167Y209167D01*
X52459Y209250D01*
X52751Y209458D01*
X52917Y209708D01*
X52959Y210000D01*
X52876Y210333D01*
X52667Y210583D01*
X52292Y210833D01*
G01X53459Y212183D02*
X53667Y212433D01*
X53792Y212725D01*
X53834Y213100D01*
X53751Y213475D01*
X53584Y213767D01*
X53292Y213975D01*
X52959Y214017D01*
X52626Y213933D01*
X52417Y213725D01*
X52251Y213433D01*
X52209Y213142D01*
X52251Y212850D01*
X52417Y212475D01*
X51334Y212600D01*
Y213725D01*
G01X53459Y215283D02*
X53667Y215533D01*
X53792Y215825D01*
X53834Y216200D01*
X53751Y216575D01*
X53584Y216867D01*
X53292Y217075D01*
X52959Y217117D01*
X52626Y217033D01*
X52417Y216825D01*
X52251Y216533D01*
X52209Y216242D01*
X52251Y215950D01*
X52417Y215575D01*
X51334Y215700D01*
Y216825D01*
G01X61903Y207195D02*
X65903D01*
Y214595D01*
G01X49334Y199967D02*
X46834D01*
Y201008D01*
X46959Y201342D01*
X47126Y201550D01*
X47459Y201633D01*
X47792Y201550D01*
X48001Y201300D01*
X48126Y201008D01*
Y199967D01*
G01Y201008D02*
X49334Y201633D01*
G01X49042Y203192D02*
X49251Y203483D01*
X49334Y203817D01*
X49251Y204150D01*
X49001Y204442D01*
X48626Y204650D01*
X48251Y204733D01*
X47792D01*
X47417Y204650D01*
X47084Y204442D01*
X46917Y204192D01*
X46834Y203900D01*
X46917Y203567D01*
X47084Y203317D01*
X47334Y203150D01*
X47667Y203067D01*
X47959Y203150D01*
X48251Y203358D01*
X48417Y203608D01*
X48459Y203900D01*
X48376Y204233D01*
X48167Y204483D01*
X47792Y204733D01*
G01X49042Y206292D02*
X49251Y206583D01*
X49334Y206917D01*
X49251Y207250D01*
X49001Y207542D01*
X48626Y207750D01*
X48251Y207833D01*
X47792D01*
X47417Y207750D01*
X47084Y207542D01*
X46917Y207292D01*
X46834Y207000D01*
X46917Y206667D01*
X47084Y206417D01*
X47334Y206250D01*
X47667Y206167D01*
X47959Y206250D01*
X48251Y206458D01*
X48417Y206708D01*
X48459Y207000D01*
X48376Y207333D01*
X48167Y207583D01*
X47792Y207833D01*
G01X48959Y209183D02*
X49167Y209433D01*
X49292Y209725D01*
X49334Y210100D01*
X49251Y210475D01*
X49084Y210767D01*
X48792Y210975D01*
X48459Y211017D01*
X48126Y210933D01*
X47917Y210725D01*
X47751Y210433D01*
X47709Y210142D01*
X47751Y209850D01*
X47917Y209475D01*
X46834Y209600D01*
Y210725D01*
G01X48292Y212408D02*
X48001Y212700D01*
X47834Y212950D01*
X47751Y213283D01*
X47834Y213575D01*
X48001Y213783D01*
X48251Y213950D01*
X48542Y213992D01*
X48792Y213950D01*
X49042Y213783D01*
X49251Y213533D01*
X49334Y213242D01*
X49251Y212908D01*
X49001Y212617D01*
X48626Y212450D01*
X48209Y212408D01*
X47667Y212492D01*
X47376Y212617D01*
X47084Y212825D01*
X46876Y213117D01*
X46834Y213408D01*
X46917Y213700D01*
X47126Y213908D01*
G01X61859Y210371D02*
X57859D01*
Y202971D01*
G01X101917Y204200D02*
Y206700D01*
X102958D01*
X103292Y206575D01*
X103500Y206408D01*
X103583Y206075D01*
X103500Y205742D01*
X103250Y205533D01*
X102958Y205408D01*
X101917D01*
G01X102958D02*
X103583Y204200D01*
G01X105142Y204492D02*
X105433Y204283D01*
X105767Y204200D01*
X106100Y204283D01*
X106392Y204533D01*
X106600Y204908D01*
X106683Y205283D01*
Y205742D01*
X106600Y206117D01*
X106392Y206450D01*
X106142Y206617D01*
X105850Y206700D01*
X105517Y206617D01*
X105267Y206450D01*
X105100Y206200D01*
X105017Y205867D01*
X105100Y205575D01*
X105308Y205283D01*
X105558Y205117D01*
X105850Y205075D01*
X106183Y205158D01*
X106433Y205367D01*
X106683Y205742D01*
G01X109450Y204200D02*
Y206700D01*
X107908Y204908D01*
X109992D01*
G01X111133Y204575D02*
X111383Y204367D01*
X111675Y204242D01*
X112050Y204200D01*
X112425Y204283D01*
X112717Y204450D01*
X112925Y204742D01*
X112967Y205075D01*
X112883Y205408D01*
X112675Y205617D01*
X112383Y205783D01*
X112092Y205825D01*
X111800Y205783D01*
X111425Y205617D01*
X111550Y206700D01*
X112675D01*
G01X115067Y204200D02*
X115150Y204742D01*
X115275Y205200D01*
X115442Y205617D01*
X115650Y206075D01*
X115983Y206700D01*
X114317D01*
G01X98200Y203500D02*
Y207500D01*
X90800D01*
G01X90933Y254500D02*
Y252708D01*
X91100Y252333D01*
X91433Y252083D01*
X91850Y252000D01*
X92267Y252083D01*
X92600Y252333D01*
X92767Y252708D01*
Y254500D01*
G01X94158Y254083D02*
X94408Y254333D01*
X94700Y254458D01*
X95033Y254500D01*
X95450Y254417D01*
X95742Y254208D01*
X95825Y253958D01*
X95783Y253708D01*
X95617Y253500D01*
X94783Y253083D01*
X94408Y252792D01*
X94158Y252375D01*
X94075Y252000D01*
X95825D01*
G01X98050D02*
Y254500D01*
X97550Y254000D01*
G01Y252000D02*
X98550D01*
G01X101150D02*
Y254500D01*
X100650Y254000D01*
G01Y252000D02*
X101650D01*
G01X87781Y249423D02*
X101181D01*
G01X87781Y239423D02*
Y249423D01*
G01X101181Y239423D02*
X87781D01*
G01X101181Y249423D02*
Y239423D01*
G01X96727Y323057D02*
X96602Y322807D01*
X96519Y322515D01*
Y322182D01*
X96644Y321807D01*
X96852Y321515D01*
X97102Y321307D01*
X97519Y321140D01*
X97894Y321098D01*
X98269Y321182D01*
X98519Y321307D01*
X98769Y321557D01*
X98936Y321848D01*
X99019Y322140D01*
Y322432D01*
X98936Y322723D01*
X98811Y322973D01*
X98644Y323182D01*
G01X98519Y324323D02*
X98811Y324573D01*
X98977Y324907D01*
X99019Y325282D01*
X98977Y325615D01*
X98769Y325948D01*
X98519Y326157D01*
X98269Y326198D01*
X97977Y326115D01*
X97769Y325823D01*
X97686Y325532D01*
Y325157D01*
G01Y325532D02*
X97561Y325782D01*
X97352Y325990D01*
X97102Y326073D01*
X96852Y325990D01*
X96644Y325782D01*
X96519Y325407D01*
X96561Y325032D01*
X96727Y324657D01*
G01X98727Y327632D02*
X98936Y327923D01*
X99019Y328257D01*
X98936Y328590D01*
X98686Y328882D01*
X98311Y329090D01*
X97936Y329173D01*
X97477D01*
X97102Y329090D01*
X96769Y328882D01*
X96602Y328632D01*
X96519Y328340D01*
X96602Y328007D01*
X96769Y327757D01*
X97019Y327590D01*
X97352Y327507D01*
X97644Y327590D01*
X97936Y327798D01*
X98102Y328048D01*
X98144Y328340D01*
X98061Y328673D01*
X97852Y328923D01*
X97477Y329173D01*
G01X99019Y331440D02*
X96519D01*
X97019Y330940D01*
G01X99019D02*
Y331940D01*
G01X89417Y334161D02*
Y336661D01*
X90458D01*
X90792Y336536D01*
X91000Y336369D01*
X91083Y336036D01*
X91000Y335703D01*
X90750Y335494D01*
X90458Y335369D01*
X89417D01*
G01X90458D02*
X91083Y334161D01*
G01X93350D02*
Y336661D01*
X92850Y336161D01*
G01Y334161D02*
X93850D01*
G01X96950D02*
Y336661D01*
X95408Y334869D01*
X97492D01*
G01X99467Y334161D02*
X99550Y334703D01*
X99675Y335161D01*
X99842Y335578D01*
X100050Y336036D01*
X100383Y336661D01*
X98717D01*
G01X90519Y321307D02*
X88019D01*
Y322348D01*
X88144Y322682D01*
X88311Y322890D01*
X88644Y322973D01*
X88977Y322890D01*
X89186Y322640D01*
X89311Y322348D01*
Y321307D01*
G01Y322348D02*
X90519Y322973D01*
G01X90144Y324323D02*
X90352Y324573D01*
X90477Y324865D01*
X90519Y325240D01*
X90436Y325615D01*
X90269Y325907D01*
X89977Y326115D01*
X89644Y326157D01*
X89311Y326073D01*
X89102Y325865D01*
X88936Y325573D01*
X88894Y325282D01*
X88936Y324990D01*
X89102Y324615D01*
X88019Y324740D01*
Y325865D01*
G01X89477Y327548D02*
X89186Y327840D01*
X89019Y328090D01*
X88936Y328423D01*
X89019Y328715D01*
X89186Y328923D01*
X89436Y329090D01*
X89727Y329132D01*
X89977Y329090D01*
X90227Y328923D01*
X90436Y328673D01*
X90519Y328382D01*
X90436Y328048D01*
X90186Y327757D01*
X89811Y327590D01*
X89394Y327548D01*
X88852Y327632D01*
X88561Y327757D01*
X88269Y327965D01*
X88061Y328257D01*
X88019Y328548D01*
X88102Y328840D01*
X88311Y329048D01*
G01X88019Y331440D02*
X88102Y331107D01*
X88311Y330857D01*
X88561Y330690D01*
X88894Y330565D01*
X89269Y330523D01*
X89644Y330565D01*
X89977Y330690D01*
X90227Y330857D01*
X90436Y331107D01*
X90519Y331440D01*
X90436Y331773D01*
X90227Y332023D01*
X89977Y332190D01*
X89644Y332315D01*
X89269Y332357D01*
X88894Y332315D01*
X88561Y332190D01*
X88311Y332023D01*
X88102Y331773D01*
X88019Y331440D01*
G01X95019Y321307D02*
X92519D01*
Y322348D01*
X92644Y322682D01*
X92811Y322890D01*
X93144Y322973D01*
X93477Y322890D01*
X93686Y322640D01*
X93811Y322348D01*
Y321307D01*
G01Y322348D02*
X95019Y322973D01*
G01X94644Y324323D02*
X94852Y324573D01*
X94977Y324865D01*
X95019Y325240D01*
X94936Y325615D01*
X94769Y325907D01*
X94477Y326115D01*
X94144Y326157D01*
X93811Y326073D01*
X93602Y325865D01*
X93436Y325573D01*
X93394Y325282D01*
X93436Y324990D01*
X93602Y324615D01*
X92519Y324740D01*
Y325865D01*
G01X95019Y328257D02*
X94477Y328340D01*
X94019Y328465D01*
X93602Y328632D01*
X93144Y328840D01*
X92519Y329173D01*
Y327507D01*
G01X94644Y330523D02*
X94852Y330773D01*
X94977Y331065D01*
X95019Y331440D01*
X94936Y331815D01*
X94769Y332107D01*
X94477Y332315D01*
X94144Y332357D01*
X93811Y332273D01*
X93602Y332065D01*
X93436Y331773D01*
X93394Y331482D01*
X93436Y331190D01*
X93602Y330815D01*
X92519Y330940D01*
Y332065D01*
G01X110667Y309375D02*
X110875Y309708D01*
X111000Y310083D01*
Y310417D01*
X110875Y310750D01*
X110667Y311000D01*
X110375Y311125D01*
X110083Y311042D01*
X109833Y310833D01*
X109667Y310458D01*
X109583Y309958D01*
X109417Y309667D01*
X109125Y309542D01*
X108833Y309625D01*
X108625Y309833D01*
X108500Y310125D01*
Y310417D01*
X108583Y310708D01*
X108792Y310958D01*
G01X111000Y312517D02*
X108500D01*
Y313558D01*
X108625Y313892D01*
X108792Y314100D01*
X109125Y314183D01*
X109458Y314100D01*
X109667Y313850D01*
X109792Y313558D01*
Y312517D01*
G01Y313558D02*
X111000Y314183D01*
G01Y316450D02*
X108500D01*
X109000Y315950D01*
G01X111000D02*
Y316950D01*
G01Y319550D02*
X108500D01*
X109000Y319050D01*
G01X111000D02*
Y320050D01*
G01X108500Y322650D02*
X108583Y322317D01*
X108792Y322067D01*
X109042Y321900D01*
X109375Y321775D01*
X109750Y321733D01*
X110125Y321775D01*
X110458Y321900D01*
X110708Y322067D01*
X110917Y322317D01*
X111000Y322650D01*
X110917Y322983D01*
X110708Y323233D01*
X110458Y323400D01*
X110125Y323525D01*
X109750Y323567D01*
X109375Y323525D01*
X109042Y323400D01*
X108792Y323233D01*
X108583Y322983D01*
X108500Y322650D01*
G01X110708Y325042D02*
X110917Y325333D01*
X111000Y325667D01*
X110917Y326000D01*
X110667Y326292D01*
X110292Y326500D01*
X109917Y326583D01*
X109458D01*
X109083Y326500D01*
X108750Y326292D01*
X108583Y326042D01*
X108500Y325750D01*
X108583Y325417D01*
X108750Y325167D01*
X109000Y325000D01*
X109333Y324917D01*
X109625Y325000D01*
X109917Y325208D01*
X110083Y325458D01*
X110125Y325750D01*
X110042Y326083D01*
X109833Y326333D01*
X109458Y326583D01*
G01X73967Y269000D02*
Y271500D01*
X75008D01*
X75342Y271375D01*
X75550Y271208D01*
X75633Y270875D01*
X75550Y270542D01*
X75300Y270333D01*
X75008Y270208D01*
X73967D01*
G01X75008D02*
X75633Y269000D01*
G01X77192Y269292D02*
X77483Y269083D01*
X77817Y269000D01*
X78150Y269083D01*
X78442Y269333D01*
X78650Y269708D01*
X78733Y270083D01*
Y270542D01*
X78650Y270917D01*
X78442Y271250D01*
X78192Y271417D01*
X77900Y271500D01*
X77567Y271417D01*
X77317Y271250D01*
X77150Y271000D01*
X77067Y270667D01*
X77150Y270375D01*
X77358Y270083D01*
X77608Y269917D01*
X77900Y269875D01*
X78233Y269958D01*
X78483Y270167D01*
X78733Y270542D01*
G01X81000Y269000D02*
X81292Y269042D01*
X81625Y269167D01*
X81833Y269375D01*
X81917Y269667D01*
X81833Y269958D01*
X81583Y270208D01*
X81208Y270333D01*
X80792D01*
X80542Y270417D01*
X80333Y270625D01*
X80250Y270917D01*
X80375Y271208D01*
X80667Y271417D01*
X81000Y271500D01*
X81333Y271417D01*
X81625Y271208D01*
X81750Y270917D01*
X81667Y270625D01*
X81458Y270417D01*
X81208Y270333D01*
X80792D01*
X80417Y270208D01*
X80167Y269958D01*
X80083Y269667D01*
X80167Y269375D01*
X80375Y269167D01*
X80708Y269042D01*
X81000Y269000D01*
G01X84017D02*
X84100Y269542D01*
X84225Y270000D01*
X84392Y270417D01*
X84600Y270875D01*
X84933Y271500D01*
X83267D01*
G01X86283Y269500D02*
X86533Y269208D01*
X86867Y269042D01*
X87242Y269000D01*
X87575Y269042D01*
X87908Y269250D01*
X88117Y269500D01*
X88158Y269750D01*
X88075Y270042D01*
X87783Y270250D01*
X87492Y270333D01*
X87117D01*
G01X87492D02*
X87742Y270458D01*
X87950Y270667D01*
X88033Y270917D01*
X87950Y271167D01*
X87742Y271375D01*
X87367Y271500D01*
X86992Y271458D01*
X86617Y271292D01*
G01X111417Y410500D02*
Y413000D01*
X112417D01*
X112750Y412875D01*
X113000Y412583D01*
X113083Y412250D01*
X113000Y411917D01*
X112792Y411667D01*
X112417Y411542D01*
X111417D01*
G01X116267Y412792D02*
X116017Y412917D01*
X115725Y413000D01*
X115392D01*
X115017Y412875D01*
X114725Y412667D01*
X114517Y412417D01*
X114350Y412000D01*
X114308Y411625D01*
X114392Y411250D01*
X114517Y411000D01*
X114767Y410750D01*
X115058Y410583D01*
X115350Y410500D01*
X115642D01*
X115933Y410583D01*
X116183Y410708D01*
X116392Y410875D01*
G01X118450Y410500D02*
Y413000D01*
X117950Y412500D01*
G01Y410500D02*
X118950D01*
G01X120758Y412583D02*
X121008Y412833D01*
X121300Y412958D01*
X121633Y413000D01*
X122050Y412917D01*
X122342Y412708D01*
X122425Y412458D01*
X122383Y412208D01*
X122217Y412000D01*
X121383Y411583D01*
X121008Y411292D01*
X120758Y410875D01*
X120675Y410500D01*
X122425D01*
G01X124650D02*
Y413000D01*
X124150Y412500D01*
G01Y410500D02*
X125150D01*
G01X126958Y412583D02*
X127208Y412833D01*
X127500Y412958D01*
X127833Y413000D01*
X128250Y412917D01*
X128542Y412708D01*
X128625Y412458D01*
X128583Y412208D01*
X128417Y412000D01*
X127583Y411583D01*
X127208Y411292D01*
X126958Y410875D01*
X126875Y410500D01*
X128625D01*
G01X79200Y350900D02*
X79158Y350567D01*
X78992Y350275D01*
X78742Y350025D01*
X78450Y349858D01*
X78117Y349775D01*
X77783D01*
X77450Y349858D01*
X77158Y350025D01*
X76908Y350275D01*
X76742Y350567D01*
X76700Y350900D01*
X76742Y351233D01*
X76908Y351525D01*
X77158Y351775D01*
X77450Y351942D01*
X77783Y352025D01*
X78117D01*
X78450Y351942D01*
X78742Y351775D01*
X78992Y351525D01*
X79158Y351233D01*
X79200Y350900D01*
G01X78533Y351233D02*
X79200Y351733D01*
G01Y354000D02*
X76700D01*
X77200Y353500D01*
G01X79200D02*
Y354500D01*
G01Y357017D02*
X78658Y357100D01*
X78200Y357225D01*
X77783Y357392D01*
X77325Y357600D01*
X76700Y357933D01*
Y356267D01*
G01X102200Y352000D02*
Y366000D01*
G01X89200Y352000D02*
X102200D01*
G01X89200Y366000D02*
Y352000D01*
G01X102200Y366000D02*
X89200D01*
G01X94400Y382000D02*
X94067Y382042D01*
X93775Y382208D01*
X93525Y382458D01*
X93358Y382750D01*
X93275Y383083D01*
Y383417D01*
X93358Y383750D01*
X93525Y384042D01*
X93775Y384292D01*
X94067Y384458D01*
X94400Y384500D01*
X94733Y384458D01*
X95025Y384292D01*
X95275Y384042D01*
X95442Y383750D01*
X95525Y383417D01*
Y383083D01*
X95442Y382750D01*
X95275Y382458D01*
X95025Y382208D01*
X94733Y382042D01*
X94400Y382000D01*
G01X94733Y382667D02*
X95233Y382000D01*
G01X97417D02*
X97500Y382542D01*
X97625Y383000D01*
X97792Y383417D01*
X98000Y383875D01*
X98333Y384500D01*
X96667D01*
G01X100600Y382000D02*
Y384500D01*
X100100Y384000D01*
G01Y382000D02*
X101100D01*
G01X111000Y380400D02*
X97000D01*
G01X111000Y367400D02*
Y380400D01*
G01X97000Y367400D02*
X111000D01*
G01X97000Y380400D02*
Y367400D01*
G01X101400Y347000D02*
Y351000D01*
X94000D01*
G01X93200Y346700D02*
X89200D01*
Y339300D01*
G01X93700D02*
X97700D01*
Y346700D01*
G01X77500Y363467D02*
X75000D01*
Y364508D01*
X75125Y364842D01*
X75292Y365050D01*
X75625Y365133D01*
X75958Y365050D01*
X76167Y364800D01*
X76292Y364508D01*
Y363467D01*
G01Y364508D02*
X77500Y365133D01*
G01X77208Y366692D02*
X77417Y366983D01*
X77500Y367317D01*
X77417Y367650D01*
X77167Y367942D01*
X76792Y368150D01*
X76417Y368233D01*
X75958D01*
X75583Y368150D01*
X75250Y367942D01*
X75083Y367692D01*
X75000Y367400D01*
X75083Y367067D01*
X75250Y366817D01*
X75500Y366650D01*
X75833Y366567D01*
X76125Y366650D01*
X76417Y366858D01*
X76583Y367108D01*
X76625Y367400D01*
X76542Y367733D01*
X76333Y367983D01*
X75958Y368233D01*
G01X77500Y370417D02*
X76958Y370500D01*
X76500Y370625D01*
X76083Y370792D01*
X75625Y371000D01*
X75000Y371333D01*
Y369667D01*
G01X77125Y372683D02*
X77333Y372933D01*
X77458Y373225D01*
X77500Y373600D01*
X77417Y373975D01*
X77250Y374267D01*
X76958Y374475D01*
X76625Y374517D01*
X76292Y374433D01*
X76083Y374225D01*
X75917Y373933D01*
X75875Y373642D01*
X75917Y373350D01*
X76083Y372975D01*
X75000Y373100D01*
Y374225D01*
G01Y376700D02*
X75083Y376367D01*
X75292Y376117D01*
X75542Y375950D01*
X75875Y375825D01*
X76250Y375783D01*
X76625Y375825D01*
X76958Y375950D01*
X77208Y376117D01*
X77417Y376367D01*
X77500Y376700D01*
X77417Y377033D01*
X77208Y377283D01*
X76958Y377450D01*
X76625Y377575D01*
X76250Y377617D01*
X75875Y377575D01*
X75542Y377450D01*
X75292Y377283D01*
X75083Y377033D01*
X75000Y376700D01*
G01X88000Y367300D02*
X92000D01*
Y374700D01*
G01X82000Y363467D02*
X79500D01*
Y364508D01*
X79625Y364842D01*
X79792Y365050D01*
X80125Y365133D01*
X80458Y365050D01*
X80667Y364800D01*
X80792Y364508D01*
Y363467D01*
G01Y364508D02*
X82000Y365133D01*
G01X81708Y366692D02*
X81917Y366983D01*
X82000Y367317D01*
X81917Y367650D01*
X81667Y367942D01*
X81292Y368150D01*
X80917Y368233D01*
X80458D01*
X80083Y368150D01*
X79750Y367942D01*
X79583Y367692D01*
X79500Y367400D01*
X79583Y367067D01*
X79750Y366817D01*
X80000Y366650D01*
X80333Y366567D01*
X80625Y366650D01*
X80917Y366858D01*
X81083Y367108D01*
X81125Y367400D01*
X81042Y367733D01*
X80833Y367983D01*
X80458Y368233D01*
G01X82000Y370417D02*
X81458Y370500D01*
X81000Y370625D01*
X80583Y370792D01*
X80125Y371000D01*
X79500Y371333D01*
Y369667D01*
G01X80958Y372808D02*
X80667Y373100D01*
X80500Y373350D01*
X80417Y373683D01*
X80500Y373975D01*
X80667Y374183D01*
X80917Y374350D01*
X81208Y374392D01*
X81458Y374350D01*
X81708Y374183D01*
X81917Y373933D01*
X82000Y373642D01*
X81917Y373308D01*
X81667Y373017D01*
X81292Y372850D01*
X80875Y372808D01*
X80333Y372892D01*
X80042Y373017D01*
X79750Y373225D01*
X79542Y373517D01*
X79500Y373808D01*
X79583Y374100D01*
X79792Y374308D01*
G01X81708Y375992D02*
X81917Y376283D01*
X82000Y376617D01*
X81917Y376950D01*
X81667Y377242D01*
X81292Y377450D01*
X80917Y377533D01*
X80458D01*
X80083Y377450D01*
X79750Y377242D01*
X79583Y376992D01*
X79500Y376700D01*
X79583Y376367D01*
X79750Y376117D01*
X80000Y375950D01*
X80333Y375867D01*
X80625Y375950D01*
X80917Y376158D01*
X81083Y376408D01*
X81125Y376700D01*
X81042Y377033D01*
X80833Y377283D01*
X80458Y377533D01*
G01X96500Y374700D02*
X92500D01*
Y367300D01*
G01X75967Y383000D02*
Y385500D01*
X77008D01*
X77342Y385375D01*
X77550Y385208D01*
X77633Y384875D01*
X77550Y384542D01*
X77300Y384333D01*
X77008Y384208D01*
X75967D01*
G01X77008D02*
X77633Y383000D01*
G01X79192Y383292D02*
X79483Y383083D01*
X79817Y383000D01*
X80150Y383083D01*
X80442Y383333D01*
X80650Y383708D01*
X80733Y384083D01*
Y384542D01*
X80650Y384917D01*
X80442Y385250D01*
X80192Y385417D01*
X79900Y385500D01*
X79567Y385417D01*
X79317Y385250D01*
X79150Y385000D01*
X79067Y384667D01*
X79150Y384375D01*
X79358Y384083D01*
X79608Y383917D01*
X79900Y383875D01*
X80233Y383958D01*
X80483Y384167D01*
X80733Y384542D01*
G01X83000Y383000D02*
X83292Y383042D01*
X83625Y383167D01*
X83833Y383375D01*
X83917Y383667D01*
X83833Y383958D01*
X83583Y384208D01*
X83208Y384333D01*
X82792D01*
X82542Y384417D01*
X82333Y384625D01*
X82250Y384917D01*
X82375Y385208D01*
X82667Y385417D01*
X83000Y385500D01*
X83333Y385417D01*
X83625Y385208D01*
X83750Y384917D01*
X83667Y384625D01*
X83458Y384417D01*
X83208Y384333D01*
X82792D01*
X82417Y384208D01*
X82167Y383958D01*
X82083Y383667D01*
X82167Y383375D01*
X82375Y383167D01*
X82708Y383042D01*
X83000Y383000D01*
G01X85183Y383500D02*
X85433Y383208D01*
X85767Y383042D01*
X86142Y383000D01*
X86475Y383042D01*
X86808Y383250D01*
X87017Y383500D01*
X87058Y383750D01*
X86975Y384042D01*
X86683Y384250D01*
X86392Y384333D01*
X86017D01*
G01X86392D02*
X86642Y384458D01*
X86850Y384667D01*
X86933Y384917D01*
X86850Y385167D01*
X86642Y385375D01*
X86267Y385500D01*
X85892Y385458D01*
X85517Y385292D01*
G01X88492Y383292D02*
X88783Y383083D01*
X89117Y383000D01*
X89450Y383083D01*
X89742Y383333D01*
X89950Y383708D01*
X90033Y384083D01*
Y384542D01*
X89950Y384917D01*
X89742Y385250D01*
X89492Y385417D01*
X89200Y385500D01*
X88867Y385417D01*
X88617Y385250D01*
X88450Y385000D01*
X88367Y384667D01*
X88450Y384375D01*
X88658Y384083D01*
X88908Y383917D01*
X89200Y383875D01*
X89533Y383958D01*
X89783Y384167D01*
X90033Y384542D01*
G01X83475Y379775D02*
Y375775D01*
X90875D01*
G01X103967Y382000D02*
Y384500D01*
X105008D01*
X105342Y384375D01*
X105550Y384208D01*
X105633Y383875D01*
X105550Y383542D01*
X105300Y383333D01*
X105008Y383208D01*
X103967D01*
G01X105008D02*
X105633Y382000D01*
G01X107192Y382292D02*
X107483Y382083D01*
X107817Y382000D01*
X108150Y382083D01*
X108442Y382333D01*
X108650Y382708D01*
X108733Y383083D01*
Y383542D01*
X108650Y383917D01*
X108442Y384250D01*
X108192Y384417D01*
X107900Y384500D01*
X107567Y384417D01*
X107317Y384250D01*
X107150Y384000D01*
X107067Y383667D01*
X107150Y383375D01*
X107358Y383083D01*
X107608Y382917D01*
X107900Y382875D01*
X108233Y382958D01*
X108483Y383167D01*
X108733Y383542D01*
G01X111000Y382000D02*
X111292Y382042D01*
X111625Y382167D01*
X111833Y382375D01*
X111917Y382667D01*
X111833Y382958D01*
X111583Y383208D01*
X111208Y383333D01*
X110792D01*
X110542Y383417D01*
X110333Y383625D01*
X110250Y383917D01*
X110375Y384208D01*
X110667Y384417D01*
X111000Y384500D01*
X111333Y384417D01*
X111625Y384208D01*
X111750Y383917D01*
X111667Y383625D01*
X111458Y383417D01*
X111208Y383333D01*
X110792D01*
X110417Y383208D01*
X110167Y382958D01*
X110083Y382667D01*
X110167Y382375D01*
X110375Y382167D01*
X110708Y382042D01*
X111000Y382000D01*
G01X114600D02*
Y384500D01*
X113058Y382708D01*
X115142D01*
G01X117200Y384500D02*
X116867Y384417D01*
X116617Y384208D01*
X116450Y383958D01*
X116325Y383625D01*
X116283Y383250D01*
X116325Y382875D01*
X116450Y382542D01*
X116617Y382292D01*
X116867Y382083D01*
X117200Y382000D01*
X117533Y382083D01*
X117783Y382292D01*
X117950Y382542D01*
X118075Y382875D01*
X118117Y383250D01*
X118075Y383625D01*
X117950Y383958D01*
X117783Y384208D01*
X117533Y384417D01*
X117200Y384500D01*
G01X93917Y393500D02*
Y396000D01*
X94958D01*
X95292Y395875D01*
X95500Y395708D01*
X95583Y395375D01*
X95500Y395042D01*
X95250Y394833D01*
X94958Y394708D01*
X93917D01*
G01X94958D02*
X95583Y393500D01*
G01X97142Y393792D02*
X97433Y393583D01*
X97767Y393500D01*
X98100Y393583D01*
X98392Y393833D01*
X98600Y394208D01*
X98683Y394583D01*
Y395042D01*
X98600Y395417D01*
X98392Y395750D01*
X98142Y395917D01*
X97850Y396000D01*
X97517Y395917D01*
X97267Y395750D01*
X97100Y395500D01*
X97017Y395167D01*
X97100Y394875D01*
X97308Y394583D01*
X97558Y394417D01*
X97850Y394375D01*
X98183Y394458D01*
X98433Y394667D01*
X98683Y395042D01*
G01X100950Y393500D02*
X101242Y393542D01*
X101575Y393667D01*
X101783Y393875D01*
X101867Y394167D01*
X101783Y394458D01*
X101533Y394708D01*
X101158Y394833D01*
X100742D01*
X100492Y394917D01*
X100283Y395125D01*
X100200Y395417D01*
X100325Y395708D01*
X100617Y395917D01*
X100950Y396000D01*
X101283Y395917D01*
X101575Y395708D01*
X101700Y395417D01*
X101617Y395125D01*
X101408Y394917D01*
X101158Y394833D01*
X100742D01*
X100367Y394708D01*
X100117Y394458D01*
X100033Y394167D01*
X100117Y393875D01*
X100325Y393667D01*
X100658Y393542D01*
X100950Y393500D01*
G01X103258Y394542D02*
X103550Y394833D01*
X103800Y395000D01*
X104133Y395083D01*
X104425Y395000D01*
X104633Y394833D01*
X104800Y394583D01*
X104842Y394292D01*
X104800Y394042D01*
X104633Y393792D01*
X104383Y393583D01*
X104092Y393500D01*
X103758Y393583D01*
X103467Y393833D01*
X103300Y394208D01*
X103258Y394625D01*
X103342Y395167D01*
X103467Y395458D01*
X103675Y395750D01*
X103967Y395958D01*
X104258Y396000D01*
X104550Y395917D01*
X104758Y395708D01*
G01X107650Y393500D02*
Y396000D01*
X106108Y394208D01*
X108192D01*
G01X94525Y404525D02*
X99725D01*
G01X94525Y397525D02*
X102325D01*
G01X94525Y404525D02*
Y397525D01*
G01X107925Y404525D02*
X99225D01*
G01X107925Y397525D02*
Y404525D01*
G01X101525Y397525D02*
X107925D01*
G01X67267Y393000D02*
Y395500D01*
X68308D01*
X68642Y395375D01*
X68850Y395208D01*
X68933Y394875D01*
X68850Y394542D01*
X68600Y394333D01*
X68308Y394208D01*
X67267D01*
G01X68308D02*
X68933Y393000D01*
G01X70492Y393292D02*
X70783Y393083D01*
X71117Y393000D01*
X71450Y393083D01*
X71742Y393333D01*
X71950Y393708D01*
X72033Y394083D01*
Y394542D01*
X71950Y394917D01*
X71742Y395250D01*
X71492Y395417D01*
X71200Y395500D01*
X70867Y395417D01*
X70617Y395250D01*
X70450Y395000D01*
X70367Y394667D01*
X70450Y394375D01*
X70658Y394083D01*
X70908Y393917D01*
X71200Y393875D01*
X71533Y393958D01*
X71783Y394167D01*
X72033Y394542D01*
G01X73508Y395083D02*
X73758Y395333D01*
X74050Y395458D01*
X74383Y395500D01*
X74800Y395417D01*
X75092Y395208D01*
X75175Y394958D01*
X75133Y394708D01*
X74967Y394500D01*
X74133Y394083D01*
X73758Y393792D01*
X73508Y393375D01*
X73425Y393000D01*
X75175D01*
G01X77900D02*
Y395500D01*
X76358Y393708D01*
X78442D01*
G01X79708Y394042D02*
X80000Y394333D01*
X80250Y394500D01*
X80583Y394583D01*
X80875Y394500D01*
X81083Y394333D01*
X81250Y394083D01*
X81292Y393792D01*
X81250Y393542D01*
X81083Y393292D01*
X80833Y393083D01*
X80542Y393000D01*
X80208Y393083D01*
X79917Y393333D01*
X79750Y393708D01*
X79708Y394125D01*
X79792Y394667D01*
X79917Y394958D01*
X80125Y395250D01*
X80417Y395458D01*
X80708Y395500D01*
X81000Y395417D01*
X81208Y395208D01*
G01X63800Y413700D02*
Y400700D01*
G01X89800D02*
Y413700D01*
G01X63800Y400700D02*
X89800D01*
G01X93300Y408417D02*
X90800D01*
Y409417D01*
X90925Y409750D01*
X91217Y410000D01*
X91550Y410083D01*
X91883Y410000D01*
X92133Y409792D01*
X92258Y409417D01*
Y408417D01*
G01X91008Y413267D02*
X90883Y413017D01*
X90800Y412725D01*
Y412392D01*
X90925Y412017D01*
X91133Y411725D01*
X91383Y411517D01*
X91800Y411350D01*
X92175Y411308D01*
X92550Y411392D01*
X92800Y411517D01*
X93050Y411767D01*
X93217Y412058D01*
X93300Y412350D01*
Y412642D01*
X93217Y412933D01*
X93092Y413183D01*
X92925Y413392D01*
G01X93300Y415450D02*
X90800D01*
X91300Y414950D01*
G01X93300D02*
Y415950D01*
G01X91217Y417758D02*
X90967Y418008D01*
X90842Y418300D01*
X90800Y418633D01*
X90883Y419050D01*
X91092Y419342D01*
X91342Y419425D01*
X91592Y419383D01*
X91800Y419217D01*
X92217Y418383D01*
X92508Y418008D01*
X92925Y417758D01*
X93300Y417675D01*
Y419425D01*
G01Y421650D02*
X90800D01*
X91300Y421150D01*
G01X93300D02*
Y422150D01*
G01X90800Y424750D02*
X90883Y424417D01*
X91092Y424167D01*
X91342Y424000D01*
X91675Y423875D01*
X92050Y423833D01*
X92425Y423875D01*
X92758Y424000D01*
X93008Y424167D01*
X93217Y424417D01*
X93300Y424750D01*
X93217Y425083D01*
X93008Y425333D01*
X92758Y425500D01*
X92425Y425625D01*
X92050Y425667D01*
X91675Y425625D01*
X91342Y425500D01*
X91092Y425333D01*
X90883Y425083D01*
X90800Y424750D01*
G01X94450Y407150D02*
Y425850D01*
X104750D01*
Y407150D01*
X94450D01*
G01X74834Y349983D02*
X72334D01*
Y350817D01*
X72459Y351150D01*
X72626Y351400D01*
X72876Y351608D01*
X73167Y351775D01*
X73584Y351817D01*
X74001Y351775D01*
X74292Y351608D01*
X74542Y351400D01*
X74709Y351150D01*
X74834Y350817D01*
Y349983D01*
G01X72751Y353208D02*
X72501Y353458D01*
X72376Y353750D01*
X72334Y354083D01*
X72417Y354500D01*
X72626Y354792D01*
X72876Y354875D01*
X73126Y354833D01*
X73334Y354667D01*
X73751Y353833D01*
X74042Y353458D01*
X74459Y353208D01*
X74834Y353125D01*
Y354875D01*
G01Y357017D02*
X74292Y357100D01*
X73834Y357225D01*
X73417Y357392D01*
X72959Y357600D01*
X72334Y357933D01*
Y356267D01*
G01X81200Y344000D02*
Y360100D01*
G01X88200Y344000D02*
X81200D01*
G01X88200Y360100D02*
Y344000D01*
G01X81200Y360100D02*
X88200D01*
G01X114473Y515715D02*
X113640Y514382D01*
X113140Y512882D01*
Y511548D01*
X113640Y510215D01*
X114473Y509215D01*
X115640Y508715D01*
X116806Y509048D01*
X117807Y509882D01*
X118473Y511382D01*
X118807Y513382D01*
X119473Y514548D01*
X120640Y515048D01*
X121807Y514715D01*
X122640Y513882D01*
X123140Y512715D01*
Y511548D01*
X122807Y510382D01*
X121973Y509382D01*
G01X114473Y505115D02*
X113640Y503782D01*
X113140Y502282D01*
Y500948D01*
X113640Y499615D01*
X114473Y498615D01*
X115640Y498115D01*
X116806Y498448D01*
X117807Y499282D01*
X118473Y500782D01*
X118807Y502782D01*
X119473Y503948D01*
X120640Y504448D01*
X121807Y504115D01*
X122640Y503282D01*
X123140Y502115D01*
Y500948D01*
X122807Y499782D01*
X121973Y498782D01*
G01X113140Y494682D02*
X123140D01*
Y491348D01*
X122640Y490015D01*
X121973Y489015D01*
X120973Y488182D01*
X119806Y487515D01*
X118140Y487348D01*
X116473Y487515D01*
X115307Y488182D01*
X114306Y489015D01*
X113640Y490015D01*
X113140Y491348D01*
Y494682D01*
G01Y480415D02*
X123140D01*
X121140Y482415D01*
G01X113140D02*
Y478415D01*
G01X115140Y473482D02*
X113973Y472482D01*
X113307Y471149D01*
X113140Y469648D01*
X113307Y468315D01*
X114140Y466982D01*
X115140Y466148D01*
X116140Y465982D01*
X117306Y466315D01*
X118140Y467482D01*
X118473Y468648D01*
Y470148D01*
G01Y468648D02*
X118973Y467648D01*
X119806Y466815D01*
X120807Y466482D01*
X121807Y466815D01*
X122640Y467648D01*
X123140Y469148D01*
X122973Y470648D01*
X122307Y472148D01*
G01X105700Y447117D02*
X103200D01*
Y448117D01*
X103325Y448450D01*
X103617Y448700D01*
X103950Y448783D01*
X104283Y448700D01*
X104533Y448492D01*
X104658Y448117D01*
Y447117D01*
G01X103408Y451967D02*
X103283Y451717D01*
X103200Y451425D01*
Y451092D01*
X103325Y450717D01*
X103533Y450425D01*
X103783Y450217D01*
X104200Y450050D01*
X104575Y450008D01*
X104950Y450092D01*
X105200Y450217D01*
X105450Y450467D01*
X105617Y450758D01*
X105700Y451050D01*
Y451342D01*
X105617Y451633D01*
X105492Y451883D01*
X105325Y452092D01*
G01X105700Y454150D02*
X103200D01*
X103700Y453650D01*
G01X105700D02*
Y454650D01*
G01X103617Y456458D02*
X103367Y456708D01*
X103242Y457000D01*
X103200Y457333D01*
X103283Y457750D01*
X103492Y458042D01*
X103742Y458125D01*
X103992Y458083D01*
X104200Y457917D01*
X104617Y457083D01*
X104908Y456708D01*
X105325Y456458D01*
X105700Y456375D01*
Y458125D01*
G01Y460350D02*
X103200D01*
X103700Y459850D01*
G01X105700D02*
Y460850D01*
G01X105200Y462533D02*
X105492Y462783D01*
X105658Y463117D01*
X105700Y463492D01*
X105658Y463825D01*
X105450Y464158D01*
X105200Y464367D01*
X104950Y464408D01*
X104658Y464325D01*
X104450Y464033D01*
X104367Y463742D01*
Y463367D01*
G01Y463742D02*
X104242Y463992D01*
X104033Y464200D01*
X103783Y464283D01*
X103533Y464200D01*
X103325Y463992D01*
X103200Y463617D01*
X103242Y463242D01*
X103408Y462867D01*
G01X89800Y413700D02*
X63800D01*
G01X112700Y447517D02*
X110200D01*
Y448517D01*
X110325Y448850D01*
X110617Y449100D01*
X110950Y449183D01*
X111283Y449100D01*
X111533Y448892D01*
X111658Y448517D01*
Y447517D01*
G01X110408Y452367D02*
X110283Y452117D01*
X110200Y451825D01*
Y451492D01*
X110325Y451117D01*
X110533Y450825D01*
X110783Y450617D01*
X111200Y450450D01*
X111575Y450408D01*
X111950Y450492D01*
X112200Y450617D01*
X112450Y450867D01*
X112617Y451158D01*
X112700Y451450D01*
Y451742D01*
X112617Y452033D01*
X112492Y452283D01*
X112325Y452492D01*
G01X112700Y454550D02*
X110200D01*
X110700Y454050D01*
G01X112700D02*
Y455050D01*
G01X110617Y456858D02*
X110367Y457108D01*
X110242Y457400D01*
X110200Y457733D01*
X110283Y458150D01*
X110492Y458442D01*
X110742Y458525D01*
X110992Y458483D01*
X111200Y458317D01*
X111617Y457483D01*
X111908Y457108D01*
X112325Y456858D01*
X112700Y456775D01*
Y458525D01*
G01Y460750D02*
X110200D01*
X110700Y460250D01*
G01X112700D02*
Y461250D01*
G01Y463850D02*
X110200D01*
X110700Y463350D01*
G01X112700D02*
Y464350D01*
G01X111450Y445350D02*
Y426650D01*
X101150D01*
Y445350D01*
X111450D01*
G01X101600Y512167D02*
X101850Y512375D01*
X102017Y512625D01*
X102100Y512917D01*
X102017Y513250D01*
X101850Y513500D01*
X101600Y513750D01*
X101267Y513833D01*
X99600D01*
G01X102100Y516100D02*
X99600D01*
X100100Y515600D01*
G01X102100D02*
Y516600D01*
G01X101600Y518283D02*
X101892Y518533D01*
X102058Y518867D01*
X102100Y519242D01*
X102058Y519575D01*
X101850Y519908D01*
X101600Y520117D01*
X101350Y520158D01*
X101058Y520075D01*
X100850Y519783D01*
X100767Y519492D01*
Y519117D01*
G01Y519492D02*
X100642Y519742D01*
X100433Y519950D01*
X100183Y520033D01*
X99933Y519950D01*
X99725Y519742D01*
X99600Y519367D01*
X99642Y518992D01*
X99808Y518617D01*
G01X105000Y535917D02*
X102500D01*
Y536917D01*
X102625Y537250D01*
X102917Y537500D01*
X103250Y537583D01*
X103583Y537500D01*
X103833Y537292D01*
X103958Y536917D01*
Y535917D01*
G01X102708Y540767D02*
X102583Y540517D01*
X102500Y540225D01*
Y539892D01*
X102625Y539517D01*
X102833Y539225D01*
X103083Y539017D01*
X103500Y538850D01*
X103875Y538808D01*
X104250Y538892D01*
X104500Y539017D01*
X104750Y539267D01*
X104917Y539558D01*
X105000Y539850D01*
Y540142D01*
X104917Y540433D01*
X104792Y540683D01*
X104625Y540892D01*
G01X105000Y542950D02*
X102500D01*
X103000Y542450D01*
G01X105000D02*
Y543450D01*
G01X102917Y545258D02*
X102667Y545508D01*
X102542Y545800D01*
X102500Y546133D01*
X102583Y546550D01*
X102792Y546842D01*
X103042Y546925D01*
X103292Y546883D01*
X103500Y546717D01*
X103917Y545883D01*
X104208Y545508D01*
X104625Y545258D01*
X105000Y545175D01*
Y546925D01*
G01Y549150D02*
X102500D01*
X103000Y548650D01*
G01X105000D02*
Y549650D01*
G01Y552750D02*
X102500D01*
X104292Y551208D01*
Y553292D01*
G01X84675Y592633D02*
X85008Y592425D01*
X85383Y592300D01*
X85717D01*
X86050Y592425D01*
X86300Y592633D01*
X86425Y592925D01*
X86342Y593217D01*
X86133Y593467D01*
X85758Y593633D01*
X85258Y593717D01*
X84967Y593883D01*
X84842Y594175D01*
X84925Y594467D01*
X85133Y594675D01*
X85425Y594800D01*
X85717D01*
X86008Y594717D01*
X86258Y594508D01*
G01X87733Y592300D02*
Y594800D01*
X88567D01*
X88900Y594675D01*
X89150Y594508D01*
X89358Y594258D01*
X89525Y593967D01*
X89567Y593550D01*
X89525Y593133D01*
X89358Y592842D01*
X89150Y592592D01*
X88900Y592425D01*
X88567Y592300D01*
X87733D01*
G01X90833D02*
Y594800D01*
X91667D01*
X92000Y594675D01*
X92250Y594508D01*
X92458Y594258D01*
X92625Y593967D01*
X92667Y593550D01*
X92625Y593133D01*
X92458Y592842D01*
X92250Y592592D01*
X92000Y592425D01*
X91667Y592300D01*
X90833D01*
G01X96908D02*
X97950Y594800D01*
X98992Y592300D01*
G01X98617Y593175D02*
X97283D01*
G01X101967Y594592D02*
X101717Y594717D01*
X101425Y594800D01*
X101092D01*
X100717Y594675D01*
X100425Y594467D01*
X100217Y594217D01*
X100050Y593800D01*
X100008Y593425D01*
X100092Y593050D01*
X100217Y592800D01*
X100467Y592550D01*
X100758Y592383D01*
X101050Y592300D01*
X101342D01*
X101633Y592383D01*
X101883Y592508D01*
X102092Y592675D01*
G01X104150Y594800D02*
Y592300D01*
G01X103192Y594800D02*
X105108D01*
G01X107250Y592300D02*
Y594800D01*
X106750Y594300D01*
G01Y592300D02*
X107750D01*
G01X109433Y592800D02*
X109683Y592508D01*
X110017Y592342D01*
X110392Y592300D01*
X110725Y592342D01*
X111058Y592550D01*
X111267Y592800D01*
X111308Y593050D01*
X111225Y593342D01*
X110933Y593550D01*
X110642Y593633D01*
X110267D01*
G01X110642D02*
X110892Y593758D01*
X111100Y593967D01*
X111183Y594217D01*
X111100Y594467D01*
X110892Y594675D01*
X110517Y594800D01*
X110142Y594758D01*
X109767Y594592D01*
G01X84917Y596500D02*
Y599000D01*
X85917D01*
X86250Y598875D01*
X86500Y598583D01*
X86583Y598250D01*
X86500Y597917D01*
X86292Y597667D01*
X85917Y597542D01*
X84917D01*
G01X89683Y596500D02*
X88017D01*
Y599000D01*
X89683D01*
G01X89017Y597792D02*
X88017D01*
G01X92283Y597833D02*
X92450Y597958D01*
X92575Y598167D01*
X92658Y598458D01*
X92575Y598708D01*
X92408Y598875D01*
X92117Y599000D01*
X90992D01*
Y596500D01*
X92367D01*
X92658Y596667D01*
X92825Y596917D01*
X92908Y597208D01*
X92825Y597500D01*
X92575Y597750D01*
X92283Y597833D01*
X90992D01*
G01X97108Y596500D02*
X98150Y599000D01*
X99192Y596500D01*
G01X98817Y597375D02*
X97483D01*
G01X101250Y599000D02*
Y596500D01*
G01X100292Y599000D02*
X102208D01*
G01X104350D02*
Y596500D01*
G01X103392Y599000D02*
X105308D01*
G01X106492Y596500D02*
Y599000D01*
X108408Y596500D01*
Y599000D01*
G01X110550Y596500D02*
Y599000D01*
X110050Y598500D01*
G01Y596500D02*
X111050D01*
G01X112733Y597000D02*
X112983Y596708D01*
X113317Y596542D01*
X113692Y596500D01*
X114025Y596542D01*
X114358Y596750D01*
X114567Y597000D01*
X114608Y597250D01*
X114525Y597542D01*
X114233Y597750D01*
X113942Y597833D01*
X113567D01*
G01X113942D02*
X114192Y597958D01*
X114400Y598167D01*
X114483Y598417D01*
X114400Y598667D01*
X114192Y598875D01*
X113817Y599000D01*
X113442Y598958D01*
X113067Y598792D01*
G01X66967Y608000D02*
Y605500D01*
X68633D01*
G01X71733D02*
X70067D01*
Y608000D01*
X71733D01*
G01X71067Y606792D02*
X70067D01*
G01X73083Y605500D02*
Y608000D01*
X73917D01*
X74250Y607875D01*
X74500Y607708D01*
X74708Y607458D01*
X74875Y607167D01*
X74917Y606750D01*
X74875Y606333D01*
X74708Y606042D01*
X74500Y605792D01*
X74250Y605625D01*
X73917Y605500D01*
X73083D01*
G01X77100D02*
Y608000D01*
X76600Y607500D01*
G01Y605500D02*
X77600D01*
G01X79283Y606000D02*
X79533Y605708D01*
X79867Y605542D01*
X80242Y605500D01*
X80575Y605542D01*
X80908Y605750D01*
X81117Y606000D01*
X81158Y606250D01*
X81075Y606542D01*
X80783Y606750D01*
X80492Y606833D01*
X80117D01*
G01X80492D02*
X80742Y606958D01*
X80950Y607167D01*
X81033Y607417D01*
X80950Y607667D01*
X80742Y607875D01*
X80367Y608000D01*
X79992Y607958D01*
X79617Y607792D01*
G01X67135Y609980D02*
Y617580D01*
X78535D01*
Y609980D01*
X67135D01*
G01X109000Y628400D02*
X108958Y628067D01*
X108792Y627775D01*
X108542Y627525D01*
X108250Y627358D01*
X107917Y627275D01*
X107583D01*
X107250Y627358D01*
X106958Y627525D01*
X106708Y627775D01*
X106542Y628067D01*
X106500Y628400D01*
X106542Y628733D01*
X106708Y629025D01*
X106958Y629275D01*
X107250Y629442D01*
X107583Y629525D01*
X107917D01*
X108250Y629442D01*
X108542Y629275D01*
X108792Y629025D01*
X108958Y628733D01*
X109000Y628400D01*
G01X108333Y628733D02*
X109000Y629233D01*
G01X108708Y630792D02*
X108917Y631083D01*
X109000Y631417D01*
X108917Y631750D01*
X108667Y632042D01*
X108292Y632250D01*
X107917Y632333D01*
X107458D01*
X107083Y632250D01*
X106750Y632042D01*
X106583Y631792D01*
X106500Y631500D01*
X106583Y631167D01*
X106750Y630917D01*
X107000Y630750D01*
X107333Y630667D01*
X107625Y630750D01*
X107917Y630958D01*
X108083Y631208D01*
X108125Y631500D01*
X108042Y631833D01*
X107833Y632083D01*
X107458Y632333D01*
G01X109000Y635100D02*
X106500D01*
X108292Y633558D01*
Y635642D01*
G01X91000Y622977D02*
X105000D01*
G01X91000Y635977D02*
Y622977D01*
G01X105000D02*
Y635977D01*
G01X88100Y621300D02*
X88058Y620967D01*
X87892Y620675D01*
X87642Y620425D01*
X87350Y620258D01*
X87017Y620175D01*
X86683D01*
X86350Y620258D01*
X86058Y620425D01*
X85808Y620675D01*
X85642Y620967D01*
X85600Y621300D01*
X85642Y621633D01*
X85808Y621925D01*
X86058Y622175D01*
X86350Y622342D01*
X86683Y622425D01*
X87017D01*
X87350Y622342D01*
X87642Y622175D01*
X87892Y621925D01*
X88058Y621633D01*
X88100Y621300D01*
G01X87433Y621633D02*
X88100Y622133D01*
G01X87808Y623692D02*
X88017Y623983D01*
X88100Y624317D01*
X88017Y624650D01*
X87767Y624942D01*
X87392Y625150D01*
X87017Y625233D01*
X86558D01*
X86183Y625150D01*
X85850Y624942D01*
X85683Y624692D01*
X85600Y624400D01*
X85683Y624067D01*
X85850Y623817D01*
X86100Y623650D01*
X86433Y623567D01*
X86725Y623650D01*
X87017Y623858D01*
X87183Y624108D01*
X87225Y624400D01*
X87142Y624733D01*
X86933Y624983D01*
X86558Y625233D01*
G01X87725Y626583D02*
X87933Y626833D01*
X88058Y627125D01*
X88100Y627500D01*
X88017Y627875D01*
X87850Y628167D01*
X87558Y628375D01*
X87225Y628417D01*
X86892Y628333D01*
X86683Y628125D01*
X86517Y627833D01*
X86475Y627542D01*
X86517Y627250D01*
X86683Y626875D01*
X85600Y627000D01*
Y628125D01*
G01X69958Y619496D02*
X83958D01*
G01X69958Y632496D02*
Y619496D01*
G01X83958D02*
Y632496D01*
G01X99717Y613600D02*
Y616100D01*
X100758D01*
X101092Y615975D01*
X101300Y615808D01*
X101383Y615475D01*
X101300Y615142D01*
X101050Y614933D01*
X100758Y614808D01*
X99717D01*
G01X100758D02*
X101383Y613600D01*
G01X102942Y613892D02*
X103233Y613683D01*
X103567Y613600D01*
X103900Y613683D01*
X104192Y613933D01*
X104400Y614308D01*
X104483Y614683D01*
Y615142D01*
X104400Y615517D01*
X104192Y615850D01*
X103942Y616017D01*
X103650Y616100D01*
X103317Y616017D01*
X103067Y615850D01*
X102900Y615600D01*
X102817Y615267D01*
X102900Y614975D01*
X103108Y614683D01*
X103358Y614517D01*
X103650Y614475D01*
X103983Y614558D01*
X104233Y614767D01*
X104483Y615142D01*
G01X107250Y613600D02*
Y616100D01*
X105708Y614308D01*
X107792D01*
G01X109058Y615683D02*
X109308Y615933D01*
X109600Y616058D01*
X109933Y616100D01*
X110350Y616017D01*
X110642Y615808D01*
X110725Y615558D01*
X110683Y615308D01*
X110517Y615100D01*
X109683Y614683D01*
X109308Y614392D01*
X109058Y613975D01*
X108975Y613600D01*
X110725D01*
G01X112950D02*
Y616100D01*
X112450Y615600D01*
G01Y613600D02*
X113450D01*
G01X98200Y613500D02*
Y617500D01*
X90800D01*
G01X99675Y617933D02*
X100008Y617725D01*
X100383Y617600D01*
X100717D01*
X101050Y617725D01*
X101300Y617933D01*
X101425Y618225D01*
X101342Y618517D01*
X101133Y618767D01*
X100758Y618933D01*
X100258Y619017D01*
X99967Y619183D01*
X99842Y619475D01*
X99925Y619767D01*
X100133Y619975D01*
X100425Y620100D01*
X100717D01*
X101008Y620017D01*
X101258Y619808D01*
G01X102817Y617600D02*
Y620100D01*
X103858D01*
X104192Y619975D01*
X104400Y619808D01*
X104483Y619475D01*
X104400Y619142D01*
X104150Y618933D01*
X103858Y618808D01*
X102817D01*
G01X103858D02*
X104483Y617600D01*
G01X106750D02*
Y620100D01*
X106250Y619600D01*
G01Y617600D02*
X107250D01*
G01X109850D02*
Y620100D01*
X109350Y619600D01*
G01Y617600D02*
X110350D01*
G01X113450D02*
Y620100D01*
X111908Y618308D01*
X113992D01*
G01X115967Y617600D02*
X116050Y618142D01*
X116175Y618600D01*
X116342Y619017D01*
X116550Y619475D01*
X116883Y620100D01*
X115217D01*
G01X98200Y617977D02*
Y621977D01*
X90800D01*
G01X97767Y604900D02*
Y607400D01*
X98808D01*
X99142Y607275D01*
X99350Y607108D01*
X99433Y606775D01*
X99350Y606442D01*
X99100Y606233D01*
X98808Y606108D01*
X97767D01*
G01X98808D02*
X99433Y604900D01*
G01X100992Y605192D02*
X101283Y604983D01*
X101617Y604900D01*
X101950Y604983D01*
X102242Y605233D01*
X102450Y605608D01*
X102533Y605983D01*
Y606442D01*
X102450Y606817D01*
X102242Y607150D01*
X101992Y607317D01*
X101700Y607400D01*
X101367Y607317D01*
X101117Y607150D01*
X100950Y606900D01*
X100867Y606567D01*
X100950Y606275D01*
X101158Y605983D01*
X101408Y605817D01*
X101700Y605775D01*
X102033Y605858D01*
X102283Y606067D01*
X102533Y606442D01*
G01X104092Y605192D02*
X104383Y604983D01*
X104717Y604900D01*
X105050Y604983D01*
X105342Y605233D01*
X105550Y605608D01*
X105633Y605983D01*
Y606442D01*
X105550Y606817D01*
X105342Y607150D01*
X105092Y607317D01*
X104800Y607400D01*
X104467Y607317D01*
X104217Y607150D01*
X104050Y606900D01*
X103967Y606567D01*
X104050Y606275D01*
X104258Y605983D01*
X104508Y605817D01*
X104800Y605775D01*
X105133Y605858D01*
X105383Y606067D01*
X105633Y606442D01*
G01X107900Y607400D02*
X107567Y607317D01*
X107317Y607108D01*
X107150Y606858D01*
X107025Y606525D01*
X106983Y606150D01*
X107025Y605775D01*
X107150Y605442D01*
X107317Y605192D01*
X107567Y604983D01*
X107900Y604900D01*
X108233Y604983D01*
X108483Y605192D01*
X108650Y605442D01*
X108775Y605775D01*
X108817Y606150D01*
X108775Y606525D01*
X108650Y606858D01*
X108483Y607108D01*
X108233Y607317D01*
X107900Y607400D01*
G01X110083Y605275D02*
X110333Y605067D01*
X110625Y604942D01*
X111000Y604900D01*
X111375Y604983D01*
X111667Y605150D01*
X111875Y605442D01*
X111917Y605775D01*
X111833Y606108D01*
X111625Y606317D01*
X111333Y606483D01*
X111042Y606525D01*
X110750Y606483D01*
X110375Y606317D01*
X110500Y607400D01*
X111625D01*
G01X90500Y601300D02*
X94500D01*
Y608700D01*
G01X59834Y606967D02*
X57334D01*
Y608008D01*
X57459Y608342D01*
X57626Y608550D01*
X57959Y608633D01*
X58292Y608550D01*
X58501Y608300D01*
X58626Y608008D01*
Y606967D01*
G01Y608008D02*
X59834Y608633D01*
G01X59542Y610192D02*
X59751Y610483D01*
X59834Y610817D01*
X59751Y611150D01*
X59501Y611442D01*
X59126Y611650D01*
X58751Y611733D01*
X58292D01*
X57917Y611650D01*
X57584Y611442D01*
X57417Y611192D01*
X57334Y610900D01*
X57417Y610567D01*
X57584Y610317D01*
X57834Y610150D01*
X58167Y610067D01*
X58459Y610150D01*
X58751Y610358D01*
X58917Y610608D01*
X58959Y610900D01*
X58876Y611233D01*
X58667Y611483D01*
X58292Y611733D01*
G01X59542Y613292D02*
X59751Y613583D01*
X59834Y613917D01*
X59751Y614250D01*
X59501Y614542D01*
X59126Y614750D01*
X58751Y614833D01*
X58292D01*
X57917Y614750D01*
X57584Y614542D01*
X57417Y614292D01*
X57334Y614000D01*
X57417Y613667D01*
X57584Y613417D01*
X57834Y613250D01*
X58167Y613167D01*
X58459Y613250D01*
X58751Y613458D01*
X58917Y613708D01*
X58959Y614000D01*
X58876Y614333D01*
X58667Y614583D01*
X58292Y614833D01*
G01X59459Y616183D02*
X59667Y616433D01*
X59792Y616725D01*
X59834Y617100D01*
X59751Y617475D01*
X59584Y617767D01*
X59292Y617975D01*
X58959Y618017D01*
X58626Y617933D01*
X58417Y617725D01*
X58251Y617433D01*
X58209Y617142D01*
X58251Y616850D01*
X58417Y616475D01*
X57334Y616600D01*
Y617725D01*
G01X59834Y620700D02*
X57334D01*
X59126Y619158D01*
Y621242D01*
G01X61623Y609170D02*
X65623D01*
Y616570D01*
G01X59333Y623967D02*
X56833D01*
Y625008D01*
X56958Y625342D01*
X57125Y625550D01*
X57458Y625633D01*
X57791Y625550D01*
X58000Y625300D01*
X58125Y625008D01*
Y623967D01*
G01Y625008D02*
X59333Y625633D01*
G01X59041Y627192D02*
X59250Y627483D01*
X59333Y627817D01*
X59250Y628150D01*
X59000Y628442D01*
X58625Y628650D01*
X58250Y628733D01*
X57791D01*
X57416Y628650D01*
X57083Y628442D01*
X56916Y628192D01*
X56833Y627900D01*
X56916Y627567D01*
X57083Y627317D01*
X57333Y627150D01*
X57666Y627067D01*
X57958Y627150D01*
X58250Y627358D01*
X58416Y627608D01*
X58458Y627900D01*
X58375Y628233D01*
X58166Y628483D01*
X57791Y628733D01*
G01X59041Y630292D02*
X59250Y630583D01*
X59333Y630917D01*
X59250Y631250D01*
X59000Y631542D01*
X58625Y631750D01*
X58250Y631833D01*
X57791D01*
X57416Y631750D01*
X57083Y631542D01*
X56916Y631292D01*
X56833Y631000D01*
X56916Y630667D01*
X57083Y630417D01*
X57333Y630250D01*
X57666Y630167D01*
X57958Y630250D01*
X58250Y630458D01*
X58416Y630708D01*
X58458Y631000D01*
X58375Y631333D01*
X58166Y631583D01*
X57791Y631833D01*
G01X58958Y633183D02*
X59166Y633433D01*
X59291Y633725D01*
X59333Y634100D01*
X59250Y634475D01*
X59083Y634767D01*
X58791Y634975D01*
X58458Y635017D01*
X58125Y634933D01*
X57916Y634725D01*
X57750Y634433D01*
X57708Y634142D01*
X57750Y633850D01*
X57916Y633475D01*
X56833Y633600D01*
Y634725D01*
G01X58833Y636283D02*
X59125Y636533D01*
X59291Y636867D01*
X59333Y637242D01*
X59291Y637575D01*
X59083Y637908D01*
X58833Y638117D01*
X58583Y638158D01*
X58291Y638075D01*
X58083Y637783D01*
X58000Y637492D01*
Y637117D01*
G01Y637492D02*
X57875Y637742D01*
X57666Y637950D01*
X57416Y638033D01*
X57166Y637950D01*
X56958Y637742D01*
X56833Y637367D01*
X56875Y636992D01*
X57041Y636617D01*
G01X69414Y633662D02*
X65414D01*
Y626262D01*
G01X99717Y609600D02*
Y612100D01*
X100758D01*
X101092Y611975D01*
X101300Y611808D01*
X101383Y611475D01*
X101300Y611142D01*
X101050Y610933D01*
X100758Y610808D01*
X99717D01*
G01X100758D02*
X101383Y609600D01*
G01X102942Y609892D02*
X103233Y609683D01*
X103567Y609600D01*
X103900Y609683D01*
X104192Y609933D01*
X104400Y610308D01*
X104483Y610683D01*
Y611142D01*
X104400Y611517D01*
X104192Y611850D01*
X103942Y612017D01*
X103650Y612100D01*
X103317Y612017D01*
X103067Y611850D01*
X102900Y611600D01*
X102817Y611267D01*
X102900Y610975D01*
X103108Y610683D01*
X103358Y610517D01*
X103650Y610475D01*
X103983Y610558D01*
X104233Y610767D01*
X104483Y611142D01*
G01X107250Y609600D02*
Y612100D01*
X105708Y610308D01*
X107792D01*
G01X109058Y611683D02*
X109308Y611933D01*
X109600Y612058D01*
X109933Y612100D01*
X110350Y612017D01*
X110642Y611808D01*
X110725Y611558D01*
X110683Y611308D01*
X110517Y611100D01*
X109683Y610683D01*
X109308Y610392D01*
X109058Y609975D01*
X108975Y609600D01*
X110725D01*
G01X112158Y611683D02*
X112408Y611933D01*
X112700Y612058D01*
X113033Y612100D01*
X113450Y612017D01*
X113742Y611808D01*
X113825Y611558D01*
X113783Y611308D01*
X113617Y611100D01*
X112783Y610683D01*
X112408Y610392D01*
X112158Y609975D01*
X112075Y609600D01*
X113825D01*
G01X98200Y609000D02*
Y613000D01*
X90800D01*
G01X76717Y672792D02*
X76467Y672917D01*
X76175Y673000D01*
X75842D01*
X75467Y672875D01*
X75175Y672667D01*
X74967Y672417D01*
X74800Y672000D01*
X74758Y671625D01*
X74842Y671250D01*
X74967Y671000D01*
X75217Y670750D01*
X75508Y670583D01*
X75800Y670500D01*
X76092D01*
X76383Y670583D01*
X76633Y670708D01*
X76842Y670875D01*
G01X78192Y670792D02*
X78483Y670583D01*
X78817Y670500D01*
X79150Y670583D01*
X79442Y670833D01*
X79650Y671208D01*
X79733Y671583D01*
Y672042D01*
X79650Y672417D01*
X79442Y672750D01*
X79192Y672917D01*
X78900Y673000D01*
X78567Y672917D01*
X78317Y672750D01*
X78150Y672500D01*
X78067Y672167D01*
X78150Y671875D01*
X78358Y671583D01*
X78608Y671417D01*
X78900Y671375D01*
X79233Y671458D01*
X79483Y671667D01*
X79733Y672042D01*
G01X81083Y670875D02*
X81333Y670667D01*
X81625Y670542D01*
X82000Y670500D01*
X82375Y670583D01*
X82667Y670750D01*
X82875Y671042D01*
X82917Y671375D01*
X82833Y671708D01*
X82625Y671917D01*
X82333Y672083D01*
X82042Y672125D01*
X81750Y672083D01*
X81375Y671917D01*
X81500Y673000D01*
X82625D01*
G01X84183Y671000D02*
X84433Y670708D01*
X84767Y670542D01*
X85142Y670500D01*
X85475Y670542D01*
X85808Y670750D01*
X86017Y671000D01*
X86058Y671250D01*
X85975Y671542D01*
X85683Y671750D01*
X85392Y671833D01*
X85017D01*
G01X85392D02*
X85642Y671958D01*
X85850Y672167D01*
X85933Y672417D01*
X85850Y672667D01*
X85642Y672875D01*
X85267Y673000D01*
X84892Y672958D01*
X84517Y672792D01*
G01X88200Y670500D02*
Y673000D01*
X87700Y672500D01*
G01Y670500D02*
X88700D01*
G01X53800Y643800D02*
X53758Y643467D01*
X53592Y643175D01*
X53342Y642925D01*
X53050Y642758D01*
X52717Y642675D01*
X52383D01*
X52050Y642758D01*
X51758Y642925D01*
X51508Y643175D01*
X51342Y643467D01*
X51300Y643800D01*
X51342Y644133D01*
X51508Y644425D01*
X51758Y644675D01*
X52050Y644842D01*
X52383Y644925D01*
X52717D01*
X53050Y644842D01*
X53342Y644675D01*
X53592Y644425D01*
X53758Y644133D01*
X53800Y643800D01*
G01X53133Y644133D02*
X53800Y644633D01*
G01X53508Y646192D02*
X53717Y646483D01*
X53800Y646817D01*
X53717Y647150D01*
X53467Y647442D01*
X53092Y647650D01*
X52717Y647733D01*
X52258D01*
X51883Y647650D01*
X51550Y647442D01*
X51383Y647192D01*
X51300Y646900D01*
X51383Y646567D01*
X51550Y646317D01*
X51800Y646150D01*
X52133Y646067D01*
X52425Y646150D01*
X52717Y646358D01*
X52883Y646608D01*
X52925Y646900D01*
X52842Y647233D01*
X52633Y647483D01*
X52258Y647733D01*
G01X53300Y649083D02*
X53592Y649333D01*
X53758Y649667D01*
X53800Y650042D01*
X53758Y650375D01*
X53550Y650708D01*
X53300Y650917D01*
X53050Y650958D01*
X52758Y650875D01*
X52550Y650583D01*
X52467Y650292D01*
Y649917D01*
G01Y650292D02*
X52342Y650542D01*
X52133Y650750D01*
X51883Y650833D01*
X51633Y650750D01*
X51425Y650542D01*
X51300Y650167D01*
X51342Y649792D01*
X51508Y649417D01*
G01X57000Y653977D02*
Y639977D01*
G01X70000Y653977D02*
X57000D01*
G01X70000Y639977D02*
Y653977D01*
G01X57000Y639977D02*
X70000D01*
G01X105000Y635977D02*
X91000D01*
G01X83958Y632496D02*
X69958D01*
G01X71967Y674500D02*
Y677000D01*
X73008D01*
X73342Y676875D01*
X73550Y676708D01*
X73633Y676375D01*
X73550Y676042D01*
X73300Y675833D01*
X73008Y675708D01*
X71967D01*
G01X73008D02*
X73633Y674500D01*
G01X75192Y674792D02*
X75483Y674583D01*
X75817Y674500D01*
X76150Y674583D01*
X76442Y674833D01*
X76650Y675208D01*
X76733Y675583D01*
Y676042D01*
X76650Y676417D01*
X76442Y676750D01*
X76192Y676917D01*
X75900Y677000D01*
X75567Y676917D01*
X75317Y676750D01*
X75150Y676500D01*
X75067Y676167D01*
X75150Y675875D01*
X75358Y675583D01*
X75608Y675417D01*
X75900Y675375D01*
X76233Y675458D01*
X76483Y675667D01*
X76733Y676042D01*
G01X79000Y674500D02*
X79292Y674542D01*
X79625Y674667D01*
X79833Y674875D01*
X79917Y675167D01*
X79833Y675458D01*
X79583Y675708D01*
X79208Y675833D01*
X78792D01*
X78542Y675917D01*
X78333Y676125D01*
X78250Y676417D01*
X78375Y676708D01*
X78667Y676917D01*
X79000Y677000D01*
X79333Y676917D01*
X79625Y676708D01*
X79750Y676417D01*
X79667Y676125D01*
X79458Y675917D01*
X79208Y675833D01*
X78792D01*
X78417Y675708D01*
X78167Y675458D01*
X78083Y675167D01*
X78167Y674875D01*
X78375Y674667D01*
X78708Y674542D01*
X79000Y674500D01*
G01X81308Y675542D02*
X81600Y675833D01*
X81850Y676000D01*
X82183Y676083D01*
X82475Y676000D01*
X82683Y675833D01*
X82850Y675583D01*
X82892Y675292D01*
X82850Y675042D01*
X82683Y674792D01*
X82433Y674583D01*
X82142Y674500D01*
X81808Y674583D01*
X81517Y674833D01*
X81350Y675208D01*
X81308Y675625D01*
X81392Y676167D01*
X81517Y676458D01*
X81725Y676750D01*
X82017Y676958D01*
X82308Y677000D01*
X82600Y676917D01*
X82808Y676708D01*
G01X85117Y674500D02*
X85200Y675042D01*
X85325Y675500D01*
X85492Y675917D01*
X85700Y676375D01*
X86033Y677000D01*
X84367D01*
G01X82700Y656977D02*
Y660977D01*
X75300D01*
G01X85589Y634527D02*
X89589D01*
Y641927D01*
G01X106000Y637967D02*
X103500D01*
Y639008D01*
X103625Y639342D01*
X103792Y639550D01*
X104125Y639633D01*
X104458Y639550D01*
X104667Y639300D01*
X104792Y639008D01*
Y637967D01*
G01Y639008D02*
X106000Y639633D01*
G01X105708Y641192D02*
X105917Y641483D01*
X106000Y641817D01*
X105917Y642150D01*
X105667Y642442D01*
X105292Y642650D01*
X104917Y642733D01*
X104458D01*
X104083Y642650D01*
X103750Y642442D01*
X103583Y642192D01*
X103500Y641900D01*
X103583Y641567D01*
X103750Y641317D01*
X104000Y641150D01*
X104333Y641067D01*
X104625Y641150D01*
X104917Y641358D01*
X105083Y641608D01*
X105125Y641900D01*
X105042Y642233D01*
X104833Y642483D01*
X104458Y642733D01*
G01X106000Y645000D02*
X105958Y645292D01*
X105833Y645625D01*
X105625Y645833D01*
X105333Y645917D01*
X105042Y645833D01*
X104792Y645583D01*
X104667Y645208D01*
Y644792D01*
X104583Y644542D01*
X104375Y644333D01*
X104083Y644250D01*
X103792Y644375D01*
X103583Y644667D01*
X103500Y645000D01*
X103583Y645333D01*
X103792Y645625D01*
X104083Y645750D01*
X104375Y645667D01*
X104583Y645458D01*
X104667Y645208D01*
Y644792D01*
X104792Y644417D01*
X105042Y644167D01*
X105333Y644083D01*
X105625Y644167D01*
X105833Y644375D01*
X105958Y644708D01*
X106000Y645000D01*
G01X104958Y647308D02*
X104667Y647600D01*
X104500Y647850D01*
X104417Y648183D01*
X104500Y648475D01*
X104667Y648683D01*
X104917Y648850D01*
X105208Y648892D01*
X105458Y648850D01*
X105708Y648683D01*
X105917Y648433D01*
X106000Y648142D01*
X105917Y647808D01*
X105667Y647517D01*
X105292Y647350D01*
X104875Y647308D01*
X104333Y647392D01*
X104042Y647517D01*
X103750Y647725D01*
X103542Y648017D01*
X103500Y648308D01*
X103583Y648600D01*
X103792Y648808D01*
G01X105708Y650492D02*
X105917Y650783D01*
X106000Y651117D01*
X105917Y651450D01*
X105667Y651742D01*
X105292Y651950D01*
X104917Y652033D01*
X104458D01*
X104083Y651950D01*
X103750Y651742D01*
X103583Y651492D01*
X103500Y651200D01*
X103583Y650867D01*
X103750Y650617D01*
X104000Y650450D01*
X104333Y650367D01*
X104625Y650450D01*
X104917Y650658D01*
X105083Y650908D01*
X105125Y651200D01*
X105042Y651533D01*
X104833Y651783D01*
X104458Y652033D01*
G01X74750Y634384D02*
X78750D01*
Y641784D01*
G01X71875Y666833D02*
X72208Y666625D01*
X72583Y666500D01*
X72917D01*
X73250Y666625D01*
X73500Y666833D01*
X73625Y667125D01*
X73542Y667417D01*
X73333Y667667D01*
X72958Y667833D01*
X72458Y667917D01*
X72167Y668083D01*
X72042Y668375D01*
X72125Y668667D01*
X72333Y668875D01*
X72625Y669000D01*
X72917D01*
X73208Y668917D01*
X73458Y668708D01*
G01X75017Y666500D02*
Y669000D01*
X76058D01*
X76392Y668875D01*
X76600Y668708D01*
X76683Y668375D01*
X76600Y668042D01*
X76350Y667833D01*
X76058Y667708D01*
X75017D01*
G01X76058D02*
X76683Y666500D01*
G01X78950D02*
Y669000D01*
X78450Y668500D01*
G01Y666500D02*
X79450D01*
G01X82050D02*
Y669000D01*
X81550Y668500D01*
G01Y666500D02*
X82550D01*
G01X85650D02*
Y669000D01*
X84108Y667208D01*
X86192D01*
G01X88250Y666500D02*
X88542Y666542D01*
X88875Y666667D01*
X89083Y666875D01*
X89167Y667167D01*
X89083Y667458D01*
X88833Y667708D01*
X88458Y667833D01*
X88042D01*
X87792Y667917D01*
X87583Y668125D01*
X87500Y668417D01*
X87625Y668708D01*
X87917Y668917D01*
X88250Y669000D01*
X88583Y668917D01*
X88875Y668708D01*
X89000Y668417D01*
X88917Y668125D01*
X88708Y667917D01*
X88458Y667833D01*
X88042D01*
X87667Y667708D01*
X87417Y667458D01*
X87333Y667167D01*
X87417Y666875D01*
X87625Y666667D01*
X87958Y666542D01*
X88250Y666500D01*
G01X83950Y643227D02*
Y647227D01*
X76550D01*
G01X110000Y637967D02*
X107500D01*
Y639008D01*
X107625Y639342D01*
X107792Y639550D01*
X108125Y639633D01*
X108458Y639550D01*
X108667Y639300D01*
X108792Y639008D01*
Y637967D01*
G01Y639008D02*
X110000Y639633D01*
G01X109708Y641192D02*
X109917Y641483D01*
X110000Y641817D01*
X109917Y642150D01*
X109667Y642442D01*
X109292Y642650D01*
X108917Y642733D01*
X108458D01*
X108083Y642650D01*
X107750Y642442D01*
X107583Y642192D01*
X107500Y641900D01*
X107583Y641567D01*
X107750Y641317D01*
X108000Y641150D01*
X108333Y641067D01*
X108625Y641150D01*
X108917Y641358D01*
X109083Y641608D01*
X109125Y641900D01*
X109042Y642233D01*
X108833Y642483D01*
X108458Y642733D01*
G01X109708Y644292D02*
X109917Y644583D01*
X110000Y644917D01*
X109917Y645250D01*
X109667Y645542D01*
X109292Y645750D01*
X108917Y645833D01*
X108458D01*
X108083Y645750D01*
X107750Y645542D01*
X107583Y645292D01*
X107500Y645000D01*
X107583Y644667D01*
X107750Y644417D01*
X108000Y644250D01*
X108333Y644167D01*
X108625Y644250D01*
X108917Y644458D01*
X109083Y644708D01*
X109125Y645000D01*
X109042Y645333D01*
X108833Y645583D01*
X108458Y645833D01*
G01X107917Y647308D02*
X107667Y647558D01*
X107542Y647850D01*
X107500Y648183D01*
X107583Y648600D01*
X107792Y648892D01*
X108042Y648975D01*
X108292Y648933D01*
X108500Y648767D01*
X108917Y647933D01*
X109208Y647558D01*
X109625Y647308D01*
X110000Y647225D01*
Y648975D01*
G01X109625Y650283D02*
X109833Y650533D01*
X109958Y650825D01*
X110000Y651200D01*
X109917Y651575D01*
X109750Y651867D01*
X109458Y652075D01*
X109125Y652117D01*
X108792Y652033D01*
X108583Y651825D01*
X108417Y651533D01*
X108375Y651242D01*
X108417Y650950D01*
X108583Y650575D01*
X107500Y650700D01*
Y651825D01*
G01X81589Y634527D02*
X85589D01*
Y641927D01*
G01X88933Y659500D02*
Y657708D01*
X89100Y657333D01*
X89433Y657083D01*
X89850Y657000D01*
X90267Y657083D01*
X90600Y657333D01*
X90767Y657708D01*
Y659500D01*
G01X92158Y659083D02*
X92408Y659333D01*
X92700Y659458D01*
X93033Y659500D01*
X93450Y659417D01*
X93742Y659208D01*
X93825Y658958D01*
X93783Y658708D01*
X93617Y658500D01*
X92783Y658083D01*
X92408Y657792D01*
X92158Y657375D01*
X92075Y657000D01*
X93825D01*
G01X96050D02*
Y659500D01*
X95550Y659000D01*
G01Y657000D02*
X96550D01*
G01X99150Y659500D02*
X98817Y659417D01*
X98567Y659208D01*
X98400Y658958D01*
X98275Y658625D01*
X98233Y658250D01*
X98275Y657875D01*
X98400Y657542D01*
X98567Y657292D01*
X98817Y657083D01*
X99150Y657000D01*
X99483Y657083D01*
X99733Y657292D01*
X99900Y657542D01*
X100025Y657875D01*
X100067Y658250D01*
X100025Y658625D01*
X99900Y658958D01*
X99733Y659208D01*
X99483Y659417D01*
X99150Y659500D01*
G01X87781Y654935D02*
X101181D01*
G01X87781Y644935D02*
Y654935D01*
G01X101181Y644935D02*
X87781D01*
G01X101181Y654935D02*
Y644935D01*
G01X96197Y728507D02*
X96072Y728257D01*
X95989Y727965D01*
Y727632D01*
X96114Y727257D01*
X96322Y726965D01*
X96572Y726757D01*
X96989Y726590D01*
X97364Y726548D01*
X97739Y726632D01*
X97989Y726757D01*
X98239Y727007D01*
X98406Y727298D01*
X98489Y727590D01*
Y727882D01*
X98406Y728173D01*
X98281Y728423D01*
X98114Y728632D01*
G01X97989Y729773D02*
X98281Y730023D01*
X98447Y730357D01*
X98489Y730732D01*
X98447Y731065D01*
X98239Y731398D01*
X97989Y731607D01*
X97739Y731648D01*
X97447Y731565D01*
X97239Y731273D01*
X97156Y730982D01*
Y730607D01*
G01Y730982D02*
X97031Y731232D01*
X96822Y731440D01*
X96572Y731523D01*
X96322Y731440D01*
X96114Y731232D01*
X95989Y730857D01*
X96031Y730482D01*
X96197Y730107D01*
G01X98197Y733082D02*
X98406Y733373D01*
X98489Y733707D01*
X98406Y734040D01*
X98156Y734332D01*
X97781Y734540D01*
X97406Y734623D01*
X96947D01*
X96572Y734540D01*
X96239Y734332D01*
X96072Y734082D01*
X95989Y733790D01*
X96072Y733457D01*
X96239Y733207D01*
X96489Y733040D01*
X96822Y732957D01*
X97114Y733040D01*
X97406Y733248D01*
X97572Y733498D01*
X97614Y733790D01*
X97531Y734123D01*
X97322Y734373D01*
X96947Y734623D01*
G01X95989Y736890D02*
X96072Y736557D01*
X96281Y736307D01*
X96531Y736140D01*
X96864Y736015D01*
X97239Y735973D01*
X97614Y736015D01*
X97947Y736140D01*
X98197Y736307D01*
X98406Y736557D01*
X98489Y736890D01*
X98406Y737223D01*
X98197Y737473D01*
X97947Y737640D01*
X97614Y737765D01*
X97239Y737807D01*
X96864Y737765D01*
X96531Y737640D01*
X96281Y737473D01*
X96072Y737223D01*
X95989Y736890D01*
G01X79200Y754400D02*
X79158Y754067D01*
X78992Y753775D01*
X78742Y753525D01*
X78450Y753358D01*
X78117Y753275D01*
X77783D01*
X77450Y753358D01*
X77158Y753525D01*
X76908Y753775D01*
X76742Y754067D01*
X76700Y754400D01*
X76742Y754733D01*
X76908Y755025D01*
X77158Y755275D01*
X77450Y755442D01*
X77783Y755525D01*
X78117D01*
X78450Y755442D01*
X78742Y755275D01*
X78992Y755025D01*
X79158Y754733D01*
X79200Y754400D01*
G01X78533Y754733D02*
X79200Y755233D01*
G01Y757500D02*
X76700D01*
X77200Y757000D01*
G01X79200D02*
Y758000D01*
G01X78158Y759808D02*
X77867Y760100D01*
X77700Y760350D01*
X77617Y760683D01*
X77700Y760975D01*
X77867Y761183D01*
X78117Y761350D01*
X78408Y761392D01*
X78658Y761350D01*
X78908Y761183D01*
X79117Y760933D01*
X79200Y760642D01*
X79117Y760308D01*
X78867Y760017D01*
X78492Y759850D01*
X78075Y759808D01*
X77533Y759892D01*
X77242Y760017D01*
X76950Y760225D01*
X76742Y760517D01*
X76700Y760808D01*
X76783Y761100D01*
X76992Y761308D01*
G01X102200Y757500D02*
Y771500D01*
G01X89200Y757500D02*
X102200D01*
G01X89200Y771500D02*
Y757500D01*
G01X102200Y771500D02*
X89200D01*
G01X111000Y772900D02*
Y785900D01*
G01X97000Y772900D02*
X111000D01*
G01X97000Y785900D02*
Y772900D01*
G01X89437Y739391D02*
Y741891D01*
X90478D01*
X90812Y741766D01*
X91020Y741599D01*
X91103Y741266D01*
X91020Y740933D01*
X90770Y740724D01*
X90478Y740599D01*
X89437D01*
G01X90478D02*
X91103Y739391D01*
G01X93370D02*
Y741891D01*
X92870Y741391D01*
G01Y739391D02*
X93870D01*
G01X96970D02*
Y741891D01*
X95428Y740099D01*
X97512D01*
G01X98778Y740433D02*
X99070Y740724D01*
X99320Y740891D01*
X99653Y740974D01*
X99945Y740891D01*
X100153Y740724D01*
X100320Y740474D01*
X100362Y740183D01*
X100320Y739933D01*
X100153Y739683D01*
X99903Y739474D01*
X99612Y739391D01*
X99278Y739474D01*
X98987Y739724D01*
X98820Y740099D01*
X98778Y740516D01*
X98862Y741058D01*
X98987Y741349D01*
X99195Y741641D01*
X99487Y741849D01*
X99778Y741891D01*
X100070Y741808D01*
X100278Y741599D01*
G01X101400Y752500D02*
Y756500D01*
X94000D01*
G01X89989Y726757D02*
X87489D01*
Y727798D01*
X87614Y728132D01*
X87781Y728340D01*
X88114Y728423D01*
X88447Y728340D01*
X88656Y728090D01*
X88781Y727798D01*
Y726757D01*
G01Y727798D02*
X89989Y728423D01*
G01X89614Y729773D02*
X89822Y730023D01*
X89947Y730315D01*
X89989Y730690D01*
X89906Y731065D01*
X89739Y731357D01*
X89447Y731565D01*
X89114Y731607D01*
X88781Y731523D01*
X88572Y731315D01*
X88406Y731023D01*
X88364Y730732D01*
X88406Y730440D01*
X88572Y730065D01*
X87489Y730190D01*
Y731315D01*
G01X89614Y732873D02*
X89822Y733123D01*
X89947Y733415D01*
X89989Y733790D01*
X89906Y734165D01*
X89739Y734457D01*
X89447Y734665D01*
X89114Y734707D01*
X88781Y734623D01*
X88572Y734415D01*
X88406Y734123D01*
X88364Y733832D01*
X88406Y733540D01*
X88572Y733165D01*
X87489Y733290D01*
Y734415D01*
G01X89697Y736182D02*
X89906Y736473D01*
X89989Y736807D01*
X89906Y737140D01*
X89656Y737432D01*
X89281Y737640D01*
X88906Y737723D01*
X88447D01*
X88072Y737640D01*
X87739Y737432D01*
X87572Y737182D01*
X87489Y736890D01*
X87572Y736557D01*
X87739Y736307D01*
X87989Y736140D01*
X88322Y736057D01*
X88614Y736140D01*
X88906Y736348D01*
X89072Y736598D01*
X89114Y736890D01*
X89031Y737223D01*
X88822Y737473D01*
X88447Y737723D01*
G01X93200Y752200D02*
X89200D01*
Y744800D01*
G01X94489Y726757D02*
X91989D01*
Y727798D01*
X92114Y728132D01*
X92281Y728340D01*
X92614Y728423D01*
X92947Y728340D01*
X93156Y728090D01*
X93281Y727798D01*
Y726757D01*
G01Y727798D02*
X94489Y728423D01*
G01X94114Y729773D02*
X94322Y730023D01*
X94447Y730315D01*
X94489Y730690D01*
X94406Y731065D01*
X94239Y731357D01*
X93947Y731565D01*
X93614Y731607D01*
X93281Y731523D01*
X93072Y731315D01*
X92906Y731023D01*
X92864Y730732D01*
X92906Y730440D01*
X93072Y730065D01*
X91989Y730190D01*
Y731315D01*
G01X94489Y733707D02*
X93947Y733790D01*
X93489Y733915D01*
X93072Y734082D01*
X92614Y734290D01*
X91989Y734623D01*
Y732957D01*
G01X94489Y737390D02*
X91989D01*
X93781Y735848D01*
Y737932D01*
G01X93700Y744800D02*
X97700D01*
Y752200D01*
G01X73000Y767967D02*
X70500D01*
Y769008D01*
X70625Y769342D01*
X70792Y769550D01*
X71125Y769633D01*
X71458Y769550D01*
X71667Y769300D01*
X71792Y769008D01*
Y767967D01*
G01Y769008D02*
X73000Y769633D01*
G01X72708Y771192D02*
X72917Y771483D01*
X73000Y771817D01*
X72917Y772150D01*
X72667Y772442D01*
X72292Y772650D01*
X71917Y772733D01*
X71458D01*
X71083Y772650D01*
X70750Y772442D01*
X70583Y772192D01*
X70500Y771900D01*
X70583Y771567D01*
X70750Y771317D01*
X71000Y771150D01*
X71333Y771067D01*
X71625Y771150D01*
X71917Y771358D01*
X72083Y771608D01*
X72125Y771900D01*
X72042Y772233D01*
X71833Y772483D01*
X71458Y772733D01*
G01X71958Y774208D02*
X71667Y774500D01*
X71500Y774750D01*
X71417Y775083D01*
X71500Y775375D01*
X71667Y775583D01*
X71917Y775750D01*
X72208Y775792D01*
X72458Y775750D01*
X72708Y775583D01*
X72917Y775333D01*
X73000Y775042D01*
X72917Y774708D01*
X72667Y774417D01*
X72292Y774250D01*
X71875Y774208D01*
X71333Y774292D01*
X71042Y774417D01*
X70750Y774625D01*
X70542Y774917D01*
X70500Y775208D01*
X70583Y775500D01*
X70792Y775708D01*
G01X73000Y778100D02*
X70500D01*
X71000Y777600D01*
G01X73000D02*
Y778600D01*
G01X72708Y780492D02*
X72917Y780783D01*
X73000Y781117D01*
X72917Y781450D01*
X72667Y781742D01*
X72292Y781950D01*
X71917Y782033D01*
X71458D01*
X71083Y781950D01*
X70750Y781742D01*
X70583Y781492D01*
X70500Y781200D01*
X70583Y780867D01*
X70750Y780617D01*
X71000Y780450D01*
X71333Y780367D01*
X71625Y780450D01*
X71917Y780658D01*
X72083Y780908D01*
X72125Y781200D01*
X72042Y781533D01*
X71833Y781783D01*
X71458Y782033D01*
G01X88000Y772800D02*
X92000D01*
Y780200D01*
G01X77000Y767967D02*
X74500D01*
Y769008D01*
X74625Y769342D01*
X74792Y769550D01*
X75125Y769633D01*
X75458Y769550D01*
X75667Y769300D01*
X75792Y769008D01*
Y767967D01*
G01Y769008D02*
X77000Y769633D01*
G01X76708Y771192D02*
X76917Y771483D01*
X77000Y771817D01*
X76917Y772150D01*
X76667Y772442D01*
X76292Y772650D01*
X75917Y772733D01*
X75458D01*
X75083Y772650D01*
X74750Y772442D01*
X74583Y772192D01*
X74500Y771900D01*
X74583Y771567D01*
X74750Y771317D01*
X75000Y771150D01*
X75333Y771067D01*
X75625Y771150D01*
X75917Y771358D01*
X76083Y771608D01*
X76125Y771900D01*
X76042Y772233D01*
X75833Y772483D01*
X75458Y772733D01*
G01X77000Y774917D02*
X76458Y775000D01*
X76000Y775125D01*
X75583Y775292D01*
X75125Y775500D01*
X74500Y775833D01*
Y774167D01*
G01X75958Y777308D02*
X75667Y777600D01*
X75500Y777850D01*
X75417Y778183D01*
X75500Y778475D01*
X75667Y778683D01*
X75917Y778850D01*
X76208Y778892D01*
X76458Y778850D01*
X76708Y778683D01*
X76917Y778433D01*
X77000Y778142D01*
X76917Y777808D01*
X76667Y777517D01*
X76292Y777350D01*
X75875Y777308D01*
X75333Y777392D01*
X75042Y777517D01*
X74750Y777725D01*
X74542Y778017D01*
X74500Y778308D01*
X74583Y778600D01*
X74792Y778808D01*
G01X77000Y781200D02*
X76958Y781492D01*
X76833Y781825D01*
X76625Y782033D01*
X76333Y782117D01*
X76042Y782033D01*
X75792Y781783D01*
X75667Y781408D01*
Y780992D01*
X75583Y780742D01*
X75375Y780533D01*
X75083Y780450D01*
X74792Y780575D01*
X74583Y780867D01*
X74500Y781200D01*
X74583Y781533D01*
X74792Y781825D01*
X75083Y781950D01*
X75375Y781867D01*
X75583Y781658D01*
X75667Y781408D01*
Y780992D01*
X75792Y780617D01*
X76042Y780367D01*
X76333Y780283D01*
X76625Y780367D01*
X76833Y780575D01*
X76958Y780908D01*
X77000Y781200D01*
G01X96500Y780200D02*
X92500D01*
Y772800D01*
G01X108167Y723975D02*
X108375Y724308D01*
X108500Y724683D01*
Y725017D01*
X108375Y725350D01*
X108167Y725600D01*
X107875Y725725D01*
X107583Y725642D01*
X107333Y725433D01*
X107167Y725058D01*
X107083Y724558D01*
X106917Y724267D01*
X106625Y724142D01*
X106333Y724225D01*
X106125Y724433D01*
X106000Y724725D01*
Y725017D01*
X106083Y725308D01*
X106292Y725558D01*
G01X108500Y727117D02*
X106000D01*
Y728158D01*
X106125Y728492D01*
X106292Y728700D01*
X106625Y728783D01*
X106958Y728700D01*
X107167Y728450D01*
X107292Y728158D01*
Y727117D01*
G01Y728158D02*
X108500Y728783D01*
G01Y731050D02*
X106000D01*
X106500Y730550D01*
G01X108500D02*
Y731550D01*
G01Y734150D02*
X106000D01*
X106500Y733650D01*
G01X108500D02*
Y734650D01*
G01X106000Y737250D02*
X106083Y736917D01*
X106292Y736667D01*
X106542Y736500D01*
X106875Y736375D01*
X107250Y736333D01*
X107625Y736375D01*
X107958Y736500D01*
X108208Y736667D01*
X108417Y736917D01*
X108500Y737250D01*
X108417Y737583D01*
X108208Y737833D01*
X107958Y738000D01*
X107625Y738125D01*
X107250Y738167D01*
X106875Y738125D01*
X106542Y738000D01*
X106292Y737833D01*
X106083Y737583D01*
X106000Y737250D01*
G01X108500Y740267D02*
X107958Y740350D01*
X107500Y740475D01*
X107083Y740642D01*
X106625Y740850D01*
X106000Y741183D01*
Y739517D01*
G01X112667Y723975D02*
X112875Y724308D01*
X113000Y724683D01*
Y725017D01*
X112875Y725350D01*
X112667Y725600D01*
X112375Y725725D01*
X112083Y725642D01*
X111833Y725433D01*
X111667Y725058D01*
X111583Y724558D01*
X111417Y724267D01*
X111125Y724142D01*
X110833Y724225D01*
X110625Y724433D01*
X110500Y724725D01*
Y725017D01*
X110583Y725308D01*
X110792Y725558D01*
G01X113000Y727117D02*
X110500D01*
Y728158D01*
X110625Y728492D01*
X110792Y728700D01*
X111125Y728783D01*
X111458Y728700D01*
X111667Y728450D01*
X111792Y728158D01*
Y727117D01*
G01Y728158D02*
X113000Y728783D01*
G01Y731050D02*
X110500D01*
X111000Y730550D01*
G01X113000D02*
Y731550D01*
G01Y734150D02*
X110500D01*
X111000Y733650D01*
G01X113000D02*
Y734650D01*
G01X110500Y737250D02*
X110583Y736917D01*
X110792Y736667D01*
X111042Y736500D01*
X111375Y736375D01*
X111750Y736333D01*
X112125Y736375D01*
X112458Y736500D01*
X112708Y736667D01*
X112917Y736917D01*
X113000Y737250D01*
X112917Y737583D01*
X112708Y737833D01*
X112458Y738000D01*
X112125Y738125D01*
X111750Y738167D01*
X111375Y738125D01*
X111042Y738000D01*
X110792Y737833D01*
X110583Y737583D01*
X110500Y737250D01*
G01X113000Y740350D02*
X112958Y740642D01*
X112833Y740975D01*
X112625Y741183D01*
X112333Y741267D01*
X112042Y741183D01*
X111792Y740933D01*
X111667Y740558D01*
Y740142D01*
X111583Y739892D01*
X111375Y739683D01*
X111083Y739600D01*
X110792Y739725D01*
X110583Y740017D01*
X110500Y740350D01*
X110583Y740683D01*
X110792Y740975D01*
X111083Y741100D01*
X111375Y741017D01*
X111583Y740808D01*
X111667Y740558D01*
Y740142D01*
X111792Y739767D01*
X112042Y739517D01*
X112333Y739433D01*
X112625Y739517D01*
X112833Y739725D01*
X112958Y740058D01*
X113000Y740350D01*
G01X74834Y753983D02*
X72334D01*
Y754817D01*
X72459Y755150D01*
X72626Y755400D01*
X72876Y755608D01*
X73167Y755775D01*
X73584Y755817D01*
X74001Y755775D01*
X74292Y755608D01*
X74542Y755400D01*
X74709Y755150D01*
X74834Y754817D01*
Y753983D01*
G01X72751Y757208D02*
X72501Y757458D01*
X72376Y757750D01*
X72334Y758083D01*
X72417Y758500D01*
X72626Y758792D01*
X72876Y758875D01*
X73126Y758833D01*
X73334Y758667D01*
X73751Y757833D01*
X74042Y757458D01*
X74459Y757208D01*
X74834Y757125D01*
Y758875D01*
G01X73792Y760308D02*
X73501Y760600D01*
X73334Y760850D01*
X73251Y761183D01*
X73334Y761475D01*
X73501Y761683D01*
X73751Y761850D01*
X74042Y761892D01*
X74292Y761850D01*
X74542Y761683D01*
X74751Y761433D01*
X74834Y761142D01*
X74751Y760808D01*
X74501Y760517D01*
X74126Y760350D01*
X73709Y760308D01*
X73167Y760392D01*
X72876Y760517D01*
X72584Y760725D01*
X72376Y761017D01*
X72334Y761308D01*
X72417Y761600D01*
X72626Y761808D01*
G01X81200Y749500D02*
Y765600D01*
G01X88200Y749500D02*
X81200D01*
G01X88200Y765600D02*
Y749500D01*
G01X81200Y765600D02*
X88200D01*
G01X111417Y816000D02*
Y818500D01*
X112417D01*
X112750Y818375D01*
X113000Y818083D01*
X113083Y817750D01*
X113000Y817417D01*
X112792Y817167D01*
X112417Y817042D01*
X111417D01*
G01X116267Y818292D02*
X116017Y818417D01*
X115725Y818500D01*
X115392D01*
X115017Y818375D01*
X114725Y818167D01*
X114517Y817917D01*
X114350Y817500D01*
X114308Y817125D01*
X114392Y816750D01*
X114517Y816500D01*
X114767Y816250D01*
X115058Y816083D01*
X115350Y816000D01*
X115642D01*
X115933Y816083D01*
X116183Y816208D01*
X116392Y816375D01*
G01X118450Y816000D02*
Y818500D01*
X117950Y818000D01*
G01Y816000D02*
X118950D01*
G01X120758Y818083D02*
X121008Y818333D01*
X121300Y818458D01*
X121633Y818500D01*
X122050Y818417D01*
X122342Y818208D01*
X122425Y817958D01*
X122383Y817708D01*
X122217Y817500D01*
X121383Y817083D01*
X121008Y816792D01*
X120758Y816375D01*
X120675Y816000D01*
X122425D01*
G01X123733Y816375D02*
X123983Y816167D01*
X124275Y816042D01*
X124650Y816000D01*
X125025Y816083D01*
X125317Y816250D01*
X125525Y816542D01*
X125567Y816875D01*
X125483Y817208D01*
X125275Y817417D01*
X124983Y817583D01*
X124692Y817625D01*
X124400Y817583D01*
X124025Y817417D01*
X124150Y818500D01*
X125275D01*
G01X126958Y818083D02*
X127208Y818333D01*
X127500Y818458D01*
X127833Y818500D01*
X128250Y818417D01*
X128542Y818208D01*
X128625Y817958D01*
X128583Y817708D01*
X128417Y817500D01*
X127583Y817083D01*
X127208Y816792D01*
X126958Y816375D01*
X126875Y816000D01*
X128625D01*
G01X95900Y787000D02*
X95567Y787042D01*
X95275Y787208D01*
X95025Y787458D01*
X94858Y787750D01*
X94775Y788083D01*
Y788417D01*
X94858Y788750D01*
X95025Y789042D01*
X95275Y789292D01*
X95567Y789458D01*
X95900Y789500D01*
X96233Y789458D01*
X96525Y789292D01*
X96775Y789042D01*
X96942Y788750D01*
X97025Y788417D01*
Y788083D01*
X96942Y787750D01*
X96775Y787458D01*
X96525Y787208D01*
X96233Y787042D01*
X95900Y787000D01*
G01X96233Y787667D02*
X96733Y787000D01*
G01X98208Y788042D02*
X98500Y788333D01*
X98750Y788500D01*
X99083Y788583D01*
X99375Y788500D01*
X99583Y788333D01*
X99750Y788083D01*
X99792Y787792D01*
X99750Y787542D01*
X99583Y787292D01*
X99333Y787083D01*
X99042Y787000D01*
X98708Y787083D01*
X98417Y787333D01*
X98250Y787708D01*
X98208Y788125D01*
X98292Y788667D01*
X98417Y788958D01*
X98625Y789250D01*
X98917Y789458D01*
X99208Y789500D01*
X99500Y789417D01*
X99708Y789208D01*
G01X101308Y788042D02*
X101600Y788333D01*
X101850Y788500D01*
X102183Y788583D01*
X102475Y788500D01*
X102683Y788333D01*
X102850Y788083D01*
X102892Y787792D01*
X102850Y787542D01*
X102683Y787292D01*
X102433Y787083D01*
X102142Y787000D01*
X101808Y787083D01*
X101517Y787333D01*
X101350Y787708D01*
X101308Y788125D01*
X101392Y788667D01*
X101517Y788958D01*
X101725Y789250D01*
X102017Y789458D01*
X102308Y789500D01*
X102600Y789417D01*
X102808Y789208D01*
G01X111000Y785900D02*
X97000D01*
G01X70067Y786800D02*
Y789300D01*
X71108D01*
X71442Y789175D01*
X71650Y789008D01*
X71733Y788675D01*
X71650Y788342D01*
X71400Y788133D01*
X71108Y788008D01*
X70067D01*
G01X71108D02*
X71733Y786800D01*
G01X73292Y787092D02*
X73583Y786883D01*
X73917Y786800D01*
X74250Y786883D01*
X74542Y787133D01*
X74750Y787508D01*
X74833Y787883D01*
Y788342D01*
X74750Y788717D01*
X74542Y789050D01*
X74292Y789217D01*
X74000Y789300D01*
X73667Y789217D01*
X73417Y789050D01*
X73250Y788800D01*
X73167Y788467D01*
X73250Y788175D01*
X73458Y787883D01*
X73708Y787717D01*
X74000Y787675D01*
X74333Y787758D01*
X74583Y787967D01*
X74833Y788342D01*
G01X77100Y786800D02*
X77392Y786842D01*
X77725Y786967D01*
X77933Y787175D01*
X78017Y787467D01*
X77933Y787758D01*
X77683Y788008D01*
X77308Y788133D01*
X76892D01*
X76642Y788217D01*
X76433Y788425D01*
X76350Y788717D01*
X76475Y789008D01*
X76767Y789217D01*
X77100Y789300D01*
X77433Y789217D01*
X77725Y789008D01*
X77850Y788717D01*
X77767Y788425D01*
X77558Y788217D01*
X77308Y788133D01*
X76892D01*
X76517Y788008D01*
X76267Y787758D01*
X76183Y787467D01*
X76267Y787175D01*
X76475Y786967D01*
X76808Y786842D01*
X77100Y786800D01*
G01X79283Y787300D02*
X79533Y787008D01*
X79867Y786842D01*
X80242Y786800D01*
X80575Y786842D01*
X80908Y787050D01*
X81117Y787300D01*
X81158Y787550D01*
X81075Y787842D01*
X80783Y788050D01*
X80492Y788133D01*
X80117D01*
G01X80492D02*
X80742Y788258D01*
X80950Y788467D01*
X81033Y788717D01*
X80950Y788967D01*
X80742Y789175D01*
X80367Y789300D01*
X79992Y789258D01*
X79617Y789092D01*
G01X82383Y787300D02*
X82633Y787008D01*
X82967Y786842D01*
X83342Y786800D01*
X83675Y786842D01*
X84008Y787050D01*
X84217Y787300D01*
X84258Y787550D01*
X84175Y787842D01*
X83883Y788050D01*
X83592Y788133D01*
X83217D01*
G01X83592D02*
X83842Y788258D01*
X84050Y788467D01*
X84133Y788717D01*
X84050Y788967D01*
X83842Y789175D01*
X83467Y789300D01*
X83092Y789258D01*
X82717Y789092D01*
G01X83475Y785275D02*
Y781275D01*
X90875D01*
G01X106467Y787000D02*
Y789500D01*
X107508D01*
X107842Y789375D01*
X108050Y789208D01*
X108133Y788875D01*
X108050Y788542D01*
X107800Y788333D01*
X107508Y788208D01*
X106467D01*
G01X107508D02*
X108133Y787000D01*
G01X109692Y787292D02*
X109983Y787083D01*
X110317Y787000D01*
X110650Y787083D01*
X110942Y787333D01*
X111150Y787708D01*
X111233Y788083D01*
Y788542D01*
X111150Y788917D01*
X110942Y789250D01*
X110692Y789417D01*
X110400Y789500D01*
X110067Y789417D01*
X109817Y789250D01*
X109650Y789000D01*
X109567Y788667D01*
X109650Y788375D01*
X109858Y788083D01*
X110108Y787917D01*
X110400Y787875D01*
X110733Y787958D01*
X110983Y788167D01*
X111233Y788542D01*
G01X113500Y787000D02*
X113792Y787042D01*
X114125Y787167D01*
X114333Y787375D01*
X114417Y787667D01*
X114333Y787958D01*
X114083Y788208D01*
X113708Y788333D01*
X113292D01*
X113042Y788417D01*
X112833Y788625D01*
X112750Y788917D01*
X112875Y789208D01*
X113167Y789417D01*
X113500Y789500D01*
X113833Y789417D01*
X114125Y789208D01*
X114250Y788917D01*
X114167Y788625D01*
X113958Y788417D01*
X113708Y788333D01*
X113292D01*
X112917Y788208D01*
X112667Y787958D01*
X112583Y787667D01*
X112667Y787375D01*
X112875Y787167D01*
X113208Y787042D01*
X113500Y787000D01*
G01X115683Y787500D02*
X115933Y787208D01*
X116267Y787042D01*
X116642Y787000D01*
X116975Y787042D01*
X117308Y787250D01*
X117517Y787500D01*
X117558Y787750D01*
X117475Y788042D01*
X117183Y788250D01*
X116892Y788333D01*
X116517D01*
G01X116892D02*
X117142Y788458D01*
X117350Y788667D01*
X117433Y788917D01*
X117350Y789167D01*
X117142Y789375D01*
X116767Y789500D01*
X116392Y789458D01*
X116017Y789292D01*
G01X120200Y787000D02*
Y789500D01*
X118658Y787708D01*
X120742D01*
G01X97717Y793000D02*
Y795500D01*
X98758D01*
X99092Y795375D01*
X99300Y795208D01*
X99383Y794875D01*
X99300Y794542D01*
X99050Y794333D01*
X98758Y794208D01*
X97717D01*
G01X98758D02*
X99383Y793000D01*
G01X100942Y793292D02*
X101233Y793083D01*
X101567Y793000D01*
X101900Y793083D01*
X102192Y793333D01*
X102400Y793708D01*
X102483Y794083D01*
Y794542D01*
X102400Y794917D01*
X102192Y795250D01*
X101942Y795417D01*
X101650Y795500D01*
X101317Y795417D01*
X101067Y795250D01*
X100900Y795000D01*
X100817Y794667D01*
X100900Y794375D01*
X101108Y794083D01*
X101358Y793917D01*
X101650Y793875D01*
X101983Y793958D01*
X102233Y794167D01*
X102483Y794542D01*
G01X104750Y793000D02*
X105042Y793042D01*
X105375Y793167D01*
X105583Y793375D01*
X105667Y793667D01*
X105583Y793958D01*
X105333Y794208D01*
X104958Y794333D01*
X104542D01*
X104292Y794417D01*
X104083Y794625D01*
X104000Y794917D01*
X104125Y795208D01*
X104417Y795417D01*
X104750Y795500D01*
X105083Y795417D01*
X105375Y795208D01*
X105500Y794917D01*
X105417Y794625D01*
X105208Y794417D01*
X104958Y794333D01*
X104542D01*
X104167Y794208D01*
X103917Y793958D01*
X103833Y793667D01*
X103917Y793375D01*
X104125Y793167D01*
X104458Y793042D01*
X104750Y793000D01*
G01X106933Y793375D02*
X107183Y793167D01*
X107475Y793042D01*
X107850Y793000D01*
X108225Y793083D01*
X108517Y793250D01*
X108725Y793542D01*
X108767Y793875D01*
X108683Y794208D01*
X108475Y794417D01*
X108183Y794583D01*
X107892Y794625D01*
X107600Y794583D01*
X107225Y794417D01*
X107350Y795500D01*
X108475D01*
G01X110950Y793000D02*
X111242Y793042D01*
X111575Y793167D01*
X111783Y793375D01*
X111867Y793667D01*
X111783Y793958D01*
X111533Y794208D01*
X111158Y794333D01*
X110742D01*
X110492Y794417D01*
X110283Y794625D01*
X110200Y794917D01*
X110325Y795208D01*
X110617Y795417D01*
X110950Y795500D01*
X111283Y795417D01*
X111575Y795208D01*
X111700Y794917D01*
X111617Y794625D01*
X111408Y794417D01*
X111158Y794333D01*
X110742D01*
X110367Y794208D01*
X110117Y793958D01*
X110033Y793667D01*
X110117Y793375D01*
X110325Y793167D01*
X110658Y793042D01*
X110950Y793000D01*
G01X94700Y809200D02*
X99900D01*
G01X94700Y802200D02*
X102500D01*
G01X94700Y809200D02*
Y802200D01*
G01X108100Y809200D02*
X99400D01*
G01X108100Y802200D02*
Y809200D01*
G01X101700Y802200D02*
X108100D01*
G01X70467Y798500D02*
Y801000D01*
X71508D01*
X71842Y800875D01*
X72050Y800708D01*
X72133Y800375D01*
X72050Y800042D01*
X71800Y799833D01*
X71508Y799708D01*
X70467D01*
G01X71508D02*
X72133Y798500D01*
G01X73692Y798792D02*
X73983Y798583D01*
X74317Y798500D01*
X74650Y798583D01*
X74942Y798833D01*
X75150Y799208D01*
X75233Y799583D01*
Y800042D01*
X75150Y800417D01*
X74942Y800750D01*
X74692Y800917D01*
X74400Y801000D01*
X74067Y800917D01*
X73817Y800750D01*
X73650Y800500D01*
X73567Y800167D01*
X73650Y799875D01*
X73858Y799583D01*
X74108Y799417D01*
X74400Y799375D01*
X74733Y799458D01*
X74983Y799667D01*
X75233Y800042D01*
G01X76708Y800583D02*
X76958Y800833D01*
X77250Y800958D01*
X77583Y801000D01*
X78000Y800917D01*
X78292Y800708D01*
X78375Y800458D01*
X78333Y800208D01*
X78167Y800000D01*
X77333Y799583D01*
X76958Y799292D01*
X76708Y798875D01*
X76625Y798500D01*
X78375D01*
G01X79683Y798875D02*
X79933Y798667D01*
X80225Y798542D01*
X80600Y798500D01*
X80975Y798583D01*
X81267Y798750D01*
X81475Y799042D01*
X81517Y799375D01*
X81433Y799708D01*
X81225Y799917D01*
X80933Y800083D01*
X80642Y800125D01*
X80350Y800083D01*
X79975Y799917D01*
X80100Y801000D01*
X81225D01*
G01X82908Y800583D02*
X83158Y800833D01*
X83450Y800958D01*
X83783Y801000D01*
X84200Y800917D01*
X84492Y800708D01*
X84575Y800458D01*
X84533Y800208D01*
X84367Y800000D01*
X83533Y799583D01*
X83158Y799292D01*
X82908Y798875D01*
X82825Y798500D01*
X84575D01*
G01X66400Y819700D02*
Y806700D01*
G01X92400Y819700D02*
X66400D01*
G01X92400Y806700D02*
Y819700D01*
G01X66400Y806700D02*
X92400D01*
G01X86917Y798500D02*
Y801000D01*
X87917D01*
X88250Y800875D01*
X88500Y800583D01*
X88583Y800250D01*
X88500Y799917D01*
X88292Y799667D01*
X87917Y799542D01*
X86917D01*
G01X91767Y800792D02*
X91517Y800917D01*
X91225Y801000D01*
X90892D01*
X90517Y800875D01*
X90225Y800667D01*
X90017Y800417D01*
X89850Y800000D01*
X89808Y799625D01*
X89892Y799250D01*
X90017Y799000D01*
X90267Y798750D01*
X90558Y798583D01*
X90850Y798500D01*
X91142D01*
X91433Y798583D01*
X91683Y798708D01*
X91892Y798875D01*
G01X93950Y798500D02*
Y801000D01*
X93450Y800500D01*
G01Y798500D02*
X94450D01*
G01X96258Y800583D02*
X96508Y800833D01*
X96800Y800958D01*
X97133Y801000D01*
X97550Y800917D01*
X97842Y800708D01*
X97925Y800458D01*
X97883Y800208D01*
X97717Y800000D01*
X96883Y799583D01*
X96508Y799292D01*
X96258Y798875D01*
X96175Y798500D01*
X97925D01*
G01X99233Y798875D02*
X99483Y798667D01*
X99775Y798542D01*
X100150Y798500D01*
X100525Y798583D01*
X100817Y798750D01*
X101025Y799042D01*
X101067Y799375D01*
X100983Y799708D01*
X100775Y799917D01*
X100483Y800083D01*
X100192Y800125D01*
X99900Y800083D01*
X99525Y799917D01*
X99650Y801000D01*
X100775D01*
G01X103250D02*
X102917Y800917D01*
X102667Y800708D01*
X102500Y800458D01*
X102375Y800125D01*
X102333Y799750D01*
X102375Y799375D01*
X102500Y799042D01*
X102667Y798792D01*
X102917Y798583D01*
X103250Y798500D01*
X103583Y798583D01*
X103833Y798792D01*
X104000Y799042D01*
X104125Y799375D01*
X104167Y799750D01*
X104125Y800125D01*
X104000Y800458D01*
X103833Y800708D01*
X103583Y800917D01*
X103250Y801000D01*
G01X95050Y812350D02*
Y831050D01*
X105350D01*
Y812350D01*
X95050D01*
G01X111450Y850450D02*
Y831750D01*
X101150D01*
Y850450D01*
X111450D01*
G01X102000Y917567D02*
X102250Y917775D01*
X102417Y918025D01*
X102500Y918317D01*
X102417Y918650D01*
X102250Y918900D01*
X102000Y919150D01*
X101667Y919233D01*
X100000D01*
G01X102500Y921500D02*
X100000D01*
X100500Y921000D01*
G01X102500D02*
Y922000D01*
G01X100417Y923808D02*
X100167Y924058D01*
X100042Y924350D01*
X100000Y924683D01*
X100083Y925100D01*
X100292Y925392D01*
X100542Y925475D01*
X100792Y925433D01*
X101000Y925267D01*
X101417Y924433D01*
X101708Y924058D01*
X102125Y923808D01*
X102500Y923725D01*
Y925475D01*
G01X105500Y852317D02*
X103000D01*
Y853317D01*
X103125Y853650D01*
X103417Y853900D01*
X103750Y853983D01*
X104083Y853900D01*
X104333Y853692D01*
X104458Y853317D01*
Y852317D01*
G01X103208Y857167D02*
X103083Y856917D01*
X103000Y856625D01*
Y856292D01*
X103125Y855917D01*
X103333Y855625D01*
X103583Y855417D01*
X104000Y855250D01*
X104375Y855208D01*
X104750Y855292D01*
X105000Y855417D01*
X105250Y855667D01*
X105417Y855958D01*
X105500Y856250D01*
Y856542D01*
X105417Y856833D01*
X105292Y857083D01*
X105125Y857292D01*
G01X105500Y859350D02*
X103000D01*
X103500Y858850D01*
G01X105500D02*
Y859850D01*
G01X103417Y861658D02*
X103167Y861908D01*
X103042Y862200D01*
X103000Y862533D01*
X103083Y862950D01*
X103292Y863242D01*
X103542Y863325D01*
X103792Y863283D01*
X104000Y863117D01*
X104417Y862283D01*
X104708Y861908D01*
X105125Y861658D01*
X105500Y861575D01*
Y863325D01*
G01X105125Y864633D02*
X105333Y864883D01*
X105458Y865175D01*
X105500Y865550D01*
X105417Y865925D01*
X105250Y866217D01*
X104958Y866425D01*
X104625Y866467D01*
X104292Y866383D01*
X104083Y866175D01*
X103917Y865883D01*
X103875Y865592D01*
X103917Y865300D01*
X104083Y864925D01*
X103000Y865050D01*
Y866175D01*
G01X105000Y867733D02*
X105292Y867983D01*
X105458Y868317D01*
X105500Y868692D01*
X105458Y869025D01*
X105250Y869358D01*
X105000Y869567D01*
X104750Y869608D01*
X104458Y869525D01*
X104250Y869233D01*
X104167Y868942D01*
Y868567D01*
G01Y868942D02*
X104042Y869192D01*
X103833Y869400D01*
X103583Y869483D01*
X103333Y869400D01*
X103125Y869192D01*
X103000Y868817D01*
X103042Y868442D01*
X103208Y868067D01*
G01X112800Y852217D02*
X110300D01*
Y853217D01*
X110425Y853550D01*
X110717Y853800D01*
X111050Y853883D01*
X111383Y853800D01*
X111633Y853592D01*
X111758Y853217D01*
Y852217D01*
G01X110508Y857067D02*
X110383Y856817D01*
X110300Y856525D01*
Y856192D01*
X110425Y855817D01*
X110633Y855525D01*
X110883Y855317D01*
X111300Y855150D01*
X111675Y855108D01*
X112050Y855192D01*
X112300Y855317D01*
X112550Y855567D01*
X112717Y855858D01*
X112800Y856150D01*
Y856442D01*
X112717Y856733D01*
X112592Y856983D01*
X112425Y857192D01*
G01X112800Y859250D02*
X110300D01*
X110800Y858750D01*
G01X112800D02*
Y859750D01*
G01X110717Y861558D02*
X110467Y861808D01*
X110342Y862100D01*
X110300Y862433D01*
X110383Y862850D01*
X110592Y863142D01*
X110842Y863225D01*
X111092Y863183D01*
X111300Y863017D01*
X111717Y862183D01*
X112008Y861808D01*
X112425Y861558D01*
X112800Y861475D01*
Y863225D01*
G01X112425Y864533D02*
X112633Y864783D01*
X112758Y865075D01*
X112800Y865450D01*
X112717Y865825D01*
X112550Y866117D01*
X112258Y866325D01*
X111925Y866367D01*
X111592Y866283D01*
X111383Y866075D01*
X111217Y865783D01*
X111175Y865492D01*
X111217Y865200D01*
X111383Y864825D01*
X110300Y864950D01*
Y866075D01*
G01X112800Y868550D02*
X110300D01*
X110800Y868050D01*
G01X112800D02*
Y869050D01*
G01X106000Y938417D02*
X103500D01*
Y939417D01*
X103625Y939750D01*
X103917Y940000D01*
X104250Y940083D01*
X104583Y940000D01*
X104833Y939792D01*
X104958Y939417D01*
Y938417D01*
G01X103708Y943267D02*
X103583Y943017D01*
X103500Y942725D01*
Y942392D01*
X103625Y942017D01*
X103833Y941725D01*
X104083Y941517D01*
X104500Y941350D01*
X104875Y941308D01*
X105250Y941392D01*
X105500Y941517D01*
X105750Y941767D01*
X105917Y942058D01*
X106000Y942350D01*
Y942642D01*
X105917Y942933D01*
X105792Y943183D01*
X105625Y943392D01*
G01X106000Y945450D02*
X103500D01*
X104000Y944950D01*
G01X106000D02*
Y945950D01*
G01X103917Y947758D02*
X103667Y948008D01*
X103542Y948300D01*
X103500Y948633D01*
X103583Y949050D01*
X103792Y949342D01*
X104042Y949425D01*
X104292Y949383D01*
X104500Y949217D01*
X104917Y948383D01*
X105208Y948008D01*
X105625Y947758D01*
X106000Y947675D01*
Y949425D01*
G01X105625Y950733D02*
X105833Y950983D01*
X105958Y951275D01*
X106000Y951650D01*
X105917Y952025D01*
X105750Y952317D01*
X105458Y952525D01*
X105125Y952567D01*
X104792Y952483D01*
X104583Y952275D01*
X104417Y951983D01*
X104375Y951692D01*
X104417Y951400D01*
X104583Y951025D01*
X103500Y951150D01*
Y952275D01*
G01X106000Y955250D02*
X103500D01*
X105292Y953708D01*
Y955792D01*
G01X83775Y997333D02*
X84108Y997125D01*
X84483Y997000D01*
X84817D01*
X85150Y997125D01*
X85400Y997333D01*
X85525Y997625D01*
X85442Y997917D01*
X85233Y998167D01*
X84858Y998333D01*
X84358Y998417D01*
X84067Y998583D01*
X83942Y998875D01*
X84025Y999167D01*
X84233Y999375D01*
X84525Y999500D01*
X84817D01*
X85108Y999417D01*
X85358Y999208D01*
G01X86833Y997000D02*
Y999500D01*
X87667D01*
X88000Y999375D01*
X88250Y999208D01*
X88458Y998958D01*
X88625Y998667D01*
X88667Y998250D01*
X88625Y997833D01*
X88458Y997542D01*
X88250Y997292D01*
X88000Y997125D01*
X87667Y997000D01*
X86833D01*
G01X89933D02*
Y999500D01*
X90767D01*
X91100Y999375D01*
X91350Y999208D01*
X91558Y998958D01*
X91725Y998667D01*
X91767Y998250D01*
X91725Y997833D01*
X91558Y997542D01*
X91350Y997292D01*
X91100Y997125D01*
X90767Y997000D01*
X89933D01*
G01X96008D02*
X97050Y999500D01*
X98092Y997000D01*
G01X97717Y997875D02*
X96383D01*
G01X101067Y999292D02*
X100817Y999417D01*
X100525Y999500D01*
X100192D01*
X99817Y999375D01*
X99525Y999167D01*
X99317Y998917D01*
X99150Y998500D01*
X99108Y998125D01*
X99192Y997750D01*
X99317Y997500D01*
X99567Y997250D01*
X99858Y997083D01*
X100150Y997000D01*
X100442D01*
X100733Y997083D01*
X100983Y997208D01*
X101192Y997375D01*
G01X103250Y999500D02*
Y997000D01*
G01X102292Y999500D02*
X104208D01*
G01X106350Y997000D02*
Y999500D01*
X105850Y999000D01*
G01Y997000D02*
X106850D01*
G01X108658Y999083D02*
X108908Y999333D01*
X109200Y999458D01*
X109533Y999500D01*
X109950Y999417D01*
X110242Y999208D01*
X110325Y998958D01*
X110283Y998708D01*
X110117Y998500D01*
X109283Y998083D01*
X108908Y997792D01*
X108658Y997375D01*
X108575Y997000D01*
X110325D01*
G01X84117Y1001400D02*
Y1003900D01*
X85117D01*
X85450Y1003775D01*
X85700Y1003483D01*
X85783Y1003150D01*
X85700Y1002817D01*
X85492Y1002567D01*
X85117Y1002442D01*
X84117D01*
G01X88883Y1001400D02*
X87217D01*
Y1003900D01*
X88883D01*
G01X88217Y1002692D02*
X87217D01*
G01X91483Y1002733D02*
X91650Y1002858D01*
X91775Y1003067D01*
X91858Y1003358D01*
X91775Y1003608D01*
X91608Y1003775D01*
X91317Y1003900D01*
X90192D01*
Y1001400D01*
X91567D01*
X91858Y1001567D01*
X92025Y1001817D01*
X92108Y1002108D01*
X92025Y1002400D01*
X91775Y1002650D01*
X91483Y1002733D01*
X90192D01*
G01X96308Y1001400D02*
X97350Y1003900D01*
X98392Y1001400D01*
G01X98017Y1002275D02*
X96683D01*
G01X100450Y1003900D02*
Y1001400D01*
G01X99492Y1003900D02*
X101408D01*
G01X103550D02*
Y1001400D01*
G01X102592Y1003900D02*
X104508D01*
G01X105692Y1001400D02*
Y1003900D01*
X107608Y1001400D01*
Y1003900D01*
G01X109750Y1001400D02*
Y1003900D01*
X109250Y1003400D01*
G01Y1001400D02*
X110250D01*
G01X112058Y1003483D02*
X112308Y1003733D01*
X112600Y1003858D01*
X112933Y1003900D01*
X113350Y1003817D01*
X113642Y1003608D01*
X113725Y1003358D01*
X113683Y1003108D01*
X113517Y1002900D01*
X112683Y1002483D01*
X112308Y1002192D01*
X112058Y1001775D01*
X111975Y1001400D01*
X113725D01*
G01X69967Y1013667D02*
Y1011167D01*
X71633D01*
G01X74733D02*
X73067D01*
Y1013667D01*
X74733D01*
G01X74067Y1012459D02*
X73067D01*
G01X76083Y1011167D02*
Y1013667D01*
X76917D01*
X77250Y1013542D01*
X77500Y1013375D01*
X77708Y1013125D01*
X77875Y1012834D01*
X77917Y1012417D01*
X77875Y1012000D01*
X77708Y1011709D01*
X77500Y1011459D01*
X77250Y1011292D01*
X76917Y1011167D01*
X76083D01*
G01X80100D02*
Y1013667D01*
X79600Y1013167D01*
G01Y1011167D02*
X80600D01*
G01X82408Y1013250D02*
X82658Y1013500D01*
X82950Y1013625D01*
X83283Y1013667D01*
X83700Y1013584D01*
X83992Y1013375D01*
X84075Y1013125D01*
X84033Y1012875D01*
X83867Y1012667D01*
X83033Y1012250D01*
X82658Y1011959D01*
X82408Y1011542D01*
X82325Y1011167D01*
X84075D01*
G01X67135Y1015491D02*
Y1023091D01*
X78535D01*
Y1015491D01*
X67135D01*
G01X107708Y1050217D02*
X107583Y1049967D01*
X107500Y1049675D01*
Y1049342D01*
X107625Y1048967D01*
X107833Y1048675D01*
X108083Y1048467D01*
X108500Y1048300D01*
X108875Y1048258D01*
X109250Y1048342D01*
X109500Y1048467D01*
X109750Y1048717D01*
X109917Y1049008D01*
X110000Y1049300D01*
Y1049592D01*
X109917Y1049883D01*
X109792Y1050133D01*
X109625Y1050342D01*
G01X109708Y1051692D02*
X109917Y1051983D01*
X110000Y1052317D01*
X109917Y1052650D01*
X109667Y1052942D01*
X109292Y1053150D01*
X108917Y1053233D01*
X108458D01*
X108083Y1053150D01*
X107750Y1052942D01*
X107583Y1052692D01*
X107500Y1052400D01*
X107583Y1052067D01*
X107750Y1051817D01*
X108000Y1051650D01*
X108333Y1051567D01*
X108625Y1051650D01*
X108917Y1051858D01*
X109083Y1052108D01*
X109125Y1052400D01*
X109042Y1052733D01*
X108833Y1052983D01*
X108458Y1053233D01*
G01X109625Y1054583D02*
X109833Y1054833D01*
X109958Y1055125D01*
X110000Y1055500D01*
X109917Y1055875D01*
X109750Y1056167D01*
X109458Y1056375D01*
X109125Y1056417D01*
X108792Y1056333D01*
X108583Y1056125D01*
X108417Y1055833D01*
X108375Y1055542D01*
X108417Y1055250D01*
X108583Y1054875D01*
X107500Y1055000D01*
Y1056125D01*
G01X109500Y1057683D02*
X109792Y1057933D01*
X109958Y1058267D01*
X110000Y1058642D01*
X109958Y1058975D01*
X109750Y1059308D01*
X109500Y1059517D01*
X109250Y1059558D01*
X108958Y1059475D01*
X108750Y1059183D01*
X108667Y1058892D01*
Y1058517D01*
G01Y1058892D02*
X108542Y1059142D01*
X108333Y1059350D01*
X108083Y1059433D01*
X107833Y1059350D01*
X107625Y1059142D01*
X107500Y1058767D01*
X107542Y1058392D01*
X107708Y1058017D01*
G01X107500Y1061700D02*
X107583Y1061367D01*
X107792Y1061117D01*
X108042Y1060950D01*
X108375Y1060825D01*
X108750Y1060783D01*
X109125Y1060825D01*
X109458Y1060950D01*
X109708Y1061117D01*
X109917Y1061367D01*
X110000Y1061700D01*
X109917Y1062033D01*
X109708Y1062283D01*
X109458Y1062450D01*
X109125Y1062575D01*
X108750Y1062617D01*
X108375Y1062575D01*
X108042Y1062450D01*
X107792Y1062283D01*
X107583Y1062033D01*
X107500Y1061700D01*
G01X62100Y1063100D02*
X61767Y1063142D01*
X61475Y1063308D01*
X61225Y1063558D01*
X61058Y1063850D01*
X60975Y1064183D01*
Y1064517D01*
X61058Y1064850D01*
X61225Y1065142D01*
X61475Y1065392D01*
X61767Y1065558D01*
X62100Y1065600D01*
X62433Y1065558D01*
X62725Y1065392D01*
X62975Y1065142D01*
X63142Y1064850D01*
X63225Y1064517D01*
Y1064183D01*
X63142Y1063850D01*
X62975Y1063558D01*
X62725Y1063308D01*
X62433Y1063142D01*
X62100Y1063100D01*
G01X62433Y1063767D02*
X62933Y1063100D01*
G01X65200D02*
X65492Y1063142D01*
X65825Y1063267D01*
X66033Y1063475D01*
X66117Y1063767D01*
X66033Y1064058D01*
X65783Y1064308D01*
X65408Y1064433D01*
X64992D01*
X64742Y1064517D01*
X64533Y1064725D01*
X64450Y1065017D01*
X64575Y1065308D01*
X64867Y1065517D01*
X65200Y1065600D01*
X65533Y1065517D01*
X65825Y1065308D01*
X65950Y1065017D01*
X65867Y1064725D01*
X65658Y1064517D01*
X65408Y1064433D01*
X64992D01*
X64617Y1064308D01*
X64367Y1064058D01*
X64283Y1063767D01*
X64367Y1063475D01*
X64575Y1063267D01*
X64908Y1063142D01*
X65200Y1063100D01*
G01X68300D02*
X68592Y1063142D01*
X68925Y1063267D01*
X69133Y1063475D01*
X69217Y1063767D01*
X69133Y1064058D01*
X68883Y1064308D01*
X68508Y1064433D01*
X68092D01*
X67842Y1064517D01*
X67633Y1064725D01*
X67550Y1065017D01*
X67675Y1065308D01*
X67967Y1065517D01*
X68300Y1065600D01*
X68633Y1065517D01*
X68925Y1065308D01*
X69050Y1065017D01*
X68967Y1064725D01*
X68758Y1064517D01*
X68508Y1064433D01*
X68092D01*
X67717Y1064308D01*
X67467Y1064058D01*
X67383Y1063767D01*
X67467Y1063475D01*
X67675Y1063267D01*
X68008Y1063142D01*
X68300Y1063100D01*
G01X60500Y1061500D02*
Y1047500D01*
G01X73500Y1061500D02*
X60500D01*
G01X73500Y1047500D02*
Y1061500D01*
G01X60500Y1047500D02*
X73500D01*
G01X109000Y1033900D02*
X108958Y1033567D01*
X108792Y1033275D01*
X108542Y1033025D01*
X108250Y1032858D01*
X107917Y1032775D01*
X107583D01*
X107250Y1032858D01*
X106958Y1033025D01*
X106708Y1033275D01*
X106542Y1033567D01*
X106500Y1033900D01*
X106542Y1034233D01*
X106708Y1034525D01*
X106958Y1034775D01*
X107250Y1034942D01*
X107583Y1035025D01*
X107917D01*
X108250Y1034942D01*
X108542Y1034775D01*
X108792Y1034525D01*
X108958Y1034233D01*
X109000Y1033900D01*
G01X108333Y1034233D02*
X109000Y1034733D01*
G01Y1037000D02*
X108958Y1037292D01*
X108833Y1037625D01*
X108625Y1037833D01*
X108333Y1037917D01*
X108042Y1037833D01*
X107792Y1037583D01*
X107667Y1037208D01*
Y1036792D01*
X107583Y1036542D01*
X107375Y1036333D01*
X107083Y1036250D01*
X106792Y1036375D01*
X106583Y1036667D01*
X106500Y1037000D01*
X106583Y1037333D01*
X106792Y1037625D01*
X107083Y1037750D01*
X107375Y1037667D01*
X107583Y1037458D01*
X107667Y1037208D01*
Y1036792D01*
X107792Y1036417D01*
X108042Y1036167D01*
X108333Y1036083D01*
X108625Y1036167D01*
X108833Y1036375D01*
X108958Y1036708D01*
X109000Y1037000D01*
G01X108708Y1039392D02*
X108917Y1039683D01*
X109000Y1040017D01*
X108917Y1040350D01*
X108667Y1040642D01*
X108292Y1040850D01*
X107917Y1040933D01*
X107458D01*
X107083Y1040850D01*
X106750Y1040642D01*
X106583Y1040392D01*
X106500Y1040100D01*
X106583Y1039767D01*
X106750Y1039517D01*
X107000Y1039350D01*
X107333Y1039267D01*
X107625Y1039350D01*
X107917Y1039558D01*
X108083Y1039808D01*
X108125Y1040100D01*
X108042Y1040433D01*
X107833Y1040683D01*
X107458Y1040933D01*
G01X91000Y1028488D02*
X105000D01*
G01X91000Y1041488D02*
Y1028488D01*
G01X105000Y1041488D02*
X91000D01*
G01X105000Y1028488D02*
Y1041488D01*
G01X88000Y1025400D02*
X87958Y1025067D01*
X87792Y1024775D01*
X87542Y1024525D01*
X87250Y1024358D01*
X86917Y1024275D01*
X86583D01*
X86250Y1024358D01*
X85958Y1024525D01*
X85708Y1024775D01*
X85542Y1025067D01*
X85500Y1025400D01*
X85542Y1025733D01*
X85708Y1026025D01*
X85958Y1026275D01*
X86250Y1026442D01*
X86583Y1026525D01*
X86917D01*
X87250Y1026442D01*
X87542Y1026275D01*
X87792Y1026025D01*
X87958Y1025733D01*
X88000Y1025400D01*
G01X87333Y1025733D02*
X88000Y1026233D01*
G01X87708Y1027792D02*
X87917Y1028083D01*
X88000Y1028417D01*
X87917Y1028750D01*
X87667Y1029042D01*
X87292Y1029250D01*
X86917Y1029333D01*
X86458D01*
X86083Y1029250D01*
X85750Y1029042D01*
X85583Y1028792D01*
X85500Y1028500D01*
X85583Y1028167D01*
X85750Y1027917D01*
X86000Y1027750D01*
X86333Y1027667D01*
X86625Y1027750D01*
X86917Y1027958D01*
X87083Y1028208D01*
X87125Y1028500D01*
X87042Y1028833D01*
X86833Y1029083D01*
X86458Y1029333D01*
G01X85500Y1031600D02*
X85583Y1031267D01*
X85792Y1031017D01*
X86042Y1030850D01*
X86375Y1030725D01*
X86750Y1030683D01*
X87125Y1030725D01*
X87458Y1030850D01*
X87708Y1031017D01*
X87917Y1031267D01*
X88000Y1031600D01*
X87917Y1031933D01*
X87708Y1032183D01*
X87458Y1032350D01*
X87125Y1032475D01*
X86750Y1032517D01*
X86375Y1032475D01*
X86042Y1032350D01*
X85792Y1032183D01*
X85583Y1031933D01*
X85500Y1031600D01*
G01X69958Y1025007D02*
X83958D01*
G01X69958Y1038007D02*
Y1025007D01*
G01X83958Y1038007D02*
X69958D01*
G01X83958Y1025007D02*
Y1038007D01*
G01X100948Y1018970D02*
Y1021470D01*
X101989D01*
X102323Y1021345D01*
X102531Y1021178D01*
X102614Y1020845D01*
X102531Y1020512D01*
X102281Y1020303D01*
X101989Y1020178D01*
X100948D01*
G01X101989D02*
X102614Y1018970D01*
G01X104173Y1019262D02*
X104464Y1019053D01*
X104798Y1018970D01*
X105131Y1019053D01*
X105423Y1019303D01*
X105631Y1019678D01*
X105714Y1020053D01*
Y1020512D01*
X105631Y1020887D01*
X105423Y1021220D01*
X105173Y1021387D01*
X104881Y1021470D01*
X104548Y1021387D01*
X104298Y1021220D01*
X104131Y1020970D01*
X104048Y1020637D01*
X104131Y1020345D01*
X104339Y1020053D01*
X104589Y1019887D01*
X104881Y1019845D01*
X105214Y1019928D01*
X105464Y1020137D01*
X105714Y1020512D01*
G01X108481Y1018970D02*
Y1021470D01*
X106939Y1019678D01*
X109023D01*
G01X110998Y1018970D02*
X111081Y1019512D01*
X111206Y1019970D01*
X111373Y1020387D01*
X111581Y1020845D01*
X111914Y1021470D01*
X110248D01*
G01X114098Y1018970D02*
X114181Y1019512D01*
X114306Y1019970D01*
X114473Y1020387D01*
X114681Y1020845D01*
X115014Y1021470D01*
X113348D01*
G01X98200Y1019000D02*
Y1023000D01*
X90800D01*
G01X43000Y1058800D02*
X47000D01*
Y1066200D01*
G01X39000Y1058800D02*
X43000D01*
Y1066200D01*
G01X82700Y1062488D02*
Y1066488D01*
X75300D01*
G01X68700Y1031667D02*
X66200D01*
Y1032708D01*
X66325Y1033042D01*
X66492Y1033250D01*
X66825Y1033333D01*
X67158Y1033250D01*
X67367Y1033000D01*
X67492Y1032708D01*
Y1031667D01*
G01Y1032708D02*
X68700Y1033333D01*
G01X68408Y1034892D02*
X68617Y1035183D01*
X68700Y1035517D01*
X68617Y1035850D01*
X68367Y1036142D01*
X67992Y1036350D01*
X67617Y1036433D01*
X67158D01*
X66783Y1036350D01*
X66450Y1036142D01*
X66283Y1035892D01*
X66200Y1035600D01*
X66283Y1035267D01*
X66450Y1035017D01*
X66700Y1034850D01*
X67033Y1034767D01*
X67325Y1034850D01*
X67617Y1035058D01*
X67783Y1035308D01*
X67825Y1035600D01*
X67742Y1035933D01*
X67533Y1036183D01*
X67158Y1036433D01*
G01X68700Y1038700D02*
X68658Y1038992D01*
X68533Y1039325D01*
X68325Y1039533D01*
X68033Y1039617D01*
X67742Y1039533D01*
X67492Y1039283D01*
X67367Y1038908D01*
Y1038492D01*
X67283Y1038242D01*
X67075Y1038033D01*
X66783Y1037950D01*
X66492Y1038075D01*
X66283Y1038367D01*
X66200Y1038700D01*
X66283Y1039033D01*
X66492Y1039325D01*
X66783Y1039450D01*
X67075Y1039367D01*
X67283Y1039158D01*
X67367Y1038908D01*
Y1038492D01*
X67492Y1038117D01*
X67742Y1037867D01*
X68033Y1037783D01*
X68325Y1037867D01*
X68533Y1038075D01*
X68658Y1038408D01*
X68700Y1038700D01*
G01X67658Y1041008D02*
X67367Y1041300D01*
X67200Y1041550D01*
X67117Y1041883D01*
X67200Y1042175D01*
X67367Y1042383D01*
X67617Y1042550D01*
X67908Y1042592D01*
X68158Y1042550D01*
X68408Y1042383D01*
X68617Y1042133D01*
X68700Y1041842D01*
X68617Y1041508D01*
X68367Y1041217D01*
X67992Y1041050D01*
X67575Y1041008D01*
X67033Y1041092D01*
X66742Y1041217D01*
X66450Y1041425D01*
X66242Y1041717D01*
X66200Y1042008D01*
X66283Y1042300D01*
X66492Y1042508D01*
G01X66617Y1044108D02*
X66367Y1044358D01*
X66242Y1044650D01*
X66200Y1044983D01*
X66283Y1045400D01*
X66492Y1045692D01*
X66742Y1045775D01*
X66992Y1045733D01*
X67200Y1045567D01*
X67617Y1044733D01*
X67908Y1044358D01*
X68325Y1044108D01*
X68700Y1044025D01*
Y1045775D01*
G01X86000Y1040800D02*
X90000D01*
Y1048200D01*
G01X54100Y1031367D02*
X51600D01*
Y1032408D01*
X51725Y1032742D01*
X51892Y1032950D01*
X52225Y1033033D01*
X52558Y1032950D01*
X52767Y1032700D01*
X52892Y1032408D01*
Y1031367D01*
G01Y1032408D02*
X54100Y1033033D01*
G01X53808Y1034592D02*
X54017Y1034883D01*
X54100Y1035217D01*
X54017Y1035550D01*
X53767Y1035842D01*
X53392Y1036050D01*
X53017Y1036133D01*
X52558D01*
X52183Y1036050D01*
X51850Y1035842D01*
X51683Y1035592D01*
X51600Y1035300D01*
X51683Y1034967D01*
X51850Y1034717D01*
X52100Y1034550D01*
X52433Y1034467D01*
X52725Y1034550D01*
X53017Y1034758D01*
X53183Y1035008D01*
X53225Y1035300D01*
X53142Y1035633D01*
X52933Y1035883D01*
X52558Y1036133D01*
G01X54100Y1038400D02*
X54058Y1038692D01*
X53933Y1039025D01*
X53725Y1039233D01*
X53433Y1039317D01*
X53142Y1039233D01*
X52892Y1038983D01*
X52767Y1038608D01*
Y1038192D01*
X52683Y1037942D01*
X52475Y1037733D01*
X52183Y1037650D01*
X51892Y1037775D01*
X51683Y1038067D01*
X51600Y1038400D01*
X51683Y1038733D01*
X51892Y1039025D01*
X52183Y1039150D01*
X52475Y1039067D01*
X52683Y1038858D01*
X52767Y1038608D01*
Y1038192D01*
X52892Y1037817D01*
X53142Y1037567D01*
X53433Y1037483D01*
X53725Y1037567D01*
X53933Y1037775D01*
X54058Y1038108D01*
X54100Y1038400D01*
G01X53058Y1040708D02*
X52767Y1041000D01*
X52600Y1041250D01*
X52517Y1041583D01*
X52600Y1041875D01*
X52767Y1042083D01*
X53017Y1042250D01*
X53308Y1042292D01*
X53558Y1042250D01*
X53808Y1042083D01*
X54017Y1041833D01*
X54100Y1041542D01*
X54017Y1041208D01*
X53767Y1040917D01*
X53392Y1040750D01*
X52975Y1040708D01*
X52433Y1040792D01*
X52142Y1040917D01*
X51850Y1041125D01*
X51642Y1041417D01*
X51600Y1041708D01*
X51683Y1042000D01*
X51892Y1042208D01*
G01X53600Y1043683D02*
X53892Y1043933D01*
X54058Y1044267D01*
X54100Y1044642D01*
X54058Y1044975D01*
X53850Y1045308D01*
X53600Y1045517D01*
X53350Y1045558D01*
X53058Y1045475D01*
X52850Y1045183D01*
X52767Y1044892D01*
Y1044517D01*
G01Y1044892D02*
X52642Y1045142D01*
X52433Y1045350D01*
X52183Y1045433D01*
X51933Y1045350D01*
X51725Y1045142D01*
X51600Y1044767D01*
X51642Y1044392D01*
X51808Y1044017D01*
G01X75750Y1038895D02*
X79750D01*
Y1046295D01*
G01X100375Y1023833D02*
X100708Y1023625D01*
X101083Y1023500D01*
X101417D01*
X101750Y1023625D01*
X102000Y1023833D01*
X102125Y1024125D01*
X102042Y1024417D01*
X101833Y1024667D01*
X101458Y1024833D01*
X100958Y1024917D01*
X100667Y1025083D01*
X100542Y1025375D01*
X100625Y1025667D01*
X100833Y1025875D01*
X101125Y1026000D01*
X101417D01*
X101708Y1025917D01*
X101958Y1025708D01*
G01X103517Y1023500D02*
Y1026000D01*
X104558D01*
X104892Y1025875D01*
X105100Y1025708D01*
X105183Y1025375D01*
X105100Y1025042D01*
X104850Y1024833D01*
X104558Y1024708D01*
X103517D01*
G01X104558D02*
X105183Y1023500D01*
G01X107450D02*
Y1026000D01*
X106950Y1025500D01*
G01Y1023500D02*
X107950D01*
G01X110550D02*
Y1026000D01*
X110050Y1025500D01*
G01Y1023500D02*
X111050D01*
G01X114150D02*
Y1026000D01*
X112608Y1024208D01*
X114692D01*
G01X115833Y1023875D02*
X116083Y1023667D01*
X116375Y1023542D01*
X116750Y1023500D01*
X117125Y1023583D01*
X117417Y1023750D01*
X117625Y1024042D01*
X117667Y1024375D01*
X117583Y1024708D01*
X117375Y1024917D01*
X117083Y1025083D01*
X116792Y1025125D01*
X116500Y1025083D01*
X116125Y1024917D01*
X116250Y1026000D01*
X117375D01*
G01X98200Y1023488D02*
Y1027488D01*
X90800D01*
G01X105667Y1046875D02*
X105875Y1047208D01*
X106000Y1047583D01*
Y1047917D01*
X105875Y1048250D01*
X105667Y1048500D01*
X105375Y1048625D01*
X105083Y1048542D01*
X104833Y1048333D01*
X104667Y1047958D01*
X104583Y1047458D01*
X104417Y1047167D01*
X104125Y1047042D01*
X103833Y1047125D01*
X103625Y1047333D01*
X103500Y1047625D01*
Y1047917D01*
X103583Y1048208D01*
X103792Y1048458D01*
G01X106000Y1050017D02*
X103500D01*
Y1051058D01*
X103625Y1051392D01*
X103792Y1051600D01*
X104125Y1051683D01*
X104458Y1051600D01*
X104667Y1051350D01*
X104792Y1051058D01*
Y1050017D01*
G01Y1051058D02*
X106000Y1051683D01*
G01Y1053950D02*
X103500D01*
X104000Y1053450D01*
G01X106000D02*
Y1054450D01*
G01Y1057050D02*
X103500D01*
X104000Y1056550D01*
G01X106000D02*
Y1057550D01*
G01Y1060650D02*
X103500D01*
X105292Y1059108D01*
Y1061192D01*
G01X104958Y1062458D02*
X104667Y1062750D01*
X104500Y1063000D01*
X104417Y1063333D01*
X104500Y1063625D01*
X104667Y1063833D01*
X104917Y1064000D01*
X105208Y1064042D01*
X105458Y1064000D01*
X105708Y1063833D01*
X105917Y1063583D01*
X106000Y1063292D01*
X105917Y1062958D01*
X105667Y1062667D01*
X105292Y1062500D01*
X104875Y1062458D01*
X104333Y1062542D01*
X104042Y1062667D01*
X103750Y1062875D01*
X103542Y1063167D01*
X103500Y1063458D01*
X103583Y1063750D01*
X103792Y1063958D01*
G01X79750Y1054836D02*
X75750D01*
Y1047436D01*
G01X99419Y1009824D02*
Y1012324D01*
X100460D01*
X100794Y1012199D01*
X101002Y1012032D01*
X101085Y1011699D01*
X101002Y1011366D01*
X100752Y1011157D01*
X100460Y1011032D01*
X99419D01*
G01X100460D02*
X101085Y1009824D01*
G01X102644Y1010116D02*
X102935Y1009907D01*
X103269Y1009824D01*
X103602Y1009907D01*
X103894Y1010157D01*
X104102Y1010532D01*
X104185Y1010907D01*
Y1011366D01*
X104102Y1011741D01*
X103894Y1012074D01*
X103644Y1012241D01*
X103352Y1012324D01*
X103019Y1012241D01*
X102769Y1012074D01*
X102602Y1011824D01*
X102519Y1011491D01*
X102602Y1011199D01*
X102810Y1010907D01*
X103060Y1010741D01*
X103352Y1010699D01*
X103685Y1010782D01*
X103935Y1010991D01*
X104185Y1011366D01*
G01X105744Y1010116D02*
X106035Y1009907D01*
X106369Y1009824D01*
X106702Y1009907D01*
X106994Y1010157D01*
X107202Y1010532D01*
X107285Y1010907D01*
Y1011366D01*
X107202Y1011741D01*
X106994Y1012074D01*
X106744Y1012241D01*
X106452Y1012324D01*
X106119Y1012241D01*
X105869Y1012074D01*
X105702Y1011824D01*
X105619Y1011491D01*
X105702Y1011199D01*
X105910Y1010907D01*
X106160Y1010741D01*
X106452Y1010699D01*
X106785Y1010782D01*
X107035Y1010991D01*
X107285Y1011366D01*
G01X109552Y1012324D02*
X109219Y1012241D01*
X108969Y1012032D01*
X108802Y1011782D01*
X108677Y1011449D01*
X108635Y1011074D01*
X108677Y1010699D01*
X108802Y1010366D01*
X108969Y1010116D01*
X109219Y1009907D01*
X109552Y1009824D01*
X109885Y1009907D01*
X110135Y1010116D01*
X110302Y1010366D01*
X110427Y1010699D01*
X110469Y1011074D01*
X110427Y1011449D01*
X110302Y1011782D01*
X110135Y1012032D01*
X109885Y1012241D01*
X109552Y1012324D01*
G01X113152Y1009824D02*
Y1012324D01*
X111610Y1010532D01*
X113694D01*
G01X91000Y1006800D02*
X95000D01*
Y1014200D01*
G01X61800Y1031167D02*
X59300D01*
Y1032208D01*
X59425Y1032542D01*
X59592Y1032750D01*
X59925Y1032833D01*
X60258Y1032750D01*
X60467Y1032500D01*
X60592Y1032208D01*
Y1031167D01*
G01Y1032208D02*
X61800Y1032833D01*
G01X61508Y1034392D02*
X61717Y1034683D01*
X61800Y1035017D01*
X61717Y1035350D01*
X61467Y1035642D01*
X61092Y1035850D01*
X60717Y1035933D01*
X60258D01*
X59883Y1035850D01*
X59550Y1035642D01*
X59383Y1035392D01*
X59300Y1035100D01*
X59383Y1034767D01*
X59550Y1034517D01*
X59800Y1034350D01*
X60133Y1034267D01*
X60425Y1034350D01*
X60717Y1034558D01*
X60883Y1034808D01*
X60925Y1035100D01*
X60842Y1035433D01*
X60633Y1035683D01*
X60258Y1035933D01*
G01X61508Y1037492D02*
X61717Y1037783D01*
X61800Y1038117D01*
X61717Y1038450D01*
X61467Y1038742D01*
X61092Y1038950D01*
X60717Y1039033D01*
X60258D01*
X59883Y1038950D01*
X59550Y1038742D01*
X59383Y1038492D01*
X59300Y1038200D01*
X59383Y1037867D01*
X59550Y1037617D01*
X59800Y1037450D01*
X60133Y1037367D01*
X60425Y1037450D01*
X60717Y1037658D01*
X60883Y1037908D01*
X60925Y1038200D01*
X60842Y1038533D01*
X60633Y1038783D01*
X60258Y1039033D01*
G01X59717Y1040508D02*
X59467Y1040758D01*
X59342Y1041050D01*
X59300Y1041383D01*
X59383Y1041800D01*
X59592Y1042092D01*
X59842Y1042175D01*
X60092Y1042133D01*
X60300Y1041967D01*
X60717Y1041133D01*
X61008Y1040758D01*
X61425Y1040508D01*
X61800Y1040425D01*
Y1042175D01*
G01Y1044900D02*
X59300D01*
X61092Y1043358D01*
Y1045442D01*
G01X82000Y1040800D02*
X86000D01*
Y1048200D01*
G01X53334Y999967D02*
X50834D01*
Y1001008D01*
X50959Y1001342D01*
X51126Y1001550D01*
X51459Y1001633D01*
X51792Y1001550D01*
X52001Y1001300D01*
X52126Y1001008D01*
Y999967D01*
G01Y1001008D02*
X53334Y1001633D01*
G01X53042Y1003192D02*
X53251Y1003483D01*
X53334Y1003817D01*
X53251Y1004150D01*
X53001Y1004442D01*
X52626Y1004650D01*
X52251Y1004733D01*
X51792D01*
X51417Y1004650D01*
X51084Y1004442D01*
X50917Y1004192D01*
X50834Y1003900D01*
X50917Y1003567D01*
X51084Y1003317D01*
X51334Y1003150D01*
X51667Y1003067D01*
X51959Y1003150D01*
X52251Y1003358D01*
X52417Y1003608D01*
X52459Y1003900D01*
X52376Y1004233D01*
X52167Y1004483D01*
X51792Y1004733D01*
G01X53042Y1006292D02*
X53251Y1006583D01*
X53334Y1006917D01*
X53251Y1007250D01*
X53001Y1007542D01*
X52626Y1007750D01*
X52251Y1007833D01*
X51792D01*
X51417Y1007750D01*
X51084Y1007542D01*
X50917Y1007292D01*
X50834Y1007000D01*
X50917Y1006667D01*
X51084Y1006417D01*
X51334Y1006250D01*
X51667Y1006167D01*
X51959Y1006250D01*
X52251Y1006458D01*
X52417Y1006708D01*
X52459Y1007000D01*
X52376Y1007333D01*
X52167Y1007583D01*
X51792Y1007833D01*
G01X52959Y1009183D02*
X53167Y1009433D01*
X53292Y1009725D01*
X53334Y1010100D01*
X53251Y1010475D01*
X53084Y1010767D01*
X52792Y1010975D01*
X52459Y1011017D01*
X52126Y1010933D01*
X51917Y1010725D01*
X51751Y1010433D01*
X51709Y1010142D01*
X51751Y1009850D01*
X51917Y1009475D01*
X50834Y1009600D01*
Y1010725D01*
G01X51251Y1012408D02*
X51001Y1012658D01*
X50876Y1012950D01*
X50834Y1013283D01*
X50917Y1013700D01*
X51126Y1013992D01*
X51376Y1014075D01*
X51626Y1014033D01*
X51834Y1013867D01*
X52251Y1013033D01*
X52542Y1012658D01*
X52959Y1012408D01*
X53334Y1012325D01*
Y1014075D01*
G01X61495Y1014436D02*
Y1010436D01*
X68895D01*
G01X60834Y1014967D02*
X58334D01*
Y1016008D01*
X58459Y1016342D01*
X58626Y1016550D01*
X58959Y1016633D01*
X59292Y1016550D01*
X59501Y1016300D01*
X59626Y1016008D01*
Y1014967D01*
G01Y1016008D02*
X60834Y1016633D01*
G01X60542Y1018192D02*
X60751Y1018483D01*
X60834Y1018817D01*
X60751Y1019150D01*
X60501Y1019442D01*
X60126Y1019650D01*
X59751Y1019733D01*
X59292D01*
X58917Y1019650D01*
X58584Y1019442D01*
X58417Y1019192D01*
X58334Y1018900D01*
X58417Y1018567D01*
X58584Y1018317D01*
X58834Y1018150D01*
X59167Y1018067D01*
X59459Y1018150D01*
X59751Y1018358D01*
X59917Y1018608D01*
X59959Y1018900D01*
X59876Y1019233D01*
X59667Y1019483D01*
X59292Y1019733D01*
G01X60542Y1021292D02*
X60751Y1021583D01*
X60834Y1021917D01*
X60751Y1022250D01*
X60501Y1022542D01*
X60126Y1022750D01*
X59751Y1022833D01*
X59292D01*
X58917Y1022750D01*
X58584Y1022542D01*
X58417Y1022292D01*
X58334Y1022000D01*
X58417Y1021667D01*
X58584Y1021417D01*
X58834Y1021250D01*
X59167Y1021167D01*
X59459Y1021250D01*
X59751Y1021458D01*
X59917Y1021708D01*
X59959Y1022000D01*
X59876Y1022333D01*
X59667Y1022583D01*
X59292Y1022833D01*
G01X60459Y1024183D02*
X60667Y1024433D01*
X60792Y1024725D01*
X60834Y1025100D01*
X60751Y1025475D01*
X60584Y1025767D01*
X60292Y1025975D01*
X59959Y1026017D01*
X59626Y1025933D01*
X59417Y1025725D01*
X59251Y1025433D01*
X59209Y1025142D01*
X59251Y1024850D01*
X59417Y1024475D01*
X58334Y1024600D01*
Y1025725D01*
G01X60834Y1028200D02*
X58334D01*
X58834Y1027700D01*
G01X60834D02*
Y1028700D01*
G01X62040Y1018285D02*
X66040D01*
Y1025685D01*
G01X100737Y1015401D02*
Y1017901D01*
X101778D01*
X102112Y1017776D01*
X102320Y1017609D01*
X102403Y1017276D01*
X102320Y1016943D01*
X102070Y1016734D01*
X101778Y1016609D01*
X100737D01*
G01X101778D02*
X102403Y1015401D01*
G01X103962Y1015693D02*
X104253Y1015484D01*
X104587Y1015401D01*
X104920Y1015484D01*
X105212Y1015734D01*
X105420Y1016109D01*
X105503Y1016484D01*
Y1016943D01*
X105420Y1017318D01*
X105212Y1017651D01*
X104962Y1017818D01*
X104670Y1017901D01*
X104337Y1017818D01*
X104087Y1017651D01*
X103920Y1017401D01*
X103837Y1017068D01*
X103920Y1016776D01*
X104128Y1016484D01*
X104378Y1016318D01*
X104670Y1016276D01*
X105003Y1016359D01*
X105253Y1016568D01*
X105503Y1016943D01*
G01X108270Y1015401D02*
Y1017901D01*
X106728Y1016109D01*
X108812D01*
G01X110787Y1015401D02*
X110870Y1015943D01*
X110995Y1016401D01*
X111162Y1016818D01*
X111370Y1017276D01*
X111703Y1017901D01*
X110037D01*
G01X113970Y1015401D02*
X114262Y1015443D01*
X114595Y1015568D01*
X114803Y1015776D01*
X114887Y1016068D01*
X114803Y1016359D01*
X114553Y1016609D01*
X114178Y1016734D01*
X113762D01*
X113512Y1016818D01*
X113303Y1017026D01*
X113220Y1017318D01*
X113345Y1017609D01*
X113637Y1017818D01*
X113970Y1017901D01*
X114303Y1017818D01*
X114595Y1017609D01*
X114720Y1017318D01*
X114637Y1017026D01*
X114428Y1016818D01*
X114178Y1016734D01*
X113762D01*
X113387Y1016609D01*
X113137Y1016359D01*
X113053Y1016068D01*
X113137Y1015776D01*
X113345Y1015568D01*
X113678Y1015443D01*
X113970Y1015401D01*
G01X98200Y1014500D02*
Y1018500D01*
X90800D01*
G01X87781Y1060446D02*
X101181D01*
G01X87781Y1050446D02*
Y1060446D01*
G01X101181Y1050446D02*
X87781D01*
G01X101181Y1060446D02*
Y1050446D01*
G01X96727Y1135137D02*
X96602Y1134887D01*
X96519Y1134595D01*
Y1134262D01*
X96644Y1133887D01*
X96852Y1133595D01*
X97102Y1133387D01*
X97519Y1133220D01*
X97894Y1133178D01*
X98269Y1133262D01*
X98519Y1133387D01*
X98769Y1133637D01*
X98936Y1133928D01*
X99019Y1134220D01*
Y1134512D01*
X98936Y1134803D01*
X98811Y1135053D01*
X98644Y1135262D01*
G01X98519Y1136403D02*
X98811Y1136653D01*
X98977Y1136987D01*
X99019Y1137362D01*
X98977Y1137695D01*
X98769Y1138028D01*
X98519Y1138237D01*
X98269Y1138278D01*
X97977Y1138195D01*
X97769Y1137903D01*
X97686Y1137612D01*
Y1137237D01*
G01Y1137612D02*
X97561Y1137862D01*
X97352Y1138070D01*
X97102Y1138153D01*
X96852Y1138070D01*
X96644Y1137862D01*
X96519Y1137487D01*
X96561Y1137112D01*
X96727Y1136737D01*
G01X99019Y1140420D02*
X98977Y1140712D01*
X98852Y1141045D01*
X98644Y1141253D01*
X98352Y1141337D01*
X98061Y1141253D01*
X97811Y1141003D01*
X97686Y1140628D01*
Y1140212D01*
X97602Y1139962D01*
X97394Y1139753D01*
X97102Y1139670D01*
X96811Y1139795D01*
X96602Y1140087D01*
X96519Y1140420D01*
X96602Y1140753D01*
X96811Y1141045D01*
X97102Y1141170D01*
X97394Y1141087D01*
X97602Y1140878D01*
X97686Y1140628D01*
Y1140212D01*
X97811Y1139837D01*
X98061Y1139587D01*
X98352Y1139503D01*
X98644Y1139587D01*
X98852Y1139795D01*
X98977Y1140128D01*
X99019Y1140420D01*
G01X98727Y1142812D02*
X98936Y1143103D01*
X99019Y1143437D01*
X98936Y1143770D01*
X98686Y1144062D01*
X98311Y1144270D01*
X97936Y1144353D01*
X97477D01*
X97102Y1144270D01*
X96769Y1144062D01*
X96602Y1143812D01*
X96519Y1143520D01*
X96602Y1143187D01*
X96769Y1142937D01*
X97019Y1142770D01*
X97352Y1142687D01*
X97644Y1142770D01*
X97936Y1142978D01*
X98102Y1143228D01*
X98144Y1143520D01*
X98061Y1143853D01*
X97852Y1144103D01*
X97477Y1144353D01*
G01X90519Y1133387D02*
X88019D01*
Y1134428D01*
X88144Y1134762D01*
X88311Y1134970D01*
X88644Y1135053D01*
X88977Y1134970D01*
X89186Y1134720D01*
X89311Y1134428D01*
Y1133387D01*
G01Y1134428D02*
X90519Y1135053D01*
G01X90144Y1136403D02*
X90352Y1136653D01*
X90477Y1136945D01*
X90519Y1137320D01*
X90436Y1137695D01*
X90269Y1137987D01*
X89977Y1138195D01*
X89644Y1138237D01*
X89311Y1138153D01*
X89102Y1137945D01*
X88936Y1137653D01*
X88894Y1137362D01*
X88936Y1137070D01*
X89102Y1136695D01*
X88019Y1136820D01*
Y1137945D01*
G01X90144Y1139503D02*
X90352Y1139753D01*
X90477Y1140045D01*
X90519Y1140420D01*
X90436Y1140795D01*
X90269Y1141087D01*
X89977Y1141295D01*
X89644Y1141337D01*
X89311Y1141253D01*
X89102Y1141045D01*
X88936Y1140753D01*
X88894Y1140462D01*
X88936Y1140170D01*
X89102Y1139795D01*
X88019Y1139920D01*
Y1141045D01*
G01X90519Y1143520D02*
X90477Y1143812D01*
X90352Y1144145D01*
X90144Y1144353D01*
X89852Y1144437D01*
X89561Y1144353D01*
X89311Y1144103D01*
X89186Y1143728D01*
Y1143312D01*
X89102Y1143062D01*
X88894Y1142853D01*
X88602Y1142770D01*
X88311Y1142895D01*
X88102Y1143187D01*
X88019Y1143520D01*
X88102Y1143853D01*
X88311Y1144145D01*
X88602Y1144270D01*
X88894Y1144187D01*
X89102Y1143978D01*
X89186Y1143728D01*
Y1143312D01*
X89311Y1142937D01*
X89561Y1142687D01*
X89852Y1142603D01*
X90144Y1142687D01*
X90352Y1142895D01*
X90477Y1143228D01*
X90519Y1143520D01*
G01X95019Y1133387D02*
X92519D01*
Y1134428D01*
X92644Y1134762D01*
X92811Y1134970D01*
X93144Y1135053D01*
X93477Y1134970D01*
X93686Y1134720D01*
X93811Y1134428D01*
Y1133387D01*
G01Y1134428D02*
X95019Y1135053D01*
G01X94644Y1136403D02*
X94852Y1136653D01*
X94977Y1136945D01*
X95019Y1137320D01*
X94936Y1137695D01*
X94769Y1137987D01*
X94477Y1138195D01*
X94144Y1138237D01*
X93811Y1138153D01*
X93602Y1137945D01*
X93436Y1137653D01*
X93394Y1137362D01*
X93436Y1137070D01*
X93602Y1136695D01*
X92519Y1136820D01*
Y1137945D01*
G01X95019Y1140337D02*
X94477Y1140420D01*
X94019Y1140545D01*
X93602Y1140712D01*
X93144Y1140920D01*
X92519Y1141253D01*
Y1139587D01*
G01X94519Y1142603D02*
X94811Y1142853D01*
X94977Y1143187D01*
X95019Y1143562D01*
X94977Y1143895D01*
X94769Y1144228D01*
X94519Y1144437D01*
X94269Y1144478D01*
X93977Y1144395D01*
X93769Y1144103D01*
X93686Y1143812D01*
Y1143437D01*
G01Y1143812D02*
X93561Y1144062D01*
X93352Y1144270D01*
X93102Y1144353D01*
X92852Y1144270D01*
X92644Y1144062D01*
X92519Y1143687D01*
X92561Y1143312D01*
X92727Y1142937D01*
G01X49900Y1080117D02*
X47400D01*
Y1081158D01*
X47525Y1081492D01*
X47692Y1081700D01*
X48025Y1081783D01*
X48358Y1081700D01*
X48567Y1081450D01*
X48692Y1081158D01*
Y1080117D01*
G01Y1081158D02*
X49900Y1081783D01*
G01X49608Y1083342D02*
X49817Y1083633D01*
X49900Y1083967D01*
X49817Y1084300D01*
X49567Y1084592D01*
X49192Y1084800D01*
X48817Y1084883D01*
X48358D01*
X47983Y1084800D01*
X47650Y1084592D01*
X47483Y1084342D01*
X47400Y1084050D01*
X47483Y1083717D01*
X47650Y1083467D01*
X47900Y1083300D01*
X48233Y1083217D01*
X48525Y1083300D01*
X48817Y1083508D01*
X48983Y1083758D01*
X49025Y1084050D01*
X48942Y1084383D01*
X48733Y1084633D01*
X48358Y1084883D01*
G01X47400Y1087150D02*
X47483Y1086817D01*
X47692Y1086567D01*
X47942Y1086400D01*
X48275Y1086275D01*
X48650Y1086233D01*
X49025Y1086275D01*
X49358Y1086400D01*
X49608Y1086567D01*
X49817Y1086817D01*
X49900Y1087150D01*
X49817Y1087483D01*
X49608Y1087733D01*
X49358Y1087900D01*
X49025Y1088025D01*
X48650Y1088067D01*
X48275Y1088025D01*
X47942Y1087900D01*
X47692Y1087733D01*
X47483Y1087483D01*
X47400Y1087150D01*
G01X49400Y1089333D02*
X49692Y1089583D01*
X49858Y1089917D01*
X49900Y1090292D01*
X49858Y1090625D01*
X49650Y1090958D01*
X49400Y1091167D01*
X49150Y1091208D01*
X48858Y1091125D01*
X48650Y1090833D01*
X48567Y1090542D01*
Y1090167D01*
G01Y1090542D02*
X48442Y1090792D01*
X48233Y1091000D01*
X47983Y1091083D01*
X47733Y1091000D01*
X47525Y1090792D01*
X47400Y1090417D01*
X47442Y1090042D01*
X47608Y1089667D01*
G01X49525Y1092433D02*
X49733Y1092683D01*
X49858Y1092975D01*
X49900Y1093350D01*
X49817Y1093725D01*
X49650Y1094017D01*
X49358Y1094225D01*
X49025Y1094267D01*
X48692Y1094183D01*
X48483Y1093975D01*
X48317Y1093683D01*
X48275Y1093392D01*
X48317Y1093100D01*
X48483Y1092725D01*
X47400Y1092850D01*
Y1093975D01*
G01X45900Y1080117D02*
X43400D01*
Y1081158D01*
X43525Y1081492D01*
X43692Y1081700D01*
X44025Y1081783D01*
X44358Y1081700D01*
X44567Y1081450D01*
X44692Y1081158D01*
Y1080117D01*
G01Y1081158D02*
X45900Y1081783D01*
G01X45608Y1083342D02*
X45817Y1083633D01*
X45900Y1083967D01*
X45817Y1084300D01*
X45567Y1084592D01*
X45192Y1084800D01*
X44817Y1084883D01*
X44358D01*
X43983Y1084800D01*
X43650Y1084592D01*
X43483Y1084342D01*
X43400Y1084050D01*
X43483Y1083717D01*
X43650Y1083467D01*
X43900Y1083300D01*
X44233Y1083217D01*
X44525Y1083300D01*
X44817Y1083508D01*
X44983Y1083758D01*
X45025Y1084050D01*
X44942Y1084383D01*
X44733Y1084633D01*
X44358Y1084883D01*
G01X43400Y1087150D02*
X43483Y1086817D01*
X43692Y1086567D01*
X43942Y1086400D01*
X44275Y1086275D01*
X44650Y1086233D01*
X45025Y1086275D01*
X45358Y1086400D01*
X45608Y1086567D01*
X45817Y1086817D01*
X45900Y1087150D01*
X45817Y1087483D01*
X45608Y1087733D01*
X45358Y1087900D01*
X45025Y1088025D01*
X44650Y1088067D01*
X44275Y1088025D01*
X43942Y1087900D01*
X43692Y1087733D01*
X43483Y1087483D01*
X43400Y1087150D01*
G01X45400Y1089333D02*
X45692Y1089583D01*
X45858Y1089917D01*
X45900Y1090292D01*
X45858Y1090625D01*
X45650Y1090958D01*
X45400Y1091167D01*
X45150Y1091208D01*
X44858Y1091125D01*
X44650Y1090833D01*
X44567Y1090542D01*
Y1090167D01*
G01Y1090542D02*
X44442Y1090792D01*
X44233Y1091000D01*
X43983Y1091083D01*
X43733Y1091000D01*
X43525Y1090792D01*
X43400Y1090417D01*
X43442Y1090042D01*
X43608Y1089667D01*
G01X45900Y1093350D02*
X45858Y1093642D01*
X45733Y1093975D01*
X45525Y1094183D01*
X45233Y1094267D01*
X44942Y1094183D01*
X44692Y1093933D01*
X44567Y1093558D01*
Y1093142D01*
X44483Y1092892D01*
X44275Y1092683D01*
X43983Y1092600D01*
X43692Y1092725D01*
X43483Y1093017D01*
X43400Y1093350D01*
X43483Y1093683D01*
X43692Y1093975D01*
X43983Y1094100D01*
X44275Y1094017D01*
X44483Y1093808D01*
X44567Y1093558D01*
Y1093142D01*
X44692Y1092767D01*
X44942Y1092517D01*
X45233Y1092433D01*
X45525Y1092517D01*
X45733Y1092725D01*
X45858Y1093058D01*
X45900Y1093350D01*
G01X109167Y1125375D02*
X109375Y1125708D01*
X109500Y1126083D01*
Y1126417D01*
X109375Y1126750D01*
X109167Y1127000D01*
X108875Y1127125D01*
X108583Y1127042D01*
X108333Y1126833D01*
X108167Y1126458D01*
X108083Y1125958D01*
X107917Y1125667D01*
X107625Y1125542D01*
X107333Y1125625D01*
X107125Y1125833D01*
X107000Y1126125D01*
Y1126417D01*
X107083Y1126708D01*
X107292Y1126958D01*
G01X109500Y1128517D02*
X107000D01*
Y1129558D01*
X107125Y1129892D01*
X107292Y1130100D01*
X107625Y1130183D01*
X107958Y1130100D01*
X108167Y1129850D01*
X108292Y1129558D01*
Y1128517D01*
G01Y1129558D02*
X109500Y1130183D01*
G01Y1132450D02*
X107000D01*
X107500Y1131950D01*
G01X109500D02*
Y1132950D01*
G01Y1135550D02*
X107000D01*
X107500Y1135050D01*
G01X109500D02*
Y1136050D01*
G01X107000Y1138650D02*
X107083Y1138317D01*
X107292Y1138067D01*
X107542Y1137900D01*
X107875Y1137775D01*
X108250Y1137733D01*
X108625Y1137775D01*
X108958Y1137900D01*
X109208Y1138067D01*
X109417Y1138317D01*
X109500Y1138650D01*
X109417Y1138983D01*
X109208Y1139233D01*
X108958Y1139400D01*
X108625Y1139525D01*
X108250Y1139567D01*
X107875Y1139525D01*
X107542Y1139400D01*
X107292Y1139233D01*
X107083Y1138983D01*
X107000Y1138650D01*
G01X109125Y1140833D02*
X109333Y1141083D01*
X109458Y1141375D01*
X109500Y1141750D01*
X109417Y1142125D01*
X109250Y1142417D01*
X108958Y1142625D01*
X108625Y1142667D01*
X108292Y1142583D01*
X108083Y1142375D01*
X107917Y1142083D01*
X107875Y1141792D01*
X107917Y1141500D01*
X108083Y1141125D01*
X107000Y1141250D01*
Y1142375D01*
G01X113167Y1125375D02*
X113375Y1125708D01*
X113500Y1126083D01*
Y1126417D01*
X113375Y1126750D01*
X113167Y1127000D01*
X112875Y1127125D01*
X112583Y1127042D01*
X112333Y1126833D01*
X112167Y1126458D01*
X112083Y1125958D01*
X111917Y1125667D01*
X111625Y1125542D01*
X111333Y1125625D01*
X111125Y1125833D01*
X111000Y1126125D01*
Y1126417D01*
X111083Y1126708D01*
X111292Y1126958D01*
G01X113500Y1128517D02*
X111000D01*
Y1129558D01*
X111125Y1129892D01*
X111292Y1130100D01*
X111625Y1130183D01*
X111958Y1130100D01*
X112167Y1129850D01*
X112292Y1129558D01*
Y1128517D01*
G01Y1129558D02*
X113500Y1130183D01*
G01Y1132450D02*
X111000D01*
X111500Y1131950D01*
G01X113500D02*
Y1132950D01*
G01Y1135550D02*
X111000D01*
X111500Y1135050D01*
G01X113500D02*
Y1136050D01*
G01X111000Y1138650D02*
X111083Y1138317D01*
X111292Y1138067D01*
X111542Y1137900D01*
X111875Y1137775D01*
X112250Y1137733D01*
X112625Y1137775D01*
X112958Y1137900D01*
X113208Y1138067D01*
X113417Y1138317D01*
X113500Y1138650D01*
X113417Y1138983D01*
X113208Y1139233D01*
X112958Y1139400D01*
X112625Y1139525D01*
X112250Y1139567D01*
X111875Y1139525D01*
X111542Y1139400D01*
X111292Y1139233D01*
X111083Y1138983D01*
X111000Y1138650D01*
G01X112458Y1140958D02*
X112167Y1141250D01*
X112000Y1141500D01*
X111917Y1141833D01*
X112000Y1142125D01*
X112167Y1142333D01*
X112417Y1142500D01*
X112708Y1142542D01*
X112958Y1142500D01*
X113208Y1142333D01*
X113417Y1142083D01*
X113500Y1141792D01*
X113417Y1141458D01*
X113167Y1141167D01*
X112792Y1141000D01*
X112375Y1140958D01*
X111833Y1141042D01*
X111542Y1141167D01*
X111250Y1141375D01*
X111042Y1141667D01*
X111000Y1141958D01*
X111083Y1142250D01*
X111292Y1142458D01*
G01X71967Y1073000D02*
Y1075500D01*
X73008D01*
X73342Y1075375D01*
X73550Y1075208D01*
X73633Y1074875D01*
X73550Y1074542D01*
X73300Y1074333D01*
X73008Y1074208D01*
X71967D01*
G01X73008D02*
X73633Y1073000D01*
G01X75192Y1073292D02*
X75483Y1073083D01*
X75817Y1073000D01*
X76150Y1073083D01*
X76442Y1073333D01*
X76650Y1073708D01*
X76733Y1074083D01*
Y1074542D01*
X76650Y1074917D01*
X76442Y1075250D01*
X76192Y1075417D01*
X75900Y1075500D01*
X75567Y1075417D01*
X75317Y1075250D01*
X75150Y1075000D01*
X75067Y1074667D01*
X75150Y1074375D01*
X75358Y1074083D01*
X75608Y1073917D01*
X75900Y1073875D01*
X76233Y1073958D01*
X76483Y1074167D01*
X76733Y1074542D01*
G01X79000Y1073000D02*
X79292Y1073042D01*
X79625Y1073167D01*
X79833Y1073375D01*
X79917Y1073667D01*
X79833Y1073958D01*
X79583Y1074208D01*
X79208Y1074333D01*
X78792D01*
X78542Y1074417D01*
X78333Y1074625D01*
X78250Y1074917D01*
X78375Y1075208D01*
X78667Y1075417D01*
X79000Y1075500D01*
X79333Y1075417D01*
X79625Y1075208D01*
X79750Y1074917D01*
X79667Y1074625D01*
X79458Y1074417D01*
X79208Y1074333D01*
X78792D01*
X78417Y1074208D01*
X78167Y1073958D01*
X78083Y1073667D01*
X78167Y1073375D01*
X78375Y1073167D01*
X78708Y1073042D01*
X79000Y1073000D01*
G01X81308Y1074042D02*
X81600Y1074333D01*
X81850Y1074500D01*
X82183Y1074583D01*
X82475Y1074500D01*
X82683Y1074333D01*
X82850Y1074083D01*
X82892Y1073792D01*
X82850Y1073542D01*
X82683Y1073292D01*
X82433Y1073083D01*
X82142Y1073000D01*
X81808Y1073083D01*
X81517Y1073333D01*
X81350Y1073708D01*
X81308Y1074125D01*
X81392Y1074667D01*
X81517Y1074958D01*
X81725Y1075250D01*
X82017Y1075458D01*
X82308Y1075500D01*
X82600Y1075417D01*
X82808Y1075208D01*
G01X85200Y1073000D02*
Y1075500D01*
X84700Y1075000D01*
G01Y1073000D02*
X85700D01*
G01X41900Y1080117D02*
X39400D01*
Y1081158D01*
X39525Y1081492D01*
X39692Y1081700D01*
X40025Y1081783D01*
X40358Y1081700D01*
X40567Y1081450D01*
X40692Y1081158D01*
Y1080117D01*
G01Y1081158D02*
X41900Y1081783D01*
G01X41525Y1083133D02*
X41733Y1083383D01*
X41858Y1083675D01*
X41900Y1084050D01*
X41817Y1084425D01*
X41650Y1084717D01*
X41358Y1084925D01*
X41025Y1084967D01*
X40692Y1084883D01*
X40483Y1084675D01*
X40317Y1084383D01*
X40275Y1084092D01*
X40317Y1083800D01*
X40483Y1083425D01*
X39400Y1083550D01*
Y1084675D01*
G01X41900Y1087150D02*
X41858Y1087442D01*
X41733Y1087775D01*
X41525Y1087983D01*
X41233Y1088067D01*
X40942Y1087983D01*
X40692Y1087733D01*
X40567Y1087358D01*
Y1086942D01*
X40483Y1086692D01*
X40275Y1086483D01*
X39983Y1086400D01*
X39692Y1086525D01*
X39483Y1086817D01*
X39400Y1087150D01*
X39483Y1087483D01*
X39692Y1087775D01*
X39983Y1087900D01*
X40275Y1087817D01*
X40483Y1087608D01*
X40567Y1087358D01*
Y1086942D01*
X40692Y1086567D01*
X40942Y1086317D01*
X41233Y1086233D01*
X41525Y1086317D01*
X41733Y1086525D01*
X41858Y1086858D01*
X41900Y1087150D01*
G01Y1090750D02*
X39400D01*
X41192Y1089208D01*
Y1091292D01*
G01X79200Y1162300D02*
X79158Y1161967D01*
X78992Y1161675D01*
X78742Y1161425D01*
X78450Y1161258D01*
X78117Y1161175D01*
X77783D01*
X77450Y1161258D01*
X77158Y1161425D01*
X76908Y1161675D01*
X76742Y1161967D01*
X76700Y1162300D01*
X76742Y1162633D01*
X76908Y1162925D01*
X77158Y1163175D01*
X77450Y1163342D01*
X77783Y1163425D01*
X78117D01*
X78450Y1163342D01*
X78742Y1163175D01*
X78992Y1162925D01*
X79158Y1162633D01*
X79200Y1162300D01*
G01X78533Y1162633D02*
X79200Y1163133D01*
G01Y1165400D02*
X76700D01*
X77200Y1164900D01*
G01X79200D02*
Y1165900D01*
G01X78825Y1167583D02*
X79033Y1167833D01*
X79158Y1168125D01*
X79200Y1168500D01*
X79117Y1168875D01*
X78950Y1169167D01*
X78658Y1169375D01*
X78325Y1169417D01*
X77992Y1169333D01*
X77783Y1169125D01*
X77617Y1168833D01*
X77575Y1168542D01*
X77617Y1168250D01*
X77783Y1167875D01*
X76700Y1168000D01*
Y1169125D01*
G01X102200Y1163400D02*
Y1177400D01*
G01X89200Y1163400D02*
X102200D01*
G01X89200Y1177400D02*
Y1163400D01*
G01X102200Y1177400D02*
X89200D01*
G01X95300Y1193000D02*
X94967Y1193042D01*
X94675Y1193208D01*
X94425Y1193458D01*
X94258Y1193750D01*
X94175Y1194083D01*
Y1194417D01*
X94258Y1194750D01*
X94425Y1195042D01*
X94675Y1195292D01*
X94967Y1195458D01*
X95300Y1195500D01*
X95633Y1195458D01*
X95925Y1195292D01*
X96175Y1195042D01*
X96342Y1194750D01*
X96425Y1194417D01*
Y1194083D01*
X96342Y1193750D01*
X96175Y1193458D01*
X95925Y1193208D01*
X95633Y1193042D01*
X95300Y1193000D01*
G01X95633Y1193667D02*
X96133Y1193000D01*
G01X97608Y1194042D02*
X97900Y1194333D01*
X98150Y1194500D01*
X98483Y1194583D01*
X98775Y1194500D01*
X98983Y1194333D01*
X99150Y1194083D01*
X99192Y1193792D01*
X99150Y1193542D01*
X98983Y1193292D01*
X98733Y1193083D01*
X98442Y1193000D01*
X98108Y1193083D01*
X97817Y1193333D01*
X97650Y1193708D01*
X97608Y1194125D01*
X97692Y1194667D01*
X97817Y1194958D01*
X98025Y1195250D01*
X98317Y1195458D01*
X98608Y1195500D01*
X98900Y1195417D01*
X99108Y1195208D01*
G01X100708Y1195083D02*
X100958Y1195333D01*
X101250Y1195458D01*
X101583Y1195500D01*
X102000Y1195417D01*
X102292Y1195208D01*
X102375Y1194958D01*
X102333Y1194708D01*
X102167Y1194500D01*
X101333Y1194083D01*
X100958Y1193792D01*
X100708Y1193375D01*
X100625Y1193000D01*
X102375D01*
G01X111000Y1191400D02*
X97000D01*
G01X111000Y1178400D02*
Y1191400D01*
G01X97000Y1178400D02*
X111000D01*
G01X97000Y1191400D02*
Y1178400D01*
G01X90357Y1146021D02*
Y1148521D01*
X91398D01*
X91732Y1148396D01*
X91940Y1148229D01*
X92023Y1147896D01*
X91940Y1147563D01*
X91690Y1147354D01*
X91398Y1147229D01*
X90357D01*
G01X91398D02*
X92023Y1146021D01*
G01X94290D02*
Y1148521D01*
X93790Y1148021D01*
G01Y1146021D02*
X94790D01*
G01X97890D02*
Y1148521D01*
X96348Y1146729D01*
X98432D01*
G01X99573Y1146396D02*
X99823Y1146188D01*
X100115Y1146063D01*
X100490Y1146021D01*
X100865Y1146104D01*
X101157Y1146271D01*
X101365Y1146563D01*
X101407Y1146896D01*
X101323Y1147229D01*
X101115Y1147438D01*
X100823Y1147604D01*
X100532Y1147646D01*
X100240Y1147604D01*
X99865Y1147438D01*
X99990Y1148521D01*
X101115D01*
G01X101400Y1158400D02*
Y1162400D01*
X94000D01*
G01X93200Y1158100D02*
X89200D01*
Y1150700D01*
G01X93700D02*
X97700D01*
Y1158100D01*
G01X73500Y1171467D02*
X71000D01*
Y1172508D01*
X71125Y1172842D01*
X71292Y1173050D01*
X71625Y1173133D01*
X71958Y1173050D01*
X72167Y1172800D01*
X72292Y1172508D01*
Y1171467D01*
G01Y1172508D02*
X73500Y1173133D01*
G01X73208Y1174692D02*
X73417Y1174983D01*
X73500Y1175317D01*
X73417Y1175650D01*
X73167Y1175942D01*
X72792Y1176150D01*
X72417Y1176233D01*
X71958D01*
X71583Y1176150D01*
X71250Y1175942D01*
X71083Y1175692D01*
X71000Y1175400D01*
X71083Y1175067D01*
X71250Y1174817D01*
X71500Y1174650D01*
X71833Y1174567D01*
X72125Y1174650D01*
X72417Y1174858D01*
X72583Y1175108D01*
X72625Y1175400D01*
X72542Y1175733D01*
X72333Y1175983D01*
X71958Y1176233D01*
G01X72458Y1177708D02*
X72167Y1178000D01*
X72000Y1178250D01*
X71917Y1178583D01*
X72000Y1178875D01*
X72167Y1179083D01*
X72417Y1179250D01*
X72708Y1179292D01*
X72958Y1179250D01*
X73208Y1179083D01*
X73417Y1178833D01*
X73500Y1178542D01*
X73417Y1178208D01*
X73167Y1177917D01*
X72792Y1177750D01*
X72375Y1177708D01*
X71833Y1177792D01*
X71542Y1177917D01*
X71250Y1178125D01*
X71042Y1178417D01*
X71000Y1178708D01*
X71083Y1179000D01*
X71292Y1179208D01*
G01X73500Y1181600D02*
X71000D01*
X71500Y1181100D01*
G01X73500D02*
Y1182100D01*
G01Y1184700D02*
X73458Y1184992D01*
X73333Y1185325D01*
X73125Y1185533D01*
X72833Y1185617D01*
X72542Y1185533D01*
X72292Y1185283D01*
X72167Y1184908D01*
Y1184492D01*
X72083Y1184242D01*
X71875Y1184033D01*
X71583Y1183950D01*
X71292Y1184075D01*
X71083Y1184367D01*
X71000Y1184700D01*
X71083Y1185033D01*
X71292Y1185325D01*
X71583Y1185450D01*
X71875Y1185367D01*
X72083Y1185158D01*
X72167Y1184908D01*
Y1184492D01*
X72292Y1184117D01*
X72542Y1183867D01*
X72833Y1183783D01*
X73125Y1183867D01*
X73333Y1184075D01*
X73458Y1184408D01*
X73500Y1184700D01*
G01X88000Y1178300D02*
X92000D01*
Y1185700D01*
G01X78500Y1171967D02*
X76000D01*
Y1173008D01*
X76125Y1173342D01*
X76292Y1173550D01*
X76625Y1173633D01*
X76958Y1173550D01*
X77167Y1173300D01*
X77292Y1173008D01*
Y1171967D01*
G01Y1173008D02*
X78500Y1173633D01*
G01X78208Y1175192D02*
X78417Y1175483D01*
X78500Y1175817D01*
X78417Y1176150D01*
X78167Y1176442D01*
X77792Y1176650D01*
X77417Y1176733D01*
X76958D01*
X76583Y1176650D01*
X76250Y1176442D01*
X76083Y1176192D01*
X76000Y1175900D01*
X76083Y1175567D01*
X76250Y1175317D01*
X76500Y1175150D01*
X76833Y1175067D01*
X77125Y1175150D01*
X77417Y1175358D01*
X77583Y1175608D01*
X77625Y1175900D01*
X77542Y1176233D01*
X77333Y1176483D01*
X76958Y1176733D01*
G01X78500Y1178917D02*
X77958Y1179000D01*
X77500Y1179125D01*
X77083Y1179292D01*
X76625Y1179500D01*
X76000Y1179833D01*
Y1178167D01*
G01X77458Y1181308D02*
X77167Y1181600D01*
X77000Y1181850D01*
X76917Y1182183D01*
X77000Y1182475D01*
X77167Y1182683D01*
X77417Y1182850D01*
X77708Y1182892D01*
X77958Y1182850D01*
X78208Y1182683D01*
X78417Y1182433D01*
X78500Y1182142D01*
X78417Y1181808D01*
X78167Y1181517D01*
X77792Y1181350D01*
X77375Y1181308D01*
X76833Y1181392D01*
X76542Y1181517D01*
X76250Y1181725D01*
X76042Y1182017D01*
X76000Y1182308D01*
X76083Y1182600D01*
X76292Y1182808D01*
G01X78500Y1185117D02*
X77958Y1185200D01*
X77500Y1185325D01*
X77083Y1185492D01*
X76625Y1185700D01*
X76000Y1186033D01*
Y1184367D01*
G01X96500Y1185700D02*
X92500D01*
Y1178300D01*
G01X74467Y1192500D02*
Y1195000D01*
X75508D01*
X75842Y1194875D01*
X76050Y1194708D01*
X76133Y1194375D01*
X76050Y1194042D01*
X75800Y1193833D01*
X75508Y1193708D01*
X74467D01*
G01X75508D02*
X76133Y1192500D01*
G01X77692Y1192792D02*
X77983Y1192583D01*
X78317Y1192500D01*
X78650Y1192583D01*
X78942Y1192833D01*
X79150Y1193208D01*
X79233Y1193583D01*
Y1194042D01*
X79150Y1194417D01*
X78942Y1194750D01*
X78692Y1194917D01*
X78400Y1195000D01*
X78067Y1194917D01*
X77817Y1194750D01*
X77650Y1194500D01*
X77567Y1194167D01*
X77650Y1193875D01*
X77858Y1193583D01*
X78108Y1193417D01*
X78400Y1193375D01*
X78733Y1193458D01*
X78983Y1193667D01*
X79233Y1194042D01*
G01X81500Y1192500D02*
X81792Y1192542D01*
X82125Y1192667D01*
X82333Y1192875D01*
X82417Y1193167D01*
X82333Y1193458D01*
X82083Y1193708D01*
X81708Y1193833D01*
X81292D01*
X81042Y1193917D01*
X80833Y1194125D01*
X80750Y1194417D01*
X80875Y1194708D01*
X81167Y1194917D01*
X81500Y1195000D01*
X81833Y1194917D01*
X82125Y1194708D01*
X82250Y1194417D01*
X82167Y1194125D01*
X81958Y1193917D01*
X81708Y1193833D01*
X81292D01*
X80917Y1193708D01*
X80667Y1193458D01*
X80583Y1193167D01*
X80667Y1192875D01*
X80875Y1192667D01*
X81208Y1192542D01*
X81500Y1192500D01*
G01X83808Y1194583D02*
X84058Y1194833D01*
X84350Y1194958D01*
X84683Y1195000D01*
X85100Y1194917D01*
X85392Y1194708D01*
X85475Y1194458D01*
X85433Y1194208D01*
X85267Y1194000D01*
X84433Y1193583D01*
X84058Y1193292D01*
X83808Y1192875D01*
X83725Y1192500D01*
X85475D01*
G01X87617D02*
X87700Y1193042D01*
X87825Y1193500D01*
X87992Y1193917D01*
X88200Y1194375D01*
X88533Y1195000D01*
X86867D01*
G01X83475Y1190775D02*
Y1186775D01*
X90875D01*
G01X105967Y1193000D02*
Y1195500D01*
X107008D01*
X107342Y1195375D01*
X107550Y1195208D01*
X107633Y1194875D01*
X107550Y1194542D01*
X107300Y1194333D01*
X107008Y1194208D01*
X105967D01*
G01X107008D02*
X107633Y1193000D01*
G01X109192Y1193292D02*
X109483Y1193083D01*
X109817Y1193000D01*
X110150Y1193083D01*
X110442Y1193333D01*
X110650Y1193708D01*
X110733Y1194083D01*
Y1194542D01*
X110650Y1194917D01*
X110442Y1195250D01*
X110192Y1195417D01*
X109900Y1195500D01*
X109567Y1195417D01*
X109317Y1195250D01*
X109150Y1195000D01*
X109067Y1194667D01*
X109150Y1194375D01*
X109358Y1194083D01*
X109608Y1193917D01*
X109900Y1193875D01*
X110233Y1193958D01*
X110483Y1194167D01*
X110733Y1194542D01*
G01X113000Y1193000D02*
X113292Y1193042D01*
X113625Y1193167D01*
X113833Y1193375D01*
X113917Y1193667D01*
X113833Y1193958D01*
X113583Y1194208D01*
X113208Y1194333D01*
X112792D01*
X112542Y1194417D01*
X112333Y1194625D01*
X112250Y1194917D01*
X112375Y1195208D01*
X112667Y1195417D01*
X113000Y1195500D01*
X113333Y1195417D01*
X113625Y1195208D01*
X113750Y1194917D01*
X113667Y1194625D01*
X113458Y1194417D01*
X113208Y1194333D01*
X112792D01*
X112417Y1194208D01*
X112167Y1193958D01*
X112083Y1193667D01*
X112167Y1193375D01*
X112375Y1193167D01*
X112708Y1193042D01*
X113000Y1193000D01*
G01X115308Y1195083D02*
X115558Y1195333D01*
X115850Y1195458D01*
X116183Y1195500D01*
X116600Y1195417D01*
X116892Y1195208D01*
X116975Y1194958D01*
X116933Y1194708D01*
X116767Y1194500D01*
X115933Y1194083D01*
X115558Y1193792D01*
X115308Y1193375D01*
X115225Y1193000D01*
X116975D01*
G01X119200D02*
X119492Y1193042D01*
X119825Y1193167D01*
X120033Y1193375D01*
X120117Y1193667D01*
X120033Y1193958D01*
X119783Y1194208D01*
X119408Y1194333D01*
X118992D01*
X118742Y1194417D01*
X118533Y1194625D01*
X118450Y1194917D01*
X118575Y1195208D01*
X118867Y1195417D01*
X119200Y1195500D01*
X119533Y1195417D01*
X119825Y1195208D01*
X119950Y1194917D01*
X119867Y1194625D01*
X119658Y1194417D01*
X119408Y1194333D01*
X118992D01*
X118617Y1194208D01*
X118367Y1193958D01*
X118283Y1193667D01*
X118367Y1193375D01*
X118575Y1193167D01*
X118908Y1193042D01*
X119200Y1193000D01*
G01X94417Y1204500D02*
Y1207000D01*
X95458D01*
X95792Y1206875D01*
X96000Y1206708D01*
X96083Y1206375D01*
X96000Y1206042D01*
X95750Y1205833D01*
X95458Y1205708D01*
X94417D01*
G01X95458D02*
X96083Y1204500D01*
G01X97642Y1204792D02*
X97933Y1204583D01*
X98267Y1204500D01*
X98600Y1204583D01*
X98892Y1204833D01*
X99100Y1205208D01*
X99183Y1205583D01*
Y1206042D01*
X99100Y1206417D01*
X98892Y1206750D01*
X98642Y1206917D01*
X98350Y1207000D01*
X98017Y1206917D01*
X97767Y1206750D01*
X97600Y1206500D01*
X97517Y1206167D01*
X97600Y1205875D01*
X97808Y1205583D01*
X98058Y1205417D01*
X98350Y1205375D01*
X98683Y1205458D01*
X98933Y1205667D01*
X99183Y1206042D01*
G01X101450Y1204500D02*
X101742Y1204542D01*
X102075Y1204667D01*
X102283Y1204875D01*
X102367Y1205167D01*
X102283Y1205458D01*
X102033Y1205708D01*
X101658Y1205833D01*
X101242D01*
X100992Y1205917D01*
X100783Y1206125D01*
X100700Y1206417D01*
X100825Y1206708D01*
X101117Y1206917D01*
X101450Y1207000D01*
X101783Y1206917D01*
X102075Y1206708D01*
X102200Y1206417D01*
X102117Y1206125D01*
X101908Y1205917D01*
X101658Y1205833D01*
X101242D01*
X100867Y1205708D01*
X100617Y1205458D01*
X100533Y1205167D01*
X100617Y1204875D01*
X100825Y1204667D01*
X101158Y1204542D01*
X101450Y1204500D01*
G01X103633Y1204875D02*
X103883Y1204667D01*
X104175Y1204542D01*
X104550Y1204500D01*
X104925Y1204583D01*
X105217Y1204750D01*
X105425Y1205042D01*
X105467Y1205375D01*
X105383Y1205708D01*
X105175Y1205917D01*
X104883Y1206083D01*
X104592Y1206125D01*
X104300Y1206083D01*
X103925Y1205917D01*
X104050Y1207000D01*
X105175D01*
G01X107650D02*
X107317Y1206917D01*
X107067Y1206708D01*
X106900Y1206458D01*
X106775Y1206125D01*
X106733Y1205750D01*
X106775Y1205375D01*
X106900Y1205042D01*
X107067Y1204792D01*
X107317Y1204583D01*
X107650Y1204500D01*
X107983Y1204583D01*
X108233Y1204792D01*
X108400Y1205042D01*
X108525Y1205375D01*
X108567Y1205750D01*
X108525Y1206125D01*
X108400Y1206458D01*
X108233Y1206708D01*
X107983Y1206917D01*
X107650Y1207000D01*
G01X94600Y1208300D02*
X102400D01*
G01X94600Y1215300D02*
Y1208300D01*
G01X108000D02*
Y1215300D01*
G01X101600Y1208300D02*
X108000D01*
G01X105483Y1149500D02*
Y1147708D01*
X105650Y1147333D01*
X105983Y1147083D01*
X106400Y1147000D01*
X106817Y1147083D01*
X107150Y1147333D01*
X107317Y1147708D01*
Y1149500D01*
G01X109500Y1147000D02*
Y1149500D01*
X109000Y1149000D01*
G01Y1147000D02*
X110000D01*
G01X111808Y1148042D02*
X112100Y1148333D01*
X112350Y1148500D01*
X112683Y1148583D01*
X112975Y1148500D01*
X113183Y1148333D01*
X113350Y1148083D01*
X113392Y1147792D01*
X113350Y1147542D01*
X113183Y1147292D01*
X112933Y1147083D01*
X112642Y1147000D01*
X112308Y1147083D01*
X112017Y1147333D01*
X111850Y1147708D01*
X111808Y1148125D01*
X111892Y1148667D01*
X112017Y1148958D01*
X112225Y1149250D01*
X112517Y1149458D01*
X112808Y1149500D01*
X113100Y1149417D01*
X113308Y1149208D01*
G01X74467Y1204200D02*
Y1206700D01*
X75508D01*
X75842Y1206575D01*
X76050Y1206408D01*
X76133Y1206075D01*
X76050Y1205742D01*
X75800Y1205533D01*
X75508Y1205408D01*
X74467D01*
G01X75508D02*
X76133Y1204200D01*
G01X77692Y1204492D02*
X77983Y1204283D01*
X78317Y1204200D01*
X78650Y1204283D01*
X78942Y1204533D01*
X79150Y1204908D01*
X79233Y1205283D01*
Y1205742D01*
X79150Y1206117D01*
X78942Y1206450D01*
X78692Y1206617D01*
X78400Y1206700D01*
X78067Y1206617D01*
X77817Y1206450D01*
X77650Y1206200D01*
X77567Y1205867D01*
X77650Y1205575D01*
X77858Y1205283D01*
X78108Y1205117D01*
X78400Y1205075D01*
X78733Y1205158D01*
X78983Y1205367D01*
X79233Y1205742D01*
G01X80708Y1206283D02*
X80958Y1206533D01*
X81250Y1206658D01*
X81583Y1206700D01*
X82000Y1206617D01*
X82292Y1206408D01*
X82375Y1206158D01*
X82333Y1205908D01*
X82167Y1205700D01*
X81333Y1205283D01*
X80958Y1204992D01*
X80708Y1204575D01*
X80625Y1204200D01*
X82375D01*
G01X83808Y1205242D02*
X84100Y1205533D01*
X84350Y1205700D01*
X84683Y1205783D01*
X84975Y1205700D01*
X85183Y1205533D01*
X85350Y1205283D01*
X85392Y1204992D01*
X85350Y1204742D01*
X85183Y1204492D01*
X84933Y1204283D01*
X84642Y1204200D01*
X84308Y1204283D01*
X84017Y1204533D01*
X83850Y1204908D01*
X83808Y1205325D01*
X83892Y1205867D01*
X84017Y1206158D01*
X84225Y1206450D01*
X84517Y1206658D01*
X84808Y1206700D01*
X85100Y1206617D01*
X85308Y1206408D01*
G01X87700Y1206700D02*
X87367Y1206617D01*
X87117Y1206408D01*
X86950Y1206158D01*
X86825Y1205825D01*
X86783Y1205450D01*
X86825Y1205075D01*
X86950Y1204742D01*
X87117Y1204492D01*
X87367Y1204283D01*
X87700Y1204200D01*
X88033Y1204283D01*
X88283Y1204492D01*
X88450Y1204742D01*
X88575Y1205075D01*
X88617Y1205450D01*
X88575Y1205825D01*
X88450Y1206158D01*
X88283Y1206408D01*
X88033Y1206617D01*
X87700Y1206700D01*
G01X74834Y1161483D02*
X72334D01*
Y1162317D01*
X72459Y1162650D01*
X72626Y1162900D01*
X72876Y1163108D01*
X73167Y1163275D01*
X73584Y1163317D01*
X74001Y1163275D01*
X74292Y1163108D01*
X74542Y1162900D01*
X74709Y1162650D01*
X74834Y1162317D01*
Y1161483D01*
G01X72751Y1164708D02*
X72501Y1164958D01*
X72376Y1165250D01*
X72334Y1165583D01*
X72417Y1166000D01*
X72626Y1166292D01*
X72876Y1166375D01*
X73126Y1166333D01*
X73334Y1166167D01*
X73751Y1165333D01*
X74042Y1164958D01*
X74459Y1164708D01*
X74834Y1164625D01*
Y1166375D01*
G01X74459Y1167683D02*
X74667Y1167933D01*
X74792Y1168225D01*
X74834Y1168600D01*
X74751Y1168975D01*
X74584Y1169267D01*
X74292Y1169475D01*
X73959Y1169517D01*
X73626Y1169433D01*
X73417Y1169225D01*
X73251Y1168933D01*
X73209Y1168642D01*
X73251Y1168350D01*
X73417Y1167975D01*
X72334Y1168100D01*
Y1169225D01*
G01X81200Y1155400D02*
Y1171500D01*
G01X88200Y1155400D02*
X81200D01*
G01X88200Y1171500D02*
Y1155400D01*
G01X81200Y1171500D02*
X88200D01*
G01X115467Y1323793D02*
X114634Y1322460D01*
X114134Y1320960D01*
Y1319626D01*
X114634Y1318293D01*
X115467Y1317293D01*
X116634Y1316793D01*
X117800Y1317126D01*
X118801Y1317960D01*
X119467Y1319460D01*
X119801Y1321460D01*
X120467Y1322626D01*
X121634Y1323126D01*
X122801Y1322793D01*
X123634Y1321960D01*
X124134Y1320793D01*
Y1319626D01*
X123801Y1318460D01*
X122967Y1317460D01*
G01X115467Y1313193D02*
X114634Y1311860D01*
X114134Y1310360D01*
Y1309026D01*
X114634Y1307693D01*
X115467Y1306693D01*
X116634Y1306193D01*
X117800Y1306526D01*
X118801Y1307360D01*
X119467Y1308860D01*
X119801Y1310860D01*
X120467Y1312026D01*
X121634Y1312526D01*
X122801Y1312193D01*
X123634Y1311360D01*
X124134Y1310193D01*
Y1309026D01*
X123801Y1307860D01*
X122967Y1306860D01*
G01X114134Y1302760D02*
X124134D01*
Y1299426D01*
X123634Y1298093D01*
X122967Y1297093D01*
X121967Y1296260D01*
X120800Y1295593D01*
X119134Y1295426D01*
X117467Y1295593D01*
X116301Y1296260D01*
X115300Y1297093D01*
X114634Y1298093D01*
X114134Y1299426D01*
Y1302760D01*
G01Y1288493D02*
X124134D01*
X122134Y1290493D01*
G01X114134D02*
Y1286493D01*
G01Y1277893D02*
X124134D01*
X122134Y1279893D01*
G01X114134D02*
Y1275893D01*
G01X105500Y1258017D02*
X103000D01*
Y1259017D01*
X103125Y1259350D01*
X103417Y1259600D01*
X103750Y1259683D01*
X104083Y1259600D01*
X104333Y1259392D01*
X104458Y1259017D01*
Y1258017D01*
G01X103208Y1262867D02*
X103083Y1262617D01*
X103000Y1262325D01*
Y1261992D01*
X103125Y1261617D01*
X103333Y1261325D01*
X103583Y1261117D01*
X104000Y1260950D01*
X104375Y1260908D01*
X104750Y1260992D01*
X105000Y1261117D01*
X105250Y1261367D01*
X105417Y1261658D01*
X105500Y1261950D01*
Y1262242D01*
X105417Y1262533D01*
X105292Y1262783D01*
X105125Y1262992D01*
G01X105500Y1265050D02*
X103000D01*
X103500Y1264550D01*
G01X105500D02*
Y1265550D01*
G01X103417Y1267358D02*
X103167Y1267608D01*
X103042Y1267900D01*
X103000Y1268233D01*
X103083Y1268650D01*
X103292Y1268942D01*
X103542Y1269025D01*
X103792Y1268983D01*
X104000Y1268817D01*
X104417Y1267983D01*
X104708Y1267608D01*
X105125Y1267358D01*
X105500Y1267275D01*
Y1269025D01*
G01X103417Y1270458D02*
X103167Y1270708D01*
X103042Y1271000D01*
X103000Y1271333D01*
X103083Y1271750D01*
X103292Y1272042D01*
X103542Y1272125D01*
X103792Y1272083D01*
X104000Y1271917D01*
X104417Y1271083D01*
X104708Y1270708D01*
X105125Y1270458D01*
X105500Y1270375D01*
Y1272125D01*
G01X105000Y1273433D02*
X105292Y1273683D01*
X105458Y1274017D01*
X105500Y1274392D01*
X105458Y1274725D01*
X105250Y1275058D01*
X105000Y1275267D01*
X104750Y1275308D01*
X104458Y1275225D01*
X104250Y1274933D01*
X104167Y1274642D01*
Y1274267D01*
G01Y1274642D02*
X104042Y1274892D01*
X103833Y1275100D01*
X103583Y1275183D01*
X103333Y1275100D01*
X103125Y1274892D01*
X103000Y1274517D01*
X103042Y1274142D01*
X103208Y1273767D01*
G01X94500Y1217917D02*
X92000D01*
Y1218917D01*
X92125Y1219250D01*
X92417Y1219500D01*
X92750Y1219583D01*
X93083Y1219500D01*
X93333Y1219292D01*
X93458Y1218917D01*
Y1217917D01*
G01X92208Y1222767D02*
X92083Y1222517D01*
X92000Y1222225D01*
Y1221892D01*
X92125Y1221517D01*
X92333Y1221225D01*
X92583Y1221017D01*
X93000Y1220850D01*
X93375Y1220808D01*
X93750Y1220892D01*
X94000Y1221017D01*
X94250Y1221267D01*
X94417Y1221558D01*
X94500Y1221850D01*
Y1222142D01*
X94417Y1222433D01*
X94292Y1222683D01*
X94125Y1222892D01*
G01X94500Y1224950D02*
X92000D01*
X92500Y1224450D01*
G01X94500D02*
Y1225450D01*
G01X92417Y1227258D02*
X92167Y1227508D01*
X92042Y1227800D01*
X92000Y1228133D01*
X92083Y1228550D01*
X92292Y1228842D01*
X92542Y1228925D01*
X92792Y1228883D01*
X93000Y1228717D01*
X93417Y1227883D01*
X93708Y1227508D01*
X94125Y1227258D01*
X94500Y1227175D01*
Y1228925D01*
G01X92417Y1230358D02*
X92167Y1230608D01*
X92042Y1230900D01*
X92000Y1231233D01*
X92083Y1231650D01*
X92292Y1231942D01*
X92542Y1232025D01*
X92792Y1231983D01*
X93000Y1231817D01*
X93417Y1230983D01*
X93708Y1230608D01*
X94125Y1230358D01*
X94500Y1230275D01*
Y1232025D01*
G01X92417Y1233458D02*
X92167Y1233708D01*
X92042Y1234000D01*
X92000Y1234333D01*
X92083Y1234750D01*
X92292Y1235042D01*
X92542Y1235125D01*
X92792Y1235083D01*
X93000Y1234917D01*
X93417Y1234083D01*
X93708Y1233708D01*
X94125Y1233458D01*
X94500Y1233375D01*
Y1235125D01*
G01X94600Y1215300D02*
X99800D01*
G01X108000D02*
X99300D01*
G01X64400Y1225200D02*
Y1212200D01*
G01X90400Y1225200D02*
X64400D01*
G01X90400Y1212200D02*
Y1225200D01*
G01X64400Y1212200D02*
X90400D01*
G01X101250Y1218050D02*
Y1236750D01*
X111550D01*
Y1218050D01*
X101250D01*
G01X112800Y1258217D02*
X110300D01*
Y1259217D01*
X110425Y1259550D01*
X110717Y1259800D01*
X111050Y1259883D01*
X111383Y1259800D01*
X111633Y1259592D01*
X111758Y1259217D01*
Y1258217D01*
G01X110508Y1263067D02*
X110383Y1262817D01*
X110300Y1262525D01*
Y1262192D01*
X110425Y1261817D01*
X110633Y1261525D01*
X110883Y1261317D01*
X111300Y1261150D01*
X111675Y1261108D01*
X112050Y1261192D01*
X112300Y1261317D01*
X112550Y1261567D01*
X112717Y1261858D01*
X112800Y1262150D01*
Y1262442D01*
X112717Y1262733D01*
X112592Y1262983D01*
X112425Y1263192D01*
G01X112800Y1265250D02*
X110300D01*
X110800Y1264750D01*
G01X112800D02*
Y1265750D01*
G01X110717Y1267558D02*
X110467Y1267808D01*
X110342Y1268100D01*
X110300Y1268433D01*
X110383Y1268850D01*
X110592Y1269142D01*
X110842Y1269225D01*
X111092Y1269183D01*
X111300Y1269017D01*
X111717Y1268183D01*
X112008Y1267808D01*
X112425Y1267558D01*
X112800Y1267475D01*
Y1269225D01*
G01X110717Y1270658D02*
X110467Y1270908D01*
X110342Y1271200D01*
X110300Y1271533D01*
X110383Y1271950D01*
X110592Y1272242D01*
X110842Y1272325D01*
X111092Y1272283D01*
X111300Y1272117D01*
X111717Y1271283D01*
X112008Y1270908D01*
X112425Y1270658D01*
X112800Y1270575D01*
Y1272325D01*
G01Y1274550D02*
X110300D01*
X110800Y1274050D01*
G01X112800D02*
Y1275050D01*
G01X111550Y1256150D02*
Y1237450D01*
X101250D01*
Y1256150D01*
X111550D01*
G01X101000Y1322067D02*
X101250Y1322275D01*
X101417Y1322525D01*
X101500Y1322817D01*
X101417Y1323150D01*
X101250Y1323400D01*
X101000Y1323650D01*
X100667Y1323733D01*
X99000D01*
G01X101500Y1326000D02*
X99000D01*
X99500Y1325500D01*
G01X101500D02*
Y1326500D01*
G01Y1329100D02*
X99000D01*
X99500Y1328600D01*
G01X101500D02*
Y1329600D01*
G01X108620Y1329927D02*
X106120D01*
Y1330927D01*
X106245Y1331260D01*
X106537Y1331510D01*
X106870Y1331593D01*
X107203Y1331510D01*
X107453Y1331302D01*
X107578Y1330927D01*
Y1329927D01*
G01X106328Y1334777D02*
X106203Y1334527D01*
X106120Y1334235D01*
Y1333902D01*
X106245Y1333527D01*
X106453Y1333235D01*
X106703Y1333027D01*
X107120Y1332860D01*
X107495Y1332818D01*
X107870Y1332902D01*
X108120Y1333027D01*
X108370Y1333277D01*
X108537Y1333568D01*
X108620Y1333860D01*
Y1334152D01*
X108537Y1334443D01*
X108412Y1334693D01*
X108245Y1334902D01*
G01X108620Y1336960D02*
X106120D01*
X106620Y1336460D01*
G01X108620D02*
Y1337460D01*
G01X106537Y1339268D02*
X106287Y1339518D01*
X106162Y1339810D01*
X106120Y1340143D01*
X106203Y1340560D01*
X106412Y1340852D01*
X106662Y1340935D01*
X106912Y1340893D01*
X107120Y1340727D01*
X107537Y1339893D01*
X107828Y1339518D01*
X108245Y1339268D01*
X108620Y1339185D01*
Y1340935D01*
G01X106537Y1342368D02*
X106287Y1342618D01*
X106162Y1342910D01*
X106120Y1343243D01*
X106203Y1343660D01*
X106412Y1343952D01*
X106662Y1344035D01*
X106912Y1343993D01*
X107120Y1343827D01*
X107537Y1342993D01*
X107828Y1342618D01*
X108245Y1342368D01*
X108620Y1342285D01*
Y1344035D01*
G01Y1346760D02*
X106120D01*
X107912Y1345218D01*
Y1347302D01*
G01X84075Y1404033D02*
X84408Y1403825D01*
X84783Y1403700D01*
X85117D01*
X85450Y1403825D01*
X85700Y1404033D01*
X85825Y1404325D01*
X85742Y1404617D01*
X85533Y1404867D01*
X85158Y1405033D01*
X84658Y1405117D01*
X84367Y1405283D01*
X84242Y1405575D01*
X84325Y1405867D01*
X84533Y1406075D01*
X84825Y1406200D01*
X85117D01*
X85408Y1406117D01*
X85658Y1405908D01*
G01X87133Y1403700D02*
Y1406200D01*
X87967D01*
X88300Y1406075D01*
X88550Y1405908D01*
X88758Y1405658D01*
X88925Y1405367D01*
X88967Y1404950D01*
X88925Y1404533D01*
X88758Y1404242D01*
X88550Y1403992D01*
X88300Y1403825D01*
X87967Y1403700D01*
X87133D01*
G01X90233D02*
Y1406200D01*
X91067D01*
X91400Y1406075D01*
X91650Y1405908D01*
X91858Y1405658D01*
X92025Y1405367D01*
X92067Y1404950D01*
X92025Y1404533D01*
X91858Y1404242D01*
X91650Y1403992D01*
X91400Y1403825D01*
X91067Y1403700D01*
X90233D01*
G01X96308D02*
X97350Y1406200D01*
X98392Y1403700D01*
G01X98017Y1404575D02*
X96683D01*
G01X101367Y1405992D02*
X101117Y1406117D01*
X100825Y1406200D01*
X100492D01*
X100117Y1406075D01*
X99825Y1405867D01*
X99617Y1405617D01*
X99450Y1405200D01*
X99408Y1404825D01*
X99492Y1404450D01*
X99617Y1404200D01*
X99867Y1403950D01*
X100158Y1403783D01*
X100450Y1403700D01*
X100742D01*
X101033Y1403783D01*
X101283Y1403908D01*
X101492Y1404075D01*
G01X103550Y1406200D02*
Y1403700D01*
G01X102592Y1406200D02*
X104508D01*
G01X106650Y1403700D02*
Y1406200D01*
X106150Y1405700D01*
G01Y1403700D02*
X107150D01*
G01X109750D02*
Y1406200D01*
X109250Y1405700D01*
G01Y1403700D02*
X110250D01*
G01X84117Y1408700D02*
Y1411200D01*
X85117D01*
X85450Y1411075D01*
X85700Y1410783D01*
X85783Y1410450D01*
X85700Y1410117D01*
X85492Y1409867D01*
X85117Y1409742D01*
X84117D01*
G01X88883Y1408700D02*
X87217D01*
Y1411200D01*
X88883D01*
G01X88217Y1409992D02*
X87217D01*
G01X91483Y1410033D02*
X91650Y1410158D01*
X91775Y1410367D01*
X91858Y1410658D01*
X91775Y1410908D01*
X91608Y1411075D01*
X91317Y1411200D01*
X90192D01*
Y1408700D01*
X91567D01*
X91858Y1408867D01*
X92025Y1409117D01*
X92108Y1409408D01*
X92025Y1409700D01*
X91775Y1409950D01*
X91483Y1410033D01*
X90192D01*
G01X96308Y1408700D02*
X97350Y1411200D01*
X98392Y1408700D01*
G01X98017Y1409575D02*
X96683D01*
G01X100450Y1411200D02*
Y1408700D01*
G01X99492Y1411200D02*
X101408D01*
G01X103550D02*
Y1408700D01*
G01X102592Y1411200D02*
X104508D01*
G01X105692Y1408700D02*
Y1411200D01*
X107608Y1408700D01*
Y1411200D01*
G01X109750Y1408700D02*
Y1411200D01*
X109250Y1410700D01*
G01Y1408700D02*
X110250D01*
G01X112850D02*
Y1411200D01*
X112350Y1410700D01*
G01Y1408700D02*
X113350D01*
G01X56833Y1418967D02*
X59333D01*
Y1420633D01*
G01Y1423733D02*
Y1422067D01*
X56833D01*
Y1423733D01*
G01X58041Y1423067D02*
Y1422067D01*
G01X59333Y1425083D02*
X56833D01*
Y1425917D01*
X56958Y1426250D01*
X57125Y1426500D01*
X57375Y1426708D01*
X57666Y1426875D01*
X58083Y1426917D01*
X58500Y1426875D01*
X58791Y1426708D01*
X59041Y1426500D01*
X59208Y1426250D01*
X59333Y1425917D01*
Y1425083D01*
G01Y1429100D02*
X56833D01*
X57333Y1428600D01*
G01X59333D02*
Y1429600D01*
G01Y1432200D02*
X56833D01*
X57333Y1431700D01*
G01X59333D02*
Y1432700D01*
G01X67135Y1421003D02*
Y1428603D01*
X78535D01*
Y1421003D01*
X67135D01*
G01X101917Y1424300D02*
Y1426800D01*
X102958D01*
X103292Y1426675D01*
X103500Y1426508D01*
X103583Y1426175D01*
X103500Y1425842D01*
X103250Y1425633D01*
X102958Y1425508D01*
X101917D01*
G01X102958D02*
X103583Y1424300D01*
G01X105142Y1424592D02*
X105433Y1424383D01*
X105767Y1424300D01*
X106100Y1424383D01*
X106392Y1424633D01*
X106600Y1425008D01*
X106683Y1425383D01*
Y1425842D01*
X106600Y1426217D01*
X106392Y1426550D01*
X106142Y1426717D01*
X105850Y1426800D01*
X105517Y1426717D01*
X105267Y1426550D01*
X105100Y1426300D01*
X105017Y1425967D01*
X105100Y1425675D01*
X105308Y1425383D01*
X105558Y1425217D01*
X105850Y1425175D01*
X106183Y1425258D01*
X106433Y1425467D01*
X106683Y1425842D01*
G01X109450Y1424300D02*
Y1426800D01*
X107908Y1425008D01*
X109992D01*
G01X111133Y1424800D02*
X111383Y1424508D01*
X111717Y1424342D01*
X112092Y1424300D01*
X112425Y1424342D01*
X112758Y1424550D01*
X112967Y1424800D01*
X113008Y1425050D01*
X112925Y1425342D01*
X112633Y1425550D01*
X112342Y1425633D01*
X111967D01*
G01X112342D02*
X112592Y1425758D01*
X112800Y1425967D01*
X112883Y1426217D01*
X112800Y1426467D01*
X112592Y1426675D01*
X112217Y1426800D01*
X111842Y1426758D01*
X111467Y1426592D01*
G01X114233Y1424675D02*
X114483Y1424467D01*
X114775Y1424342D01*
X115150Y1424300D01*
X115525Y1424383D01*
X115817Y1424550D01*
X116025Y1424842D01*
X116067Y1425175D01*
X115983Y1425508D01*
X115775Y1425717D01*
X115483Y1425883D01*
X115192Y1425925D01*
X114900Y1425883D01*
X114525Y1425717D01*
X114650Y1426800D01*
X115775D01*
G01X98200Y1424500D02*
Y1428500D01*
X90800D01*
G01X101875Y1428633D02*
X102208Y1428425D01*
X102583Y1428300D01*
X102917D01*
X103250Y1428425D01*
X103500Y1428633D01*
X103625Y1428925D01*
X103542Y1429217D01*
X103333Y1429467D01*
X102958Y1429633D01*
X102458Y1429717D01*
X102167Y1429883D01*
X102042Y1430175D01*
X102125Y1430467D01*
X102333Y1430675D01*
X102625Y1430800D01*
X102917D01*
X103208Y1430717D01*
X103458Y1430508D01*
G01X105017Y1428300D02*
Y1430800D01*
X106058D01*
X106392Y1430675D01*
X106600Y1430508D01*
X106683Y1430175D01*
X106600Y1429842D01*
X106350Y1429633D01*
X106058Y1429508D01*
X105017D01*
G01X106058D02*
X106683Y1428300D01*
G01X108950D02*
Y1430800D01*
X108450Y1430300D01*
G01Y1428300D02*
X109450D01*
G01X112050D02*
Y1430800D01*
X111550Y1430300D01*
G01Y1428300D02*
X112550D01*
G01X115650D02*
Y1430800D01*
X114108Y1429008D01*
X116192D01*
G01X117333Y1428800D02*
X117583Y1428508D01*
X117917Y1428342D01*
X118292Y1428300D01*
X118625Y1428342D01*
X118958Y1428550D01*
X119167Y1428800D01*
X119208Y1429050D01*
X119125Y1429342D01*
X118833Y1429550D01*
X118542Y1429633D01*
X118167D01*
G01X118542D02*
X118792Y1429758D01*
X119000Y1429967D01*
X119083Y1430217D01*
X119000Y1430467D01*
X118792Y1430675D01*
X118417Y1430800D01*
X118042Y1430758D01*
X117667Y1430592D01*
G01X98200Y1429000D02*
Y1433000D01*
X90800D01*
G01X101917Y1416300D02*
Y1418800D01*
X102958D01*
X103292Y1418675D01*
X103500Y1418508D01*
X103583Y1418175D01*
X103500Y1417842D01*
X103250Y1417633D01*
X102958Y1417508D01*
X101917D01*
G01X102958D02*
X103583Y1416300D01*
G01X105142Y1416592D02*
X105433Y1416383D01*
X105767Y1416300D01*
X106100Y1416383D01*
X106392Y1416633D01*
X106600Y1417008D01*
X106683Y1417383D01*
Y1417842D01*
X106600Y1418217D01*
X106392Y1418550D01*
X106142Y1418717D01*
X105850Y1418800D01*
X105517Y1418717D01*
X105267Y1418550D01*
X105100Y1418300D01*
X105017Y1417967D01*
X105100Y1417675D01*
X105308Y1417383D01*
X105558Y1417217D01*
X105850Y1417175D01*
X106183Y1417258D01*
X106433Y1417467D01*
X106683Y1417842D01*
G01X108242Y1416592D02*
X108533Y1416383D01*
X108867Y1416300D01*
X109200Y1416383D01*
X109492Y1416633D01*
X109700Y1417008D01*
X109783Y1417383D01*
Y1417842D01*
X109700Y1418217D01*
X109492Y1418550D01*
X109242Y1418717D01*
X108950Y1418800D01*
X108617Y1418717D01*
X108367Y1418550D01*
X108200Y1418300D01*
X108117Y1417967D01*
X108200Y1417675D01*
X108408Y1417383D01*
X108658Y1417217D01*
X108950Y1417175D01*
X109283Y1417258D01*
X109533Y1417467D01*
X109783Y1417842D01*
G01X112050Y1418800D02*
X111717Y1418717D01*
X111467Y1418508D01*
X111300Y1418258D01*
X111175Y1417925D01*
X111133Y1417550D01*
X111175Y1417175D01*
X111300Y1416842D01*
X111467Y1416592D01*
X111717Y1416383D01*
X112050Y1416300D01*
X112383Y1416383D01*
X112633Y1416592D01*
X112800Y1416842D01*
X112925Y1417175D01*
X112967Y1417550D01*
X112925Y1417925D01*
X112800Y1418258D01*
X112633Y1418508D01*
X112383Y1418717D01*
X112050Y1418800D01*
G01X114233Y1416800D02*
X114483Y1416508D01*
X114817Y1416342D01*
X115192Y1416300D01*
X115525Y1416342D01*
X115858Y1416550D01*
X116067Y1416800D01*
X116108Y1417050D01*
X116025Y1417342D01*
X115733Y1417550D01*
X115442Y1417633D01*
X115067D01*
G01X115442D02*
X115692Y1417758D01*
X115900Y1417967D01*
X115983Y1418217D01*
X115900Y1418467D01*
X115692Y1418675D01*
X115317Y1418800D01*
X114942Y1418758D01*
X114567Y1418592D01*
G01X98200Y1415500D02*
Y1419500D01*
X90800D01*
G01X72467Y1415166D02*
Y1417666D01*
X73508D01*
X73842Y1417541D01*
X74050Y1417374D01*
X74133Y1417041D01*
X74050Y1416708D01*
X73800Y1416499D01*
X73508Y1416374D01*
X72467D01*
G01X73508D02*
X74133Y1415166D01*
G01X75692Y1415458D02*
X75983Y1415249D01*
X76317Y1415166D01*
X76650Y1415249D01*
X76942Y1415499D01*
X77150Y1415874D01*
X77233Y1416249D01*
Y1416708D01*
X77150Y1417083D01*
X76942Y1417416D01*
X76692Y1417583D01*
X76400Y1417666D01*
X76067Y1417583D01*
X75817Y1417416D01*
X75650Y1417166D01*
X75567Y1416833D01*
X75650Y1416541D01*
X75858Y1416249D01*
X76108Y1416083D01*
X76400Y1416041D01*
X76733Y1416124D01*
X76983Y1416333D01*
X77233Y1416708D01*
G01X78792Y1415458D02*
X79083Y1415249D01*
X79417Y1415166D01*
X79750Y1415249D01*
X80042Y1415499D01*
X80250Y1415874D01*
X80333Y1416249D01*
Y1416708D01*
X80250Y1417083D01*
X80042Y1417416D01*
X79792Y1417583D01*
X79500Y1417666D01*
X79167Y1417583D01*
X78917Y1417416D01*
X78750Y1417166D01*
X78667Y1416833D01*
X78750Y1416541D01*
X78958Y1416249D01*
X79208Y1416083D01*
X79500Y1416041D01*
X79833Y1416124D01*
X80083Y1416333D01*
X80333Y1416708D01*
G01X81683Y1415541D02*
X81933Y1415333D01*
X82225Y1415208D01*
X82600Y1415166D01*
X82975Y1415249D01*
X83267Y1415416D01*
X83475Y1415708D01*
X83517Y1416041D01*
X83433Y1416374D01*
X83225Y1416583D01*
X82933Y1416749D01*
X82642Y1416791D01*
X82350Y1416749D01*
X81975Y1416583D01*
X82100Y1417666D01*
X83225D01*
G01X85700D02*
X85367Y1417583D01*
X85117Y1417374D01*
X84950Y1417124D01*
X84825Y1416791D01*
X84783Y1416416D01*
X84825Y1416041D01*
X84950Y1415708D01*
X85117Y1415458D01*
X85367Y1415249D01*
X85700Y1415166D01*
X86033Y1415249D01*
X86283Y1415458D01*
X86450Y1415708D01*
X86575Y1416041D01*
X86617Y1416416D01*
X86575Y1416791D01*
X86450Y1417124D01*
X86283Y1417374D01*
X86033Y1417583D01*
X85700Y1417666D01*
G01X62140Y1419910D02*
Y1415910D01*
X69540D01*
G01X53334Y1417967D02*
X50834D01*
Y1419008D01*
X50959Y1419342D01*
X51126Y1419550D01*
X51459Y1419633D01*
X51792Y1419550D01*
X52001Y1419300D01*
X52126Y1419008D01*
Y1417967D01*
G01Y1419008D02*
X53334Y1419633D01*
G01X53042Y1421192D02*
X53251Y1421483D01*
X53334Y1421817D01*
X53251Y1422150D01*
X53001Y1422442D01*
X52626Y1422650D01*
X52251Y1422733D01*
X51792D01*
X51417Y1422650D01*
X51084Y1422442D01*
X50917Y1422192D01*
X50834Y1421900D01*
X50917Y1421567D01*
X51084Y1421317D01*
X51334Y1421150D01*
X51667Y1421067D01*
X51959Y1421150D01*
X52251Y1421358D01*
X52417Y1421608D01*
X52459Y1421900D01*
X52376Y1422233D01*
X52167Y1422483D01*
X51792Y1422733D01*
G01X53042Y1424292D02*
X53251Y1424583D01*
X53334Y1424917D01*
X53251Y1425250D01*
X53001Y1425542D01*
X52626Y1425750D01*
X52251Y1425833D01*
X51792D01*
X51417Y1425750D01*
X51084Y1425542D01*
X50917Y1425292D01*
X50834Y1425000D01*
X50917Y1424667D01*
X51084Y1424417D01*
X51334Y1424250D01*
X51667Y1424167D01*
X51959Y1424250D01*
X52251Y1424458D01*
X52417Y1424708D01*
X52459Y1425000D01*
X52376Y1425333D01*
X52167Y1425583D01*
X51792Y1425833D01*
G01X53334Y1428600D02*
X50834D01*
X52626Y1427058D01*
Y1429142D01*
G01X53042Y1430492D02*
X53251Y1430783D01*
X53334Y1431117D01*
X53251Y1431450D01*
X53001Y1431742D01*
X52626Y1431950D01*
X52251Y1432033D01*
X51792D01*
X51417Y1431950D01*
X51084Y1431742D01*
X50917Y1431492D01*
X50834Y1431200D01*
X50917Y1430867D01*
X51084Y1430617D01*
X51334Y1430450D01*
X51667Y1430367D01*
X51959Y1430450D01*
X52251Y1430658D01*
X52417Y1430908D01*
X52459Y1431200D01*
X52376Y1431533D01*
X52167Y1431783D01*
X51792Y1432033D01*
G01X61797Y1423788D02*
X65797D01*
Y1431188D01*
G01X101917Y1420300D02*
Y1422800D01*
X102958D01*
X103292Y1422675D01*
X103500Y1422508D01*
X103583Y1422175D01*
X103500Y1421842D01*
X103250Y1421633D01*
X102958Y1421508D01*
X101917D01*
G01X102958D02*
X103583Y1420300D01*
G01X105142Y1420592D02*
X105433Y1420383D01*
X105767Y1420300D01*
X106100Y1420383D01*
X106392Y1420633D01*
X106600Y1421008D01*
X106683Y1421383D01*
Y1421842D01*
X106600Y1422217D01*
X106392Y1422550D01*
X106142Y1422717D01*
X105850Y1422800D01*
X105517Y1422717D01*
X105267Y1422550D01*
X105100Y1422300D01*
X105017Y1421967D01*
X105100Y1421675D01*
X105308Y1421383D01*
X105558Y1421217D01*
X105850Y1421175D01*
X106183Y1421258D01*
X106433Y1421467D01*
X106683Y1421842D01*
G01X109450Y1420300D02*
Y1422800D01*
X107908Y1421008D01*
X109992D01*
G01X111133Y1420800D02*
X111383Y1420508D01*
X111717Y1420342D01*
X112092Y1420300D01*
X112425Y1420342D01*
X112758Y1420550D01*
X112967Y1420800D01*
X113008Y1421050D01*
X112925Y1421342D01*
X112633Y1421550D01*
X112342Y1421633D01*
X111967D01*
G01X112342D02*
X112592Y1421758D01*
X112800Y1421967D01*
X112883Y1422217D01*
X112800Y1422467D01*
X112592Y1422675D01*
X112217Y1422800D01*
X111842Y1422758D01*
X111467Y1422592D01*
G01X114358Y1421342D02*
X114650Y1421633D01*
X114900Y1421800D01*
X115233Y1421883D01*
X115525Y1421800D01*
X115733Y1421633D01*
X115900Y1421383D01*
X115942Y1421092D01*
X115900Y1420842D01*
X115733Y1420592D01*
X115483Y1420383D01*
X115192Y1420300D01*
X114858Y1420383D01*
X114567Y1420633D01*
X114400Y1421008D01*
X114358Y1421425D01*
X114442Y1421967D01*
X114567Y1422258D01*
X114775Y1422550D01*
X115067Y1422758D01*
X115358Y1422800D01*
X115650Y1422717D01*
X115858Y1422508D01*
G01X98200Y1420000D02*
Y1424000D01*
X90800D01*
G01X103042Y1455217D02*
X102917Y1454967D01*
X102834Y1454675D01*
Y1454342D01*
X102959Y1453967D01*
X103167Y1453675D01*
X103417Y1453467D01*
X103834Y1453300D01*
X104209Y1453258D01*
X104584Y1453342D01*
X104834Y1453467D01*
X105084Y1453717D01*
X105251Y1454008D01*
X105334Y1454300D01*
Y1454592D01*
X105251Y1454883D01*
X105126Y1455133D01*
X104959Y1455342D01*
G01X105042Y1456692D02*
X105251Y1456983D01*
X105334Y1457317D01*
X105251Y1457650D01*
X105001Y1457942D01*
X104626Y1458150D01*
X104251Y1458233D01*
X103792D01*
X103417Y1458150D01*
X103084Y1457942D01*
X102917Y1457692D01*
X102834Y1457400D01*
X102917Y1457067D01*
X103084Y1456817D01*
X103334Y1456650D01*
X103667Y1456567D01*
X103959Y1456650D01*
X104251Y1456858D01*
X104417Y1457108D01*
X104459Y1457400D01*
X104376Y1457733D01*
X104167Y1457983D01*
X103792Y1458233D01*
G01X104959Y1459583D02*
X105167Y1459833D01*
X105292Y1460125D01*
X105334Y1460500D01*
X105251Y1460875D01*
X105084Y1461167D01*
X104792Y1461375D01*
X104459Y1461417D01*
X104126Y1461333D01*
X103917Y1461125D01*
X103751Y1460833D01*
X103709Y1460542D01*
X103751Y1460250D01*
X103917Y1459875D01*
X102834Y1460000D01*
Y1461125D01*
G01X103251Y1462808D02*
X103001Y1463058D01*
X102876Y1463350D01*
X102834Y1463683D01*
X102917Y1464100D01*
X103126Y1464392D01*
X103376Y1464475D01*
X103626Y1464433D01*
X103834Y1464267D01*
X104251Y1463433D01*
X104542Y1463058D01*
X104959Y1462808D01*
X105334Y1462725D01*
Y1464475D01*
G01X105042Y1465992D02*
X105251Y1466283D01*
X105334Y1466617D01*
X105251Y1466950D01*
X105001Y1467242D01*
X104626Y1467450D01*
X104251Y1467533D01*
X103792D01*
X103417Y1467450D01*
X103084Y1467242D01*
X102917Y1466992D01*
X102834Y1466700D01*
X102917Y1466367D01*
X103084Y1466117D01*
X103334Y1465950D01*
X103667Y1465867D01*
X103959Y1465950D01*
X104251Y1466158D01*
X104417Y1466408D01*
X104459Y1466700D01*
X104376Y1467033D01*
X104167Y1467283D01*
X103792Y1467533D01*
G01X40058Y1500517D02*
X39933Y1500267D01*
X39850Y1499975D01*
Y1499642D01*
X39975Y1499267D01*
X40183Y1498975D01*
X40433Y1498767D01*
X40850Y1498600D01*
X41225Y1498558D01*
X41600Y1498642D01*
X41850Y1498767D01*
X42100Y1499017D01*
X42267Y1499308D01*
X42350Y1499600D01*
Y1499892D01*
X42267Y1500183D01*
X42142Y1500433D01*
X41975Y1500642D01*
G01X42058Y1501992D02*
X42267Y1502283D01*
X42350Y1502617D01*
X42267Y1502950D01*
X42017Y1503242D01*
X41642Y1503450D01*
X41267Y1503533D01*
X40808D01*
X40433Y1503450D01*
X40100Y1503242D01*
X39933Y1502992D01*
X39850Y1502700D01*
X39933Y1502367D01*
X40100Y1502117D01*
X40350Y1501950D01*
X40683Y1501867D01*
X40975Y1501950D01*
X41267Y1502158D01*
X41433Y1502408D01*
X41475Y1502700D01*
X41392Y1503033D01*
X41183Y1503283D01*
X40808Y1503533D01*
G01X41975Y1504883D02*
X42183Y1505133D01*
X42308Y1505425D01*
X42350Y1505800D01*
X42267Y1506175D01*
X42100Y1506467D01*
X41808Y1506675D01*
X41475Y1506717D01*
X41142Y1506633D01*
X40933Y1506425D01*
X40767Y1506133D01*
X40725Y1505842D01*
X40767Y1505550D01*
X40933Y1505175D01*
X39850Y1505300D01*
Y1506425D01*
G01X41850Y1507983D02*
X42142Y1508233D01*
X42308Y1508567D01*
X42350Y1508942D01*
X42308Y1509275D01*
X42100Y1509608D01*
X41850Y1509817D01*
X41600Y1509858D01*
X41308Y1509775D01*
X41100Y1509483D01*
X41017Y1509192D01*
Y1508817D01*
G01Y1509192D02*
X40892Y1509442D01*
X40683Y1509650D01*
X40433Y1509733D01*
X40183Y1509650D01*
X39975Y1509442D01*
X39850Y1509067D01*
X39892Y1508692D01*
X40058Y1508317D01*
G01X42350Y1511917D02*
X41808Y1512000D01*
X41350Y1512125D01*
X40933Y1512292D01*
X40475Y1512500D01*
X39850Y1512833D01*
Y1511167D01*
G01X44058Y1500017D02*
X43933Y1499767D01*
X43850Y1499475D01*
Y1499142D01*
X43975Y1498767D01*
X44183Y1498475D01*
X44433Y1498267D01*
X44850Y1498100D01*
X45225Y1498058D01*
X45600Y1498142D01*
X45850Y1498267D01*
X46100Y1498517D01*
X46267Y1498808D01*
X46350Y1499100D01*
Y1499392D01*
X46267Y1499683D01*
X46142Y1499933D01*
X45975Y1500142D01*
G01X46058Y1501492D02*
X46267Y1501783D01*
X46350Y1502117D01*
X46267Y1502450D01*
X46017Y1502742D01*
X45642Y1502950D01*
X45267Y1503033D01*
X44808D01*
X44433Y1502950D01*
X44100Y1502742D01*
X43933Y1502492D01*
X43850Y1502200D01*
X43933Y1501867D01*
X44100Y1501617D01*
X44350Y1501450D01*
X44683Y1501367D01*
X44975Y1501450D01*
X45267Y1501658D01*
X45433Y1501908D01*
X45475Y1502200D01*
X45392Y1502533D01*
X45183Y1502783D01*
X44808Y1503033D01*
G01X45975Y1504383D02*
X46183Y1504633D01*
X46308Y1504925D01*
X46350Y1505300D01*
X46267Y1505675D01*
X46100Y1505967D01*
X45808Y1506175D01*
X45475Y1506217D01*
X45142Y1506133D01*
X44933Y1505925D01*
X44767Y1505633D01*
X44725Y1505342D01*
X44767Y1505050D01*
X44933Y1504675D01*
X43850Y1504800D01*
Y1505925D01*
G01X45850Y1507483D02*
X46142Y1507733D01*
X46308Y1508067D01*
X46350Y1508442D01*
X46308Y1508775D01*
X46100Y1509108D01*
X45850Y1509317D01*
X45600Y1509358D01*
X45308Y1509275D01*
X45100Y1508983D01*
X45017Y1508692D01*
Y1508317D01*
G01Y1508692D02*
X44892Y1508942D01*
X44683Y1509150D01*
X44433Y1509233D01*
X44183Y1509150D01*
X43975Y1508942D01*
X43850Y1508567D01*
X43892Y1508192D01*
X44058Y1507817D01*
G01X45308Y1510708D02*
X45017Y1511000D01*
X44850Y1511250D01*
X44767Y1511583D01*
X44850Y1511875D01*
X45017Y1512083D01*
X45267Y1512250D01*
X45558Y1512292D01*
X45808Y1512250D01*
X46058Y1512083D01*
X46267Y1511833D01*
X46350Y1511542D01*
X46267Y1511208D01*
X46017Y1510917D01*
X45642Y1510750D01*
X45225Y1510708D01*
X44683Y1510792D01*
X44392Y1510917D01*
X44100Y1511125D01*
X43892Y1511417D01*
X43850Y1511708D01*
X43933Y1512000D01*
X44142Y1512208D01*
G01X43858Y1484367D02*
X43733Y1484117D01*
X43650Y1483825D01*
Y1483492D01*
X43775Y1483117D01*
X43983Y1482825D01*
X44233Y1482617D01*
X44650Y1482450D01*
X45025Y1482408D01*
X45400Y1482492D01*
X45650Y1482617D01*
X45900Y1482867D01*
X46067Y1483158D01*
X46150Y1483450D01*
Y1483742D01*
X46067Y1484033D01*
X45942Y1484283D01*
X45775Y1484492D01*
G01X45858Y1485842D02*
X46067Y1486133D01*
X46150Y1486467D01*
X46067Y1486800D01*
X45817Y1487092D01*
X45442Y1487300D01*
X45067Y1487383D01*
X44608D01*
X44233Y1487300D01*
X43900Y1487092D01*
X43733Y1486842D01*
X43650Y1486550D01*
X43733Y1486217D01*
X43900Y1485967D01*
X44150Y1485800D01*
X44483Y1485717D01*
X44775Y1485800D01*
X45067Y1486008D01*
X45233Y1486258D01*
X45275Y1486550D01*
X45192Y1486883D01*
X44983Y1487133D01*
X44608Y1487383D01*
G01X45775Y1488733D02*
X45983Y1488983D01*
X46108Y1489275D01*
X46150Y1489650D01*
X46067Y1490025D01*
X45900Y1490317D01*
X45608Y1490525D01*
X45275Y1490567D01*
X44942Y1490483D01*
X44733Y1490275D01*
X44567Y1489983D01*
X44525Y1489692D01*
X44567Y1489400D01*
X44733Y1489025D01*
X43650Y1489150D01*
Y1490275D01*
G01X45650Y1491833D02*
X45942Y1492083D01*
X46108Y1492417D01*
X46150Y1492792D01*
X46108Y1493125D01*
X45900Y1493458D01*
X45650Y1493667D01*
X45400Y1493708D01*
X45108Y1493625D01*
X44900Y1493333D01*
X44817Y1493042D01*
Y1492667D01*
G01Y1493042D02*
X44692Y1493292D01*
X44483Y1493500D01*
X44233Y1493583D01*
X43983Y1493500D01*
X43775Y1493292D01*
X43650Y1492917D01*
X43692Y1492542D01*
X43858Y1492167D01*
G01X45775Y1494933D02*
X45983Y1495183D01*
X46108Y1495475D01*
X46150Y1495850D01*
X46067Y1496225D01*
X45900Y1496517D01*
X45608Y1496725D01*
X45275Y1496767D01*
X44942Y1496683D01*
X44733Y1496475D01*
X44567Y1496183D01*
X44525Y1495892D01*
X44567Y1495600D01*
X44733Y1495225D01*
X43650Y1495350D01*
Y1496475D01*
G01X39658Y1484767D02*
X39533Y1484517D01*
X39450Y1484225D01*
Y1483892D01*
X39575Y1483517D01*
X39783Y1483225D01*
X40033Y1483017D01*
X40450Y1482850D01*
X40825Y1482808D01*
X41200Y1482892D01*
X41450Y1483017D01*
X41700Y1483267D01*
X41867Y1483558D01*
X41950Y1483850D01*
Y1484142D01*
X41867Y1484433D01*
X41742Y1484683D01*
X41575Y1484892D01*
G01X41658Y1486242D02*
X41867Y1486533D01*
X41950Y1486867D01*
X41867Y1487200D01*
X41617Y1487492D01*
X41242Y1487700D01*
X40867Y1487783D01*
X40408D01*
X40033Y1487700D01*
X39700Y1487492D01*
X39533Y1487242D01*
X39450Y1486950D01*
X39533Y1486617D01*
X39700Y1486367D01*
X39950Y1486200D01*
X40283Y1486117D01*
X40575Y1486200D01*
X40867Y1486408D01*
X41033Y1486658D01*
X41075Y1486950D01*
X40992Y1487283D01*
X40783Y1487533D01*
X40408Y1487783D01*
G01X41575Y1489133D02*
X41783Y1489383D01*
X41908Y1489675D01*
X41950Y1490050D01*
X41867Y1490425D01*
X41700Y1490717D01*
X41408Y1490925D01*
X41075Y1490967D01*
X40742Y1490883D01*
X40533Y1490675D01*
X40367Y1490383D01*
X40325Y1490092D01*
X40367Y1489800D01*
X40533Y1489425D01*
X39450Y1489550D01*
Y1490675D01*
G01X41450Y1492233D02*
X41742Y1492483D01*
X41908Y1492817D01*
X41950Y1493192D01*
X41908Y1493525D01*
X41700Y1493858D01*
X41450Y1494067D01*
X41200Y1494108D01*
X40908Y1494025D01*
X40700Y1493733D01*
X40617Y1493442D01*
Y1493067D01*
G01Y1493442D02*
X40492Y1493692D01*
X40283Y1493900D01*
X40033Y1493983D01*
X39783Y1493900D01*
X39575Y1493692D01*
X39450Y1493317D01*
X39492Y1492942D01*
X39658Y1492567D01*
G01X41950Y1496750D02*
X39450D01*
X41242Y1495208D01*
Y1497292D01*
G01X60200Y1466700D02*
X59867Y1466742D01*
X59575Y1466908D01*
X59325Y1467158D01*
X59158Y1467450D01*
X59075Y1467783D01*
Y1468117D01*
X59158Y1468450D01*
X59325Y1468742D01*
X59575Y1468992D01*
X59867Y1469158D01*
X60200Y1469200D01*
X60533Y1469158D01*
X60825Y1468992D01*
X61075Y1468742D01*
X61242Y1468450D01*
X61325Y1468117D01*
Y1467783D01*
X61242Y1467450D01*
X61075Y1467158D01*
X60825Y1466908D01*
X60533Y1466742D01*
X60200Y1466700D01*
G01X60533Y1467367D02*
X61033Y1466700D01*
G01X63300D02*
X63592Y1466742D01*
X63925Y1466867D01*
X64133Y1467075D01*
X64217Y1467367D01*
X64133Y1467658D01*
X63883Y1467908D01*
X63508Y1468033D01*
X63092D01*
X62842Y1468117D01*
X62633Y1468325D01*
X62550Y1468617D01*
X62675Y1468908D01*
X62967Y1469117D01*
X63300Y1469200D01*
X63633Y1469117D01*
X63925Y1468908D01*
X64050Y1468617D01*
X63967Y1468325D01*
X63758Y1468117D01*
X63508Y1468033D01*
X63092D01*
X62717Y1467908D01*
X62467Y1467658D01*
X62383Y1467367D01*
X62467Y1467075D01*
X62675Y1466867D01*
X63008Y1466742D01*
X63300Y1466700D01*
G01X65483Y1467200D02*
X65733Y1466908D01*
X66067Y1466742D01*
X66442Y1466700D01*
X66775Y1466742D01*
X67108Y1466950D01*
X67317Y1467200D01*
X67358Y1467450D01*
X67275Y1467742D01*
X66983Y1467950D01*
X66692Y1468033D01*
X66317D01*
G01X66692D02*
X66942Y1468158D01*
X67150Y1468367D01*
X67233Y1468617D01*
X67150Y1468867D01*
X66942Y1469075D01*
X66567Y1469200D01*
X66192Y1469158D01*
X65817Y1468992D01*
G01X57000Y1465000D02*
Y1451000D01*
G01X70000Y1465000D02*
X57000D01*
G01X70000Y1451000D02*
Y1465000D01*
G01X57000Y1451000D02*
X70000D01*
G01X109000Y1436900D02*
X108958Y1436567D01*
X108792Y1436275D01*
X108542Y1436025D01*
X108250Y1435858D01*
X107917Y1435775D01*
X107583D01*
X107250Y1435858D01*
X106958Y1436025D01*
X106708Y1436275D01*
X106542Y1436567D01*
X106500Y1436900D01*
X106542Y1437233D01*
X106708Y1437525D01*
X106958Y1437775D01*
X107250Y1437942D01*
X107583Y1438025D01*
X107917D01*
X108250Y1437942D01*
X108542Y1437775D01*
X108792Y1437525D01*
X108958Y1437233D01*
X109000Y1436900D01*
G01X108333Y1437233D02*
X109000Y1437733D01*
G01Y1440000D02*
X108958Y1440292D01*
X108833Y1440625D01*
X108625Y1440833D01*
X108333Y1440917D01*
X108042Y1440833D01*
X107792Y1440583D01*
X107667Y1440208D01*
Y1439792D01*
X107583Y1439542D01*
X107375Y1439333D01*
X107083Y1439250D01*
X106792Y1439375D01*
X106583Y1439667D01*
X106500Y1440000D01*
X106583Y1440333D01*
X106792Y1440625D01*
X107083Y1440750D01*
X107375Y1440667D01*
X107583Y1440458D01*
X107667Y1440208D01*
Y1439792D01*
X107792Y1439417D01*
X108042Y1439167D01*
X108333Y1439083D01*
X108625Y1439167D01*
X108833Y1439375D01*
X108958Y1439708D01*
X109000Y1440000D01*
G01Y1443600D02*
X106500D01*
X108292Y1442058D01*
Y1444142D01*
G01X91000Y1434000D02*
X105000D01*
G01X91000Y1447000D02*
Y1434000D01*
G01X105000Y1447000D02*
X91000D01*
G01X105000Y1434000D02*
Y1447000D01*
G01X88000Y1432900D02*
X87958Y1432567D01*
X87792Y1432275D01*
X87542Y1432025D01*
X87250Y1431858D01*
X86917Y1431775D01*
X86583D01*
X86250Y1431858D01*
X85958Y1432025D01*
X85708Y1432275D01*
X85542Y1432567D01*
X85500Y1432900D01*
X85542Y1433233D01*
X85708Y1433525D01*
X85958Y1433775D01*
X86250Y1433942D01*
X86583Y1434025D01*
X86917D01*
X87250Y1433942D01*
X87542Y1433775D01*
X87792Y1433525D01*
X87958Y1433233D01*
X88000Y1432900D01*
G01X87333Y1433233D02*
X88000Y1433733D01*
G01Y1436000D02*
X87958Y1436292D01*
X87833Y1436625D01*
X87625Y1436833D01*
X87333Y1436917D01*
X87042Y1436833D01*
X86792Y1436583D01*
X86667Y1436208D01*
Y1435792D01*
X86583Y1435542D01*
X86375Y1435333D01*
X86083Y1435250D01*
X85792Y1435375D01*
X85583Y1435667D01*
X85500Y1436000D01*
X85583Y1436333D01*
X85792Y1436625D01*
X86083Y1436750D01*
X86375Y1436667D01*
X86583Y1436458D01*
X86667Y1436208D01*
Y1435792D01*
X86792Y1435417D01*
X87042Y1435167D01*
X87333Y1435083D01*
X87625Y1435167D01*
X87833Y1435375D01*
X87958Y1435708D01*
X88000Y1436000D01*
G01X87625Y1438183D02*
X87833Y1438433D01*
X87958Y1438725D01*
X88000Y1439100D01*
X87917Y1439475D01*
X87750Y1439767D01*
X87458Y1439975D01*
X87125Y1440017D01*
X86792Y1439933D01*
X86583Y1439725D01*
X86417Y1439433D01*
X86375Y1439142D01*
X86417Y1438850D01*
X86583Y1438475D01*
X85500Y1438600D01*
Y1439725D01*
G01X69958Y1430519D02*
X83958D01*
G01X69958Y1443519D02*
Y1430519D01*
G01X83958Y1443519D02*
X69958D01*
G01X83958Y1430519D02*
Y1443519D01*
G01X89277Y1484641D02*
Y1487141D01*
X90318D01*
X90652Y1487016D01*
X90860Y1486849D01*
X90943Y1486516D01*
X90860Y1486183D01*
X90610Y1485974D01*
X90318Y1485849D01*
X89277D01*
G01X90318D02*
X90943Y1484641D01*
G01X92293Y1485141D02*
X92543Y1484849D01*
X92877Y1484683D01*
X93252Y1484641D01*
X93585Y1484683D01*
X93918Y1484891D01*
X94127Y1485141D01*
X94168Y1485391D01*
X94085Y1485683D01*
X93793Y1485891D01*
X93502Y1485974D01*
X93127D01*
G01X93502D02*
X93752Y1486099D01*
X93960Y1486308D01*
X94043Y1486558D01*
X93960Y1486808D01*
X93752Y1487016D01*
X93377Y1487141D01*
X93002Y1487099D01*
X92627Y1486933D01*
G01X95393Y1485141D02*
X95643Y1484849D01*
X95977Y1484683D01*
X96352Y1484641D01*
X96685Y1484683D01*
X97018Y1484891D01*
X97227Y1485141D01*
X97268Y1485391D01*
X97185Y1485683D01*
X96893Y1485891D01*
X96602Y1485974D01*
X96227D01*
G01X96602D02*
X96852Y1486099D01*
X97060Y1486308D01*
X97143Y1486558D01*
X97060Y1486808D01*
X96852Y1487016D01*
X96477Y1487141D01*
X96102Y1487099D01*
X95727Y1486933D01*
G01X99410Y1487141D02*
X99077Y1487058D01*
X98827Y1486849D01*
X98660Y1486599D01*
X98535Y1486266D01*
X98493Y1485891D01*
X98535Y1485516D01*
X98660Y1485183D01*
X98827Y1484933D01*
X99077Y1484724D01*
X99410Y1484641D01*
X99743Y1484724D01*
X99993Y1484933D01*
X100160Y1485183D01*
X100285Y1485516D01*
X100327Y1485891D01*
X100285Y1486266D01*
X100160Y1486599D01*
X99993Y1486849D01*
X99743Y1487058D01*
X99410Y1487141D01*
G01X90800Y1499000D02*
Y1495000D01*
X98200D01*
G01X113520Y1457117D02*
X111020D01*
Y1458158D01*
X111145Y1458492D01*
X111312Y1458700D01*
X111645Y1458783D01*
X111978Y1458700D01*
X112187Y1458450D01*
X112312Y1458158D01*
Y1457117D01*
G01Y1458158D02*
X113520Y1458783D01*
G01X113020Y1460133D02*
X113312Y1460383D01*
X113478Y1460717D01*
X113520Y1461092D01*
X113478Y1461425D01*
X113270Y1461758D01*
X113020Y1461967D01*
X112770Y1462008D01*
X112478Y1461925D01*
X112270Y1461633D01*
X112187Y1461342D01*
Y1460967D01*
G01Y1461342D02*
X112062Y1461592D01*
X111853Y1461800D01*
X111603Y1461883D01*
X111353Y1461800D01*
X111145Y1461592D01*
X111020Y1461217D01*
X111062Y1460842D01*
X111228Y1460467D01*
G01X113020Y1463233D02*
X113312Y1463483D01*
X113478Y1463817D01*
X113520Y1464192D01*
X113478Y1464525D01*
X113270Y1464858D01*
X113020Y1465067D01*
X112770Y1465108D01*
X112478Y1465025D01*
X112270Y1464733D01*
X112187Y1464442D01*
Y1464067D01*
G01Y1464442D02*
X112062Y1464692D01*
X111853Y1464900D01*
X111603Y1464983D01*
X111353Y1464900D01*
X111145Y1464692D01*
X111020Y1464317D01*
X111062Y1463942D01*
X111228Y1463567D01*
G01X113020Y1466333D02*
X113312Y1466583D01*
X113478Y1466917D01*
X113520Y1467292D01*
X113478Y1467625D01*
X113270Y1467958D01*
X113020Y1468167D01*
X112770Y1468208D01*
X112478Y1468125D01*
X112270Y1467833D01*
X112187Y1467542D01*
Y1467167D01*
G01Y1467542D02*
X112062Y1467792D01*
X111853Y1468000D01*
X111603Y1468083D01*
X111353Y1468000D01*
X111145Y1467792D01*
X111020Y1467417D01*
X111062Y1467042D01*
X111228Y1466667D01*
G01X108000Y1471300D02*
X112000D01*
Y1478700D01*
G01X89277Y1479641D02*
Y1482141D01*
X90318D01*
X90652Y1482016D01*
X90860Y1481849D01*
X90943Y1481516D01*
X90860Y1481183D01*
X90610Y1480974D01*
X90318Y1480849D01*
X89277D01*
G01X90318D02*
X90943Y1479641D01*
G01X92293Y1480141D02*
X92543Y1479849D01*
X92877Y1479683D01*
X93252Y1479641D01*
X93585Y1479683D01*
X93918Y1479891D01*
X94127Y1480141D01*
X94168Y1480391D01*
X94085Y1480683D01*
X93793Y1480891D01*
X93502Y1480974D01*
X93127D01*
G01X93502D02*
X93752Y1481099D01*
X93960Y1481308D01*
X94043Y1481558D01*
X93960Y1481808D01*
X93752Y1482016D01*
X93377Y1482141D01*
X93002Y1482099D01*
X92627Y1481933D01*
G01X95393Y1480141D02*
X95643Y1479849D01*
X95977Y1479683D01*
X96352Y1479641D01*
X96685Y1479683D01*
X97018Y1479891D01*
X97227Y1480141D01*
X97268Y1480391D01*
X97185Y1480683D01*
X96893Y1480891D01*
X96602Y1480974D01*
X96227D01*
G01X96602D02*
X96852Y1481099D01*
X97060Y1481308D01*
X97143Y1481558D01*
X97060Y1481808D01*
X96852Y1482016D01*
X96477Y1482141D01*
X96102Y1482099D01*
X95727Y1481933D01*
G01X98493Y1480016D02*
X98743Y1479808D01*
X99035Y1479683D01*
X99410Y1479641D01*
X99785Y1479724D01*
X100077Y1479891D01*
X100285Y1480183D01*
X100327Y1480516D01*
X100243Y1480849D01*
X100035Y1481058D01*
X99743Y1481224D01*
X99452Y1481266D01*
X99160Y1481224D01*
X98785Y1481058D01*
X98910Y1482141D01*
X100035D01*
G01X90800Y1494000D02*
Y1490000D01*
X98200D01*
G01X63967Y1476500D02*
Y1479000D01*
X65008D01*
X65342Y1478875D01*
X65550Y1478708D01*
X65633Y1478375D01*
X65550Y1478042D01*
X65300Y1477833D01*
X65008Y1477708D01*
X63967D01*
G01X65008D02*
X65633Y1476500D01*
G01X67192Y1476792D02*
X67483Y1476583D01*
X67817Y1476500D01*
X68150Y1476583D01*
X68442Y1476833D01*
X68650Y1477208D01*
X68733Y1477583D01*
Y1478042D01*
X68650Y1478417D01*
X68442Y1478750D01*
X68192Y1478917D01*
X67900Y1479000D01*
X67567Y1478917D01*
X67317Y1478750D01*
X67150Y1478500D01*
X67067Y1478167D01*
X67150Y1477875D01*
X67358Y1477583D01*
X67608Y1477417D01*
X67900Y1477375D01*
X68233Y1477458D01*
X68483Y1477667D01*
X68733Y1478042D01*
G01X71000Y1476500D02*
X71292Y1476542D01*
X71625Y1476667D01*
X71833Y1476875D01*
X71917Y1477167D01*
X71833Y1477458D01*
X71583Y1477708D01*
X71208Y1477833D01*
X70792D01*
X70542Y1477917D01*
X70333Y1478125D01*
X70250Y1478417D01*
X70375Y1478708D01*
X70667Y1478917D01*
X71000Y1479000D01*
X71333Y1478917D01*
X71625Y1478708D01*
X71750Y1478417D01*
X71667Y1478125D01*
X71458Y1477917D01*
X71208Y1477833D01*
X70792D01*
X70417Y1477708D01*
X70167Y1477458D01*
X70083Y1477167D01*
X70167Y1476875D01*
X70375Y1476667D01*
X70708Y1476542D01*
X71000Y1476500D01*
G01X73183Y1476875D02*
X73433Y1476667D01*
X73725Y1476542D01*
X74100Y1476500D01*
X74475Y1476583D01*
X74767Y1476750D01*
X74975Y1477042D01*
X75017Y1477375D01*
X74933Y1477708D01*
X74725Y1477917D01*
X74433Y1478083D01*
X74142Y1478125D01*
X73850Y1478083D01*
X73475Y1477917D01*
X73600Y1479000D01*
X74725D01*
G01X76283Y1477000D02*
X76533Y1476708D01*
X76867Y1476542D01*
X77242Y1476500D01*
X77575Y1476542D01*
X77908Y1476750D01*
X78117Y1477000D01*
X78158Y1477250D01*
X78075Y1477542D01*
X77783Y1477750D01*
X77492Y1477833D01*
X77117D01*
G01X77492D02*
X77742Y1477958D01*
X77950Y1478167D01*
X78033Y1478417D01*
X77950Y1478667D01*
X77742Y1478875D01*
X77367Y1479000D01*
X76992Y1478958D01*
X76617Y1478792D01*
G01X82700Y1468000D02*
Y1472000D01*
X75300D01*
G01X59356Y1435484D02*
X56856D01*
Y1436525D01*
X56981Y1436859D01*
X57148Y1437067D01*
X57481Y1437150D01*
X57814Y1437067D01*
X58023Y1436817D01*
X58148Y1436525D01*
Y1435484D01*
G01Y1436525D02*
X59356Y1437150D01*
G01X59064Y1438709D02*
X59273Y1439000D01*
X59356Y1439334D01*
X59273Y1439667D01*
X59023Y1439959D01*
X58648Y1440167D01*
X58273Y1440250D01*
X57814D01*
X57439Y1440167D01*
X57106Y1439959D01*
X56939Y1439709D01*
X56856Y1439417D01*
X56939Y1439084D01*
X57106Y1438834D01*
X57356Y1438667D01*
X57689Y1438584D01*
X57981Y1438667D01*
X58273Y1438875D01*
X58439Y1439125D01*
X58481Y1439417D01*
X58398Y1439750D01*
X58189Y1440000D01*
X57814Y1440250D01*
G01X59356Y1442517D02*
X59314Y1442809D01*
X59189Y1443142D01*
X58981Y1443350D01*
X58689Y1443434D01*
X58398Y1443350D01*
X58148Y1443100D01*
X58023Y1442725D01*
Y1442309D01*
X57939Y1442059D01*
X57731Y1441850D01*
X57439Y1441767D01*
X57148Y1441892D01*
X56939Y1442184D01*
X56856Y1442517D01*
X56939Y1442850D01*
X57148Y1443142D01*
X57439Y1443267D01*
X57731Y1443184D01*
X57939Y1442975D01*
X58023Y1442725D01*
Y1442309D01*
X58148Y1441934D01*
X58398Y1441684D01*
X58689Y1441600D01*
X58981Y1441684D01*
X59189Y1441892D01*
X59314Y1442225D01*
X59356Y1442517D01*
G01X58981Y1444700D02*
X59189Y1444950D01*
X59314Y1445242D01*
X59356Y1445617D01*
X59273Y1445992D01*
X59106Y1446284D01*
X58814Y1446492D01*
X58481Y1446534D01*
X58148Y1446450D01*
X57939Y1446242D01*
X57773Y1445950D01*
X57731Y1445659D01*
X57773Y1445367D01*
X57939Y1444992D01*
X56856Y1445117D01*
Y1446242D01*
G01X59356Y1449217D02*
X56856D01*
X58648Y1447675D01*
Y1449759D01*
G01X85589Y1445550D02*
X89589D01*
Y1452950D01*
G01X47836Y1435434D02*
X45336D01*
Y1436475D01*
X45461Y1436809D01*
X45628Y1437017D01*
X45961Y1437100D01*
X46294Y1437017D01*
X46503Y1436767D01*
X46628Y1436475D01*
Y1435434D01*
G01Y1436475D02*
X47836Y1437100D01*
G01X47544Y1438659D02*
X47753Y1438950D01*
X47836Y1439284D01*
X47753Y1439617D01*
X47503Y1439909D01*
X47128Y1440117D01*
X46753Y1440200D01*
X46294D01*
X45919Y1440117D01*
X45586Y1439909D01*
X45419Y1439659D01*
X45336Y1439367D01*
X45419Y1439034D01*
X45586Y1438784D01*
X45836Y1438617D01*
X46169Y1438534D01*
X46461Y1438617D01*
X46753Y1438825D01*
X46919Y1439075D01*
X46961Y1439367D01*
X46878Y1439700D01*
X46669Y1439950D01*
X46294Y1440200D01*
G01X47836Y1442467D02*
X47794Y1442759D01*
X47669Y1443092D01*
X47461Y1443300D01*
X47169Y1443384D01*
X46878Y1443300D01*
X46628Y1443050D01*
X46503Y1442675D01*
Y1442259D01*
X46419Y1442009D01*
X46211Y1441800D01*
X45919Y1441717D01*
X45628Y1441842D01*
X45419Y1442134D01*
X45336Y1442467D01*
X45419Y1442800D01*
X45628Y1443092D01*
X45919Y1443217D01*
X46211Y1443134D01*
X46419Y1442925D01*
X46503Y1442675D01*
Y1442259D01*
X46628Y1441884D01*
X46878Y1441634D01*
X47169Y1441550D01*
X47461Y1441634D01*
X47669Y1441842D01*
X47794Y1442175D01*
X47836Y1442467D01*
G01X47461Y1444650D02*
X47669Y1444900D01*
X47794Y1445192D01*
X47836Y1445567D01*
X47753Y1445942D01*
X47586Y1446234D01*
X47294Y1446442D01*
X46961Y1446484D01*
X46628Y1446400D01*
X46419Y1446192D01*
X46253Y1445900D01*
X46211Y1445609D01*
X46253Y1445317D01*
X46419Y1444942D01*
X45336Y1445067D01*
Y1446192D01*
G01X47461Y1447750D02*
X47669Y1448000D01*
X47794Y1448292D01*
X47836Y1448667D01*
X47753Y1449042D01*
X47586Y1449334D01*
X47294Y1449542D01*
X46961Y1449584D01*
X46628Y1449500D01*
X46419Y1449292D01*
X46253Y1449000D01*
X46211Y1448709D01*
X46253Y1448417D01*
X46419Y1448042D01*
X45336Y1448167D01*
Y1449292D01*
G01X74750Y1445407D02*
X78750D01*
Y1452807D01*
G01X73367Y1449325D02*
X73575Y1449658D01*
X73700Y1450033D01*
Y1450367D01*
X73575Y1450700D01*
X73367Y1450950D01*
X73075Y1451075D01*
X72783Y1450992D01*
X72533Y1450783D01*
X72367Y1450408D01*
X72283Y1449908D01*
X72117Y1449617D01*
X71825Y1449492D01*
X71533Y1449575D01*
X71325Y1449783D01*
X71200Y1450075D01*
Y1450367D01*
X71283Y1450658D01*
X71492Y1450908D01*
G01X73700Y1452467D02*
X71200D01*
Y1453508D01*
X71325Y1453842D01*
X71492Y1454050D01*
X71825Y1454133D01*
X72158Y1454050D01*
X72367Y1453800D01*
X72492Y1453508D01*
Y1452467D01*
G01Y1453508D02*
X73700Y1454133D01*
G01Y1456400D02*
X71200D01*
X71700Y1455900D01*
G01X73700D02*
Y1456900D01*
G01Y1459500D02*
X71200D01*
X71700Y1459000D01*
G01X73700D02*
Y1460000D01*
G01Y1463100D02*
X71200D01*
X72992Y1461558D01*
Y1463642D01*
G01X73700Y1466200D02*
X71200D01*
X72992Y1464658D01*
Y1466742D01*
G01X78750Y1460550D02*
X74750D01*
Y1453150D01*
G01X53447Y1435335D02*
X50947D01*
Y1436376D01*
X51072Y1436710D01*
X51239Y1436918D01*
X51572Y1437001D01*
X51905Y1436918D01*
X52114Y1436668D01*
X52239Y1436376D01*
Y1435335D01*
G01Y1436376D02*
X53447Y1437001D01*
G01X53155Y1438560D02*
X53364Y1438851D01*
X53447Y1439185D01*
X53364Y1439518D01*
X53114Y1439810D01*
X52739Y1440018D01*
X52364Y1440101D01*
X51905D01*
X51530Y1440018D01*
X51197Y1439810D01*
X51030Y1439560D01*
X50947Y1439268D01*
X51030Y1438935D01*
X51197Y1438685D01*
X51447Y1438518D01*
X51780Y1438435D01*
X52072Y1438518D01*
X52364Y1438726D01*
X52530Y1438976D01*
X52572Y1439268D01*
X52489Y1439601D01*
X52280Y1439851D01*
X51905Y1440101D01*
G01X53155Y1441660D02*
X53364Y1441951D01*
X53447Y1442285D01*
X53364Y1442618D01*
X53114Y1442910D01*
X52739Y1443118D01*
X52364Y1443201D01*
X51905D01*
X51530Y1443118D01*
X51197Y1442910D01*
X51030Y1442660D01*
X50947Y1442368D01*
X51030Y1442035D01*
X51197Y1441785D01*
X51447Y1441618D01*
X51780Y1441535D01*
X52072Y1441618D01*
X52364Y1441826D01*
X52530Y1442076D01*
X52572Y1442368D01*
X52489Y1442701D01*
X52280Y1442951D01*
X51905Y1443201D01*
G01X51364Y1444676D02*
X51114Y1444926D01*
X50989Y1445218D01*
X50947Y1445551D01*
X51030Y1445968D01*
X51239Y1446260D01*
X51489Y1446343D01*
X51739Y1446301D01*
X51947Y1446135D01*
X52364Y1445301D01*
X52655Y1444926D01*
X53072Y1444676D01*
X53447Y1444593D01*
Y1446343D01*
G01X52947Y1447651D02*
X53239Y1447901D01*
X53405Y1448235D01*
X53447Y1448610D01*
X53405Y1448943D01*
X53197Y1449276D01*
X52947Y1449485D01*
X52697Y1449526D01*
X52405Y1449443D01*
X52197Y1449151D01*
X52114Y1448860D01*
Y1448485D01*
G01Y1448860D02*
X51989Y1449110D01*
X51780Y1449318D01*
X51530Y1449401D01*
X51280Y1449318D01*
X51072Y1449110D01*
X50947Y1448735D01*
X50989Y1448360D01*
X51155Y1447985D01*
G01X81589Y1445550D02*
X85589D01*
Y1452950D01*
G01X103000Y1471400D02*
X105500D01*
G01X103000Y1470442D02*
Y1472358D01*
G01X105500Y1473667D02*
X103000D01*
Y1474667D01*
X103125Y1475000D01*
X103417Y1475250D01*
X103750Y1475333D01*
X104083Y1475250D01*
X104333Y1475042D01*
X104458Y1474667D01*
Y1473667D01*
G01X105500Y1477517D02*
X104958Y1477600D01*
X104500Y1477725D01*
X104083Y1477892D01*
X103625Y1478100D01*
X103000Y1478433D01*
Y1476767D01*
G01X106983Y1504500D02*
Y1502708D01*
X107150Y1502333D01*
X107483Y1502083D01*
X107900Y1502000D01*
X108317Y1502083D01*
X108650Y1502333D01*
X108817Y1502708D01*
Y1504500D01*
G01X111500Y1502000D02*
Y1504500D01*
X109958Y1502708D01*
X112042D01*
G01X113392Y1502292D02*
X113683Y1502083D01*
X114017Y1502000D01*
X114350Y1502083D01*
X114642Y1502333D01*
X114850Y1502708D01*
X114933Y1503083D01*
Y1503542D01*
X114850Y1503917D01*
X114642Y1504250D01*
X114392Y1504417D01*
X114100Y1504500D01*
X113767Y1504417D01*
X113517Y1504250D01*
X113350Y1504000D01*
X113267Y1503667D01*
X113350Y1503375D01*
X113558Y1503083D01*
X113808Y1502917D01*
X114100Y1502875D01*
X114433Y1502958D01*
X114683Y1503167D01*
X114933Y1503542D01*
G01X106333Y1453433D02*
X108125D01*
X108500Y1453600D01*
X108750Y1453933D01*
X108833Y1454350D01*
X108750Y1454767D01*
X108500Y1455100D01*
X108125Y1455267D01*
X106333D01*
G01X106750Y1456658D02*
X106500Y1456908D01*
X106375Y1457200D01*
X106333Y1457533D01*
X106416Y1457950D01*
X106625Y1458242D01*
X106875Y1458325D01*
X107125Y1458283D01*
X107333Y1458117D01*
X107750Y1457283D01*
X108041Y1456908D01*
X108458Y1456658D01*
X108833Y1456575D01*
Y1458325D01*
G01X106333Y1460550D02*
X106416Y1460217D01*
X106625Y1459967D01*
X106875Y1459800D01*
X107208Y1459675D01*
X107583Y1459633D01*
X107958Y1459675D01*
X108291Y1459800D01*
X108541Y1459967D01*
X108750Y1460217D01*
X108833Y1460550D01*
X108750Y1460883D01*
X108541Y1461133D01*
X108291Y1461300D01*
X107958Y1461425D01*
X107583Y1461467D01*
X107208Y1461425D01*
X106875Y1461300D01*
X106625Y1461133D01*
X106416Y1460883D01*
X106333Y1460550D01*
G01X108833Y1463650D02*
X108791Y1463942D01*
X108666Y1464275D01*
X108458Y1464483D01*
X108166Y1464567D01*
X107875Y1464483D01*
X107625Y1464233D01*
X107500Y1463858D01*
Y1463442D01*
X107416Y1463192D01*
X107208Y1462983D01*
X106916Y1462900D01*
X106625Y1463025D01*
X106416Y1463317D01*
X106333Y1463650D01*
X106416Y1463983D01*
X106625Y1464275D01*
X106916Y1464400D01*
X107208Y1464317D01*
X107416Y1464108D01*
X107500Y1463858D01*
Y1463442D01*
X107625Y1463067D01*
X107875Y1462817D01*
X108166Y1462733D01*
X108458Y1462817D01*
X108666Y1463025D01*
X108791Y1463358D01*
X108833Y1463650D01*
G01X87781Y1465958D02*
X101181D01*
G01X87781Y1455958D02*
Y1465958D01*
G01X101181Y1455958D02*
X87781D01*
G01X101181Y1465958D02*
Y1455958D01*
G01X95417Y1529747D02*
X95292Y1529497D01*
X95209Y1529205D01*
Y1528872D01*
X95334Y1528497D01*
X95542Y1528205D01*
X95792Y1527997D01*
X96209Y1527830D01*
X96584Y1527788D01*
X96959Y1527872D01*
X97209Y1527997D01*
X97459Y1528247D01*
X97626Y1528538D01*
X97709Y1528830D01*
Y1529122D01*
X97626Y1529413D01*
X97501Y1529663D01*
X97334Y1529872D01*
G01X97209Y1531013D02*
X97501Y1531263D01*
X97667Y1531597D01*
X97709Y1531972D01*
X97667Y1532305D01*
X97459Y1532638D01*
X97209Y1532847D01*
X96959Y1532888D01*
X96667Y1532805D01*
X96459Y1532513D01*
X96376Y1532222D01*
Y1531847D01*
G01Y1532222D02*
X96251Y1532472D01*
X96042Y1532680D01*
X95792Y1532763D01*
X95542Y1532680D01*
X95334Y1532472D01*
X95209Y1532097D01*
X95251Y1531722D01*
X95417Y1531347D01*
G01X97709Y1535030D02*
X97667Y1535322D01*
X97542Y1535655D01*
X97334Y1535863D01*
X97042Y1535947D01*
X96751Y1535863D01*
X96501Y1535613D01*
X96376Y1535238D01*
Y1534822D01*
X96292Y1534572D01*
X96084Y1534363D01*
X95792Y1534280D01*
X95501Y1534405D01*
X95292Y1534697D01*
X95209Y1535030D01*
X95292Y1535363D01*
X95501Y1535655D01*
X95792Y1535780D01*
X96084Y1535697D01*
X96292Y1535488D01*
X96376Y1535238D01*
Y1534822D01*
X96501Y1534447D01*
X96751Y1534197D01*
X97042Y1534113D01*
X97334Y1534197D01*
X97542Y1534405D01*
X97667Y1534738D01*
X97709Y1535030D01*
G01Y1538130D02*
X97667Y1538422D01*
X97542Y1538755D01*
X97334Y1538963D01*
X97042Y1539047D01*
X96751Y1538963D01*
X96501Y1538713D01*
X96376Y1538338D01*
Y1537922D01*
X96292Y1537672D01*
X96084Y1537463D01*
X95792Y1537380D01*
X95501Y1537505D01*
X95292Y1537797D01*
X95209Y1538130D01*
X95292Y1538463D01*
X95501Y1538755D01*
X95792Y1538880D01*
X96084Y1538797D01*
X96292Y1538588D01*
X96376Y1538338D01*
Y1537922D01*
X96501Y1537547D01*
X96751Y1537297D01*
X97042Y1537213D01*
X97334Y1537297D01*
X97542Y1537505D01*
X97667Y1537838D01*
X97709Y1538130D01*
G01X79000Y1554900D02*
X78958Y1554567D01*
X78792Y1554275D01*
X78542Y1554025D01*
X78250Y1553858D01*
X77917Y1553775D01*
X77583D01*
X77250Y1553858D01*
X76958Y1554025D01*
X76708Y1554275D01*
X76542Y1554567D01*
X76500Y1554900D01*
X76542Y1555233D01*
X76708Y1555525D01*
X76958Y1555775D01*
X77250Y1555942D01*
X77583Y1556025D01*
X77917D01*
X78250Y1555942D01*
X78542Y1555775D01*
X78792Y1555525D01*
X78958Y1555233D01*
X79000Y1554900D01*
G01X78333Y1555233D02*
X79000Y1555733D01*
G01Y1558000D02*
X76500D01*
X77000Y1557500D01*
G01X79000D02*
Y1558500D01*
G01Y1561600D02*
X76500D01*
X78292Y1560058D01*
Y1562142D01*
G01X101500Y1559500D02*
Y1573500D01*
G01X88500Y1559500D02*
X101500D01*
G01X88500Y1573500D02*
Y1559500D01*
G01X101500Y1573500D02*
X88500D01*
G01X87517Y1542500D02*
Y1545000D01*
X88558D01*
X88892Y1544875D01*
X89100Y1544708D01*
X89183Y1544375D01*
X89100Y1544042D01*
X88850Y1543833D01*
X88558Y1543708D01*
X87517D01*
G01X88558D02*
X89183Y1542500D01*
G01X91450D02*
Y1545000D01*
X90950Y1544500D01*
G01Y1542500D02*
X91950D01*
G01X95050D02*
Y1545000D01*
X93508Y1543208D01*
X95592D01*
G01X98150Y1542500D02*
Y1545000D01*
X96608Y1543208D01*
X98692D01*
G01X100700Y1554500D02*
Y1558500D01*
X93300D01*
G01X89209Y1527997D02*
X86709D01*
Y1529038D01*
X86834Y1529372D01*
X87001Y1529580D01*
X87334Y1529663D01*
X87667Y1529580D01*
X87876Y1529330D01*
X88001Y1529038D01*
Y1527997D01*
G01Y1529038D02*
X89209Y1529663D01*
G01X88834Y1531013D02*
X89042Y1531263D01*
X89167Y1531555D01*
X89209Y1531930D01*
X89126Y1532305D01*
X88959Y1532597D01*
X88667Y1532805D01*
X88334Y1532847D01*
X88001Y1532763D01*
X87792Y1532555D01*
X87626Y1532263D01*
X87584Y1531972D01*
X87626Y1531680D01*
X87792Y1531305D01*
X86709Y1531430D01*
Y1532555D01*
G01X88834Y1534113D02*
X89042Y1534363D01*
X89167Y1534655D01*
X89209Y1535030D01*
X89126Y1535405D01*
X88959Y1535697D01*
X88667Y1535905D01*
X88334Y1535947D01*
X88001Y1535863D01*
X87792Y1535655D01*
X87626Y1535363D01*
X87584Y1535072D01*
X87626Y1534780D01*
X87792Y1534405D01*
X86709Y1534530D01*
Y1535655D01*
G01X89209Y1538047D02*
X88667Y1538130D01*
X88209Y1538255D01*
X87792Y1538422D01*
X87334Y1538630D01*
X86709Y1538963D01*
Y1537297D01*
G01X92500Y1554200D02*
X88500D01*
Y1546800D01*
G01X93709Y1527997D02*
X91209D01*
Y1529038D01*
X91334Y1529372D01*
X91501Y1529580D01*
X91834Y1529663D01*
X92167Y1529580D01*
X92376Y1529330D01*
X92501Y1529038D01*
Y1527997D01*
G01Y1529038D02*
X93709Y1529663D01*
G01X93334Y1531013D02*
X93542Y1531263D01*
X93667Y1531555D01*
X93709Y1531930D01*
X93626Y1532305D01*
X93459Y1532597D01*
X93167Y1532805D01*
X92834Y1532847D01*
X92501Y1532763D01*
X92292Y1532555D01*
X92126Y1532263D01*
X92084Y1531972D01*
X92126Y1531680D01*
X92292Y1531305D01*
X91209Y1531430D01*
Y1532555D01*
G01X93709Y1534947D02*
X93167Y1535030D01*
X92709Y1535155D01*
X92292Y1535322D01*
X91834Y1535530D01*
X91209Y1535863D01*
Y1534197D01*
G01X91626Y1537338D02*
X91376Y1537588D01*
X91251Y1537880D01*
X91209Y1538213D01*
X91292Y1538630D01*
X91501Y1538922D01*
X91751Y1539005D01*
X92001Y1538963D01*
X92209Y1538797D01*
X92626Y1537963D01*
X92917Y1537588D01*
X93334Y1537338D01*
X93709Y1537255D01*
Y1539005D01*
G01X93000Y1546800D02*
X97000D01*
Y1554200D01*
G01X98675Y1533333D02*
X99008Y1533125D01*
X99383Y1533000D01*
X99717D01*
X100050Y1533125D01*
X100300Y1533333D01*
X100425Y1533625D01*
X100342Y1533917D01*
X100133Y1534167D01*
X99758Y1534333D01*
X99258Y1534417D01*
X98967Y1534583D01*
X98842Y1534875D01*
X98925Y1535167D01*
X99133Y1535375D01*
X99425Y1535500D01*
X99717D01*
X100008Y1535417D01*
X100258Y1535208D01*
G01X101817Y1533000D02*
Y1535500D01*
X102858D01*
X103192Y1535375D01*
X103400Y1535208D01*
X103483Y1534875D01*
X103400Y1534542D01*
X103150Y1534333D01*
X102858Y1534208D01*
X101817D01*
G01X102858D02*
X103483Y1533000D01*
G01X105750D02*
Y1535500D01*
X105250Y1535000D01*
G01Y1533000D02*
X106250D01*
G01X108850D02*
Y1535500D01*
X108350Y1535000D01*
G01Y1533000D02*
X109350D01*
G01X111950Y1535500D02*
X111617Y1535417D01*
X111367Y1535208D01*
X111200Y1534958D01*
X111075Y1534625D01*
X111033Y1534250D01*
X111075Y1533875D01*
X111200Y1533542D01*
X111367Y1533292D01*
X111617Y1533083D01*
X111950Y1533000D01*
X112283Y1533083D01*
X112533Y1533292D01*
X112700Y1533542D01*
X112825Y1533875D01*
X112867Y1534250D01*
X112825Y1534625D01*
X112700Y1534958D01*
X112533Y1535208D01*
X112283Y1535417D01*
X111950Y1535500D01*
G01X114133Y1533500D02*
X114383Y1533208D01*
X114717Y1533042D01*
X115092Y1533000D01*
X115425Y1533042D01*
X115758Y1533250D01*
X115967Y1533500D01*
X116008Y1533750D01*
X115925Y1534042D01*
X115633Y1534250D01*
X115342Y1534333D01*
X114967D01*
G01X115342D02*
X115592Y1534458D01*
X115800Y1534667D01*
X115883Y1534917D01*
X115800Y1535167D01*
X115592Y1535375D01*
X115217Y1535500D01*
X114842Y1535458D01*
X114467Y1535292D01*
G01X107100Y1545700D02*
Y1541700D01*
X114500D01*
G01X98675Y1537333D02*
X99008Y1537125D01*
X99383Y1537000D01*
X99717D01*
X100050Y1537125D01*
X100300Y1537333D01*
X100425Y1537625D01*
X100342Y1537917D01*
X100133Y1538167D01*
X99758Y1538333D01*
X99258Y1538417D01*
X98967Y1538583D01*
X98842Y1538875D01*
X98925Y1539167D01*
X99133Y1539375D01*
X99425Y1539500D01*
X99717D01*
X100008Y1539417D01*
X100258Y1539208D01*
G01X101817Y1537000D02*
Y1539500D01*
X102858D01*
X103192Y1539375D01*
X103400Y1539208D01*
X103483Y1538875D01*
X103400Y1538542D01*
X103150Y1538333D01*
X102858Y1538208D01*
X101817D01*
G01X102858D02*
X103483Y1537000D01*
G01X105750D02*
Y1539500D01*
X105250Y1539000D01*
G01Y1537000D02*
X106250D01*
G01X108850D02*
Y1539500D01*
X108350Y1539000D01*
G01Y1537000D02*
X109350D01*
G01X111950Y1539500D02*
X111617Y1539417D01*
X111367Y1539208D01*
X111200Y1538958D01*
X111075Y1538625D01*
X111033Y1538250D01*
X111075Y1537875D01*
X111200Y1537542D01*
X111367Y1537292D01*
X111617Y1537083D01*
X111950Y1537000D01*
X112283Y1537083D01*
X112533Y1537292D01*
X112700Y1537542D01*
X112825Y1537875D01*
X112867Y1538250D01*
X112825Y1538625D01*
X112700Y1538958D01*
X112533Y1539208D01*
X112283Y1539417D01*
X111950Y1539500D01*
G01X115550Y1537000D02*
Y1539500D01*
X114008Y1537708D01*
X116092D01*
G01X114500Y1546200D02*
Y1550200D01*
X107100D01*
G01X111100Y1572400D02*
Y1553200D01*
X122300D01*
Y1572400D01*
X111100D01*
G01X74834Y1553983D02*
X72334D01*
Y1554817D01*
X72459Y1555150D01*
X72626Y1555400D01*
X72876Y1555608D01*
X73167Y1555775D01*
X73584Y1555817D01*
X74001Y1555775D01*
X74292Y1555608D01*
X74542Y1555400D01*
X74709Y1555150D01*
X74834Y1554817D01*
Y1553983D01*
G01X72751Y1557208D02*
X72501Y1557458D01*
X72376Y1557750D01*
X72334Y1558083D01*
X72417Y1558500D01*
X72626Y1558792D01*
X72876Y1558875D01*
X73126Y1558833D01*
X73334Y1558667D01*
X73751Y1557833D01*
X74042Y1557458D01*
X74459Y1557208D01*
X74834Y1557125D01*
Y1558875D01*
G01Y1561600D02*
X72334D01*
X74126Y1560058D01*
Y1562142D01*
G01X80500Y1551500D02*
Y1567600D01*
G01X87500Y1551500D02*
X80500D01*
G01X87500Y1567600D02*
Y1551500D01*
G01X80500Y1567600D02*
X87500D01*
G01X111417Y1627000D02*
Y1629500D01*
X112417D01*
X112750Y1629375D01*
X113000Y1629083D01*
X113083Y1628750D01*
X113000Y1628417D01*
X112792Y1628167D01*
X112417Y1628042D01*
X111417D01*
G01X116267Y1629292D02*
X116017Y1629417D01*
X115725Y1629500D01*
X115392D01*
X115017Y1629375D01*
X114725Y1629167D01*
X114517Y1628917D01*
X114350Y1628500D01*
X114308Y1628125D01*
X114392Y1627750D01*
X114517Y1627500D01*
X114767Y1627250D01*
X115058Y1627083D01*
X115350Y1627000D01*
X115642D01*
X115933Y1627083D01*
X116183Y1627208D01*
X116392Y1627375D01*
G01X118450Y1627000D02*
Y1629500D01*
X117950Y1629000D01*
G01Y1627000D02*
X118950D01*
G01X121550D02*
Y1629500D01*
X121050Y1629000D01*
G01Y1627000D02*
X122050D01*
G01X124650D02*
X124942Y1627042D01*
X125275Y1627167D01*
X125483Y1627375D01*
X125567Y1627667D01*
X125483Y1627958D01*
X125233Y1628208D01*
X124858Y1628333D01*
X124442D01*
X124192Y1628417D01*
X123983Y1628625D01*
X123900Y1628917D01*
X124025Y1629208D01*
X124317Y1629417D01*
X124650Y1629500D01*
X124983Y1629417D01*
X125275Y1629208D01*
X125400Y1628917D01*
X125317Y1628625D01*
X125108Y1628417D01*
X124858Y1628333D01*
X124442D01*
X124067Y1628208D01*
X123817Y1627958D01*
X123733Y1627667D01*
X123817Y1627375D01*
X124025Y1627167D01*
X124358Y1627042D01*
X124650Y1627000D01*
G01X126958Y1629083D02*
X127208Y1629333D01*
X127500Y1629458D01*
X127833Y1629500D01*
X128250Y1629417D01*
X128542Y1629208D01*
X128625Y1628958D01*
X128583Y1628708D01*
X128417Y1628500D01*
X127583Y1628083D01*
X127208Y1627792D01*
X126958Y1627375D01*
X126875Y1627000D01*
X128625D01*
G01X111900Y1593000D02*
X111567Y1593042D01*
X111275Y1593208D01*
X111025Y1593458D01*
X110858Y1593750D01*
X110775Y1594083D01*
Y1594417D01*
X110858Y1594750D01*
X111025Y1595042D01*
X111275Y1595292D01*
X111567Y1595458D01*
X111900Y1595500D01*
X112233Y1595458D01*
X112525Y1595292D01*
X112775Y1595042D01*
X112942Y1594750D01*
X113025Y1594417D01*
Y1594083D01*
X112942Y1593750D01*
X112775Y1593458D01*
X112525Y1593208D01*
X112233Y1593042D01*
X111900Y1593000D01*
G01X112233Y1593667D02*
X112733Y1593000D01*
G01X114083Y1593375D02*
X114333Y1593167D01*
X114625Y1593042D01*
X115000Y1593000D01*
X115375Y1593083D01*
X115667Y1593250D01*
X115875Y1593542D01*
X115917Y1593875D01*
X115833Y1594208D01*
X115625Y1594417D01*
X115333Y1594583D01*
X115042Y1594625D01*
X114750Y1594583D01*
X114375Y1594417D01*
X114500Y1595500D01*
X115625D01*
G01X117308Y1594042D02*
X117600Y1594333D01*
X117850Y1594500D01*
X118183Y1594583D01*
X118475Y1594500D01*
X118683Y1594333D01*
X118850Y1594083D01*
X118892Y1593792D01*
X118850Y1593542D01*
X118683Y1593292D01*
X118433Y1593083D01*
X118142Y1593000D01*
X117808Y1593083D01*
X117517Y1593333D01*
X117350Y1593708D01*
X117308Y1594125D01*
X117392Y1594667D01*
X117517Y1594958D01*
X117725Y1595250D01*
X118017Y1595458D01*
X118308Y1595500D01*
X118600Y1595417D01*
X118808Y1595208D01*
G01X119875Y1591275D02*
X105875D01*
G01Y1578275D02*
X119875D01*
G01X105875Y1591275D02*
Y1578275D01*
G01X87900Y1592500D02*
X87567Y1592542D01*
X87275Y1592708D01*
X87025Y1592958D01*
X86858Y1593250D01*
X86775Y1593583D01*
Y1593917D01*
X86858Y1594250D01*
X87025Y1594542D01*
X87275Y1594792D01*
X87567Y1594958D01*
X87900Y1595000D01*
X88233Y1594958D01*
X88525Y1594792D01*
X88775Y1594542D01*
X88942Y1594250D01*
X89025Y1593917D01*
Y1593583D01*
X88942Y1593250D01*
X88775Y1592958D01*
X88525Y1592708D01*
X88233Y1592542D01*
X87900Y1592500D01*
G01X88233Y1593167D02*
X88733Y1592500D01*
G01X90083Y1592875D02*
X90333Y1592667D01*
X90625Y1592542D01*
X91000Y1592500D01*
X91375Y1592583D01*
X91667Y1592750D01*
X91875Y1593042D01*
X91917Y1593375D01*
X91833Y1593708D01*
X91625Y1593917D01*
X91333Y1594083D01*
X91042Y1594125D01*
X90750Y1594083D01*
X90375Y1593917D01*
X90500Y1595000D01*
X91625D01*
G01X94017Y1592500D02*
X94100Y1593042D01*
X94225Y1593500D01*
X94392Y1593917D01*
X94600Y1594375D01*
X94933Y1595000D01*
X93267D01*
G01X100375Y1591275D02*
X86375D01*
G01X100375Y1578275D02*
Y1591275D01*
G01X86375Y1578275D02*
X100375D01*
G01X86375Y1591275D02*
Y1578275D01*
G01X79900Y1591467D02*
X77400D01*
Y1592508D01*
X77525Y1592842D01*
X77692Y1593050D01*
X78025Y1593133D01*
X78358Y1593050D01*
X78567Y1592800D01*
X78692Y1592508D01*
Y1591467D01*
G01Y1592508D02*
X79900Y1593133D01*
G01X79608Y1594692D02*
X79817Y1594983D01*
X79900Y1595317D01*
X79817Y1595650D01*
X79567Y1595942D01*
X79192Y1596150D01*
X78817Y1596233D01*
X78358D01*
X77983Y1596150D01*
X77650Y1595942D01*
X77483Y1595692D01*
X77400Y1595400D01*
X77483Y1595067D01*
X77650Y1594817D01*
X77900Y1594650D01*
X78233Y1594567D01*
X78525Y1594650D01*
X78817Y1594858D01*
X78983Y1595108D01*
X79025Y1595400D01*
X78942Y1595733D01*
X78733Y1595983D01*
X78358Y1596233D01*
G01X79525Y1597583D02*
X79733Y1597833D01*
X79858Y1598125D01*
X79900Y1598500D01*
X79817Y1598875D01*
X79650Y1599167D01*
X79358Y1599375D01*
X79025Y1599417D01*
X78692Y1599333D01*
X78483Y1599125D01*
X78317Y1598833D01*
X78275Y1598542D01*
X78317Y1598250D01*
X78483Y1597875D01*
X77400Y1598000D01*
Y1599125D01*
G01X79900Y1601600D02*
X77400D01*
X77900Y1601100D01*
G01X79900D02*
Y1602100D01*
G01X78858Y1603908D02*
X78567Y1604200D01*
X78400Y1604450D01*
X78317Y1604783D01*
X78400Y1605075D01*
X78567Y1605283D01*
X78817Y1605450D01*
X79108Y1605492D01*
X79358Y1605450D01*
X79608Y1605283D01*
X79817Y1605033D01*
X79900Y1604742D01*
X79817Y1604408D01*
X79567Y1604117D01*
X79192Y1603950D01*
X78775Y1603908D01*
X78233Y1603992D01*
X77942Y1604117D01*
X77650Y1604325D01*
X77442Y1604617D01*
X77400Y1604908D01*
X77483Y1605200D01*
X77692Y1605408D01*
G01X77375Y1578175D02*
X81375D01*
Y1585575D01*
G01X83900Y1591467D02*
X81400D01*
Y1592508D01*
X81525Y1592842D01*
X81692Y1593050D01*
X82025Y1593133D01*
X82358Y1593050D01*
X82567Y1592800D01*
X82692Y1592508D01*
Y1591467D01*
G01Y1592508D02*
X83900Y1593133D01*
G01X83608Y1594692D02*
X83817Y1594983D01*
X83900Y1595317D01*
X83817Y1595650D01*
X83567Y1595942D01*
X83192Y1596150D01*
X82817Y1596233D01*
X82358D01*
X81983Y1596150D01*
X81650Y1595942D01*
X81483Y1595692D01*
X81400Y1595400D01*
X81483Y1595067D01*
X81650Y1594817D01*
X81900Y1594650D01*
X82233Y1594567D01*
X82525Y1594650D01*
X82817Y1594858D01*
X82983Y1595108D01*
X83025Y1595400D01*
X82942Y1595733D01*
X82733Y1595983D01*
X82358Y1596233D01*
G01X83900Y1598417D02*
X83358Y1598500D01*
X82900Y1598625D01*
X82483Y1598792D01*
X82025Y1599000D01*
X81400Y1599333D01*
Y1597667D01*
G01X82858Y1600808D02*
X82567Y1601100D01*
X82400Y1601350D01*
X82317Y1601683D01*
X82400Y1601975D01*
X82567Y1602183D01*
X82817Y1602350D01*
X83108Y1602392D01*
X83358Y1602350D01*
X83608Y1602183D01*
X83817Y1601933D01*
X83900Y1601642D01*
X83817Y1601308D01*
X83567Y1601017D01*
X83192Y1600850D01*
X82775Y1600808D01*
X82233Y1600892D01*
X81942Y1601017D01*
X81650Y1601225D01*
X81442Y1601517D01*
X81400Y1601808D01*
X81483Y1602100D01*
X81692Y1602308D01*
G01X82858Y1603908D02*
X82567Y1604200D01*
X82400Y1604450D01*
X82317Y1604783D01*
X82400Y1605075D01*
X82567Y1605283D01*
X82817Y1605450D01*
X83108Y1605492D01*
X83358Y1605450D01*
X83608Y1605283D01*
X83817Y1605033D01*
X83900Y1604742D01*
X83817Y1604408D01*
X83567Y1604117D01*
X83192Y1603950D01*
X82775Y1603908D01*
X82233Y1603992D01*
X81942Y1604117D01*
X81650Y1604325D01*
X81442Y1604617D01*
X81400Y1604908D01*
X81483Y1605200D01*
X81692Y1605408D01*
G01X85875Y1585575D02*
X81875D01*
Y1578175D01*
G01X76000Y1591967D02*
X73500D01*
Y1593008D01*
X73625Y1593342D01*
X73792Y1593550D01*
X74125Y1593633D01*
X74458Y1593550D01*
X74667Y1593300D01*
X74792Y1593008D01*
Y1591967D01*
G01Y1593008D02*
X76000Y1593633D01*
G01X75708Y1595192D02*
X75917Y1595483D01*
X76000Y1595817D01*
X75917Y1596150D01*
X75667Y1596442D01*
X75292Y1596650D01*
X74917Y1596733D01*
X74458D01*
X74083Y1596650D01*
X73750Y1596442D01*
X73583Y1596192D01*
X73500Y1595900D01*
X73583Y1595567D01*
X73750Y1595317D01*
X74000Y1595150D01*
X74333Y1595067D01*
X74625Y1595150D01*
X74917Y1595358D01*
X75083Y1595608D01*
X75125Y1595900D01*
X75042Y1596233D01*
X74833Y1596483D01*
X74458Y1596733D01*
G01X76000Y1599000D02*
X75958Y1599292D01*
X75833Y1599625D01*
X75625Y1599833D01*
X75333Y1599917D01*
X75042Y1599833D01*
X74792Y1599583D01*
X74667Y1599208D01*
Y1598792D01*
X74583Y1598542D01*
X74375Y1598333D01*
X74083Y1598250D01*
X73792Y1598375D01*
X73583Y1598667D01*
X73500Y1599000D01*
X73583Y1599333D01*
X73792Y1599625D01*
X74083Y1599750D01*
X74375Y1599667D01*
X74583Y1599458D01*
X74667Y1599208D01*
Y1598792D01*
X74792Y1598417D01*
X75042Y1598167D01*
X75333Y1598083D01*
X75625Y1598167D01*
X75833Y1598375D01*
X75958Y1598708D01*
X76000Y1599000D01*
G01Y1602100D02*
X73500D01*
X74000Y1601600D01*
G01X76000D02*
Y1602600D01*
G01X75708Y1604492D02*
X75917Y1604783D01*
X76000Y1605117D01*
X75917Y1605450D01*
X75667Y1605742D01*
X75292Y1605950D01*
X74917Y1606033D01*
X74458D01*
X74083Y1605950D01*
X73750Y1605742D01*
X73583Y1605492D01*
X73500Y1605200D01*
X73583Y1604867D01*
X73750Y1604617D01*
X74000Y1604450D01*
X74333Y1604367D01*
X74625Y1604450D01*
X74917Y1604658D01*
X75083Y1604908D01*
X75125Y1605200D01*
X75042Y1605533D01*
X74833Y1605783D01*
X74458Y1606033D01*
G01X73256Y1581675D02*
X77256D01*
Y1589075D01*
G01X104500Y1592967D02*
X102000D01*
Y1594008D01*
X102125Y1594342D01*
X102292Y1594550D01*
X102625Y1594633D01*
X102958Y1594550D01*
X103167Y1594300D01*
X103292Y1594008D01*
Y1592967D01*
G01Y1594008D02*
X104500Y1594633D01*
G01X104208Y1596192D02*
X104417Y1596483D01*
X104500Y1596817D01*
X104417Y1597150D01*
X104167Y1597442D01*
X103792Y1597650D01*
X103417Y1597733D01*
X102958D01*
X102583Y1597650D01*
X102250Y1597442D01*
X102083Y1597192D01*
X102000Y1596900D01*
X102083Y1596567D01*
X102250Y1596317D01*
X102500Y1596150D01*
X102833Y1596067D01*
X103125Y1596150D01*
X103417Y1596358D01*
X103583Y1596608D01*
X103625Y1596900D01*
X103542Y1597233D01*
X103333Y1597483D01*
X102958Y1597733D01*
G01X104500Y1600000D02*
X104458Y1600292D01*
X104333Y1600625D01*
X104125Y1600833D01*
X103833Y1600917D01*
X103542Y1600833D01*
X103292Y1600583D01*
X103167Y1600208D01*
Y1599792D01*
X103083Y1599542D01*
X102875Y1599333D01*
X102583Y1599250D01*
X102292Y1599375D01*
X102083Y1599667D01*
X102000Y1600000D01*
X102083Y1600333D01*
X102292Y1600625D01*
X102583Y1600750D01*
X102875Y1600667D01*
X103083Y1600458D01*
X103167Y1600208D01*
Y1599792D01*
X103292Y1599417D01*
X103542Y1599167D01*
X103833Y1599083D01*
X104125Y1599167D01*
X104333Y1599375D01*
X104458Y1599708D01*
X104500Y1600000D01*
G01X102417Y1602308D02*
X102167Y1602558D01*
X102042Y1602850D01*
X102000Y1603183D01*
X102083Y1603600D01*
X102292Y1603892D01*
X102542Y1603975D01*
X102792Y1603933D01*
X103000Y1603767D01*
X103417Y1602933D01*
X103708Y1602558D01*
X104125Y1602308D01*
X104500Y1602225D01*
Y1603975D01*
G01X102000Y1606200D02*
X102083Y1605867D01*
X102292Y1605617D01*
X102542Y1605450D01*
X102875Y1605325D01*
X103250Y1605283D01*
X103625Y1605325D01*
X103958Y1605450D01*
X104208Y1605617D01*
X104417Y1605867D01*
X104500Y1606200D01*
X104417Y1606533D01*
X104208Y1606783D01*
X103958Y1606950D01*
X103625Y1607075D01*
X103250Y1607117D01*
X102875Y1607075D01*
X102542Y1606950D01*
X102292Y1606783D01*
X102083Y1606533D01*
X102000Y1606200D01*
G01X101025Y1579325D02*
X105025D01*
Y1586725D01*
G01X94917Y1609300D02*
Y1611800D01*
X95958D01*
X96292Y1611675D01*
X96500Y1611508D01*
X96583Y1611175D01*
X96500Y1610842D01*
X96250Y1610633D01*
X95958Y1610508D01*
X94917D01*
G01X95958D02*
X96583Y1609300D01*
G01X98142Y1609592D02*
X98433Y1609383D01*
X98767Y1609300D01*
X99100Y1609383D01*
X99392Y1609633D01*
X99600Y1610008D01*
X99683Y1610383D01*
Y1610842D01*
X99600Y1611217D01*
X99392Y1611550D01*
X99142Y1611717D01*
X98850Y1611800D01*
X98517Y1611717D01*
X98267Y1611550D01*
X98100Y1611300D01*
X98017Y1610967D01*
X98100Y1610675D01*
X98308Y1610383D01*
X98558Y1610217D01*
X98850Y1610175D01*
X99183Y1610258D01*
X99433Y1610467D01*
X99683Y1610842D01*
G01X101950Y1609300D02*
X102242Y1609342D01*
X102575Y1609467D01*
X102783Y1609675D01*
X102867Y1609967D01*
X102783Y1610258D01*
X102533Y1610508D01*
X102158Y1610633D01*
X101742D01*
X101492Y1610717D01*
X101283Y1610925D01*
X101200Y1611217D01*
X101325Y1611508D01*
X101617Y1611717D01*
X101950Y1611800D01*
X102283Y1611717D01*
X102575Y1611508D01*
X102700Y1611217D01*
X102617Y1610925D01*
X102408Y1610717D01*
X102158Y1610633D01*
X101742D01*
X101367Y1610508D01*
X101117Y1610258D01*
X101033Y1609967D01*
X101117Y1609675D01*
X101325Y1609467D01*
X101658Y1609342D01*
X101950Y1609300D01*
G01X105550D02*
Y1611800D01*
X104008Y1610008D01*
X106092D01*
G01X108650Y1609300D02*
Y1611800D01*
X107108Y1610008D01*
X109192D01*
G01X94500Y1620200D02*
X99700D01*
G01X94500Y1613200D02*
X102300D01*
G01X94500Y1620200D02*
Y1613200D01*
G01X107900Y1620200D02*
X99200D01*
G01X107900Y1613200D02*
Y1620200D01*
G01X101500Y1613200D02*
X107900D01*
G01X47600Y1611400D02*
Y1637400D01*
G01X69867Y1609700D02*
Y1612200D01*
X70908D01*
X71242Y1612075D01*
X71450Y1611908D01*
X71533Y1611575D01*
X71450Y1611242D01*
X71200Y1611033D01*
X70908Y1610908D01*
X69867D01*
G01X70908D02*
X71533Y1609700D01*
G01X73092Y1609992D02*
X73383Y1609783D01*
X73717Y1609700D01*
X74050Y1609783D01*
X74342Y1610033D01*
X74550Y1610408D01*
X74633Y1610783D01*
Y1611242D01*
X74550Y1611617D01*
X74342Y1611950D01*
X74092Y1612117D01*
X73800Y1612200D01*
X73467Y1612117D01*
X73217Y1611950D01*
X73050Y1611700D01*
X72967Y1611367D01*
X73050Y1611075D01*
X73258Y1610783D01*
X73508Y1610617D01*
X73800Y1610575D01*
X74133Y1610658D01*
X74383Y1610867D01*
X74633Y1611242D01*
G01X76108Y1611783D02*
X76358Y1612033D01*
X76650Y1612158D01*
X76983Y1612200D01*
X77400Y1612117D01*
X77692Y1611908D01*
X77775Y1611658D01*
X77733Y1611408D01*
X77567Y1611200D01*
X76733Y1610783D01*
X76358Y1610492D01*
X76108Y1610075D01*
X76025Y1609700D01*
X77775D01*
G01X80500D02*
Y1612200D01*
X78958Y1610408D01*
X81042D01*
G01X83100Y1609700D02*
Y1612200D01*
X82600Y1611700D01*
G01Y1609700D02*
X83600D01*
G01X62700Y1630500D02*
Y1617500D01*
G01X88700Y1630500D02*
X62700D01*
G01X88700Y1617500D02*
Y1630500D01*
G01X62700Y1617500D02*
X88700D01*
G01X112150Y1661850D02*
Y1643150D01*
X101850D01*
Y1661850D01*
X112150D01*
G01X93000Y1624917D02*
X90500D01*
Y1625917D01*
X90625Y1626250D01*
X90917Y1626500D01*
X91250Y1626583D01*
X91583Y1626500D01*
X91833Y1626292D01*
X91958Y1625917D01*
Y1624917D01*
G01X90708Y1629767D02*
X90583Y1629517D01*
X90500Y1629225D01*
Y1628892D01*
X90625Y1628517D01*
X90833Y1628225D01*
X91083Y1628017D01*
X91500Y1627850D01*
X91875Y1627808D01*
X92250Y1627892D01*
X92500Y1628017D01*
X92750Y1628267D01*
X92917Y1628558D01*
X93000Y1628850D01*
Y1629142D01*
X92917Y1629433D01*
X92792Y1629683D01*
X92625Y1629892D01*
G01X93000Y1631950D02*
X90500D01*
X91000Y1631450D01*
G01X93000D02*
Y1632450D01*
G01Y1635050D02*
X90500D01*
X91000Y1634550D01*
G01X93000D02*
Y1635550D01*
G01Y1638150D02*
X92958Y1638442D01*
X92833Y1638775D01*
X92625Y1638983D01*
X92333Y1639067D01*
X92042Y1638983D01*
X91792Y1638733D01*
X91667Y1638358D01*
Y1637942D01*
X91583Y1637692D01*
X91375Y1637483D01*
X91083Y1637400D01*
X90792Y1637525D01*
X90583Y1637817D01*
X90500Y1638150D01*
X90583Y1638483D01*
X90792Y1638775D01*
X91083Y1638900D01*
X91375Y1638817D01*
X91583Y1638608D01*
X91667Y1638358D01*
Y1637942D01*
X91792Y1637567D01*
X92042Y1637317D01*
X92333Y1637233D01*
X92625Y1637317D01*
X92833Y1637525D01*
X92958Y1637858D01*
X93000Y1638150D01*
G01Y1641250D02*
X90500D01*
X91000Y1640750D01*
G01X93000D02*
Y1641750D01*
G01X94850Y1623550D02*
Y1642250D01*
X105150D01*
Y1623550D01*
X94850D01*
G01X104834Y1663417D02*
X102334D01*
Y1664417D01*
X102459Y1664750D01*
X102751Y1665000D01*
X103084Y1665083D01*
X103417Y1665000D01*
X103667Y1664792D01*
X103792Y1664417D01*
Y1663417D01*
G01X102542Y1668267D02*
X102417Y1668017D01*
X102334Y1667725D01*
Y1667392D01*
X102459Y1667017D01*
X102667Y1666725D01*
X102917Y1666517D01*
X103334Y1666350D01*
X103709Y1666308D01*
X104084Y1666392D01*
X104334Y1666517D01*
X104584Y1666767D01*
X104751Y1667058D01*
X104834Y1667350D01*
Y1667642D01*
X104751Y1667933D01*
X104626Y1668183D01*
X104459Y1668392D01*
G01X104834Y1670450D02*
X102334D01*
X102834Y1669950D01*
G01X104834D02*
Y1670950D01*
G01Y1673550D02*
X102334D01*
X102834Y1673050D01*
G01X104834D02*
Y1674050D01*
G01Y1676650D02*
X104792Y1676942D01*
X104667Y1677275D01*
X104459Y1677483D01*
X104167Y1677567D01*
X103876Y1677483D01*
X103626Y1677233D01*
X103501Y1676858D01*
Y1676442D01*
X103417Y1676192D01*
X103209Y1675983D01*
X102917Y1675900D01*
X102626Y1676025D01*
X102417Y1676317D01*
X102334Y1676650D01*
X102417Y1676983D01*
X102626Y1677275D01*
X102917Y1677400D01*
X103209Y1677317D01*
X103417Y1677108D01*
X103501Y1676858D01*
Y1676442D01*
X103626Y1676067D01*
X103876Y1675817D01*
X104167Y1675733D01*
X104459Y1675817D01*
X104667Y1676025D01*
X104792Y1676358D01*
X104834Y1676650D01*
G01X104334Y1678833D02*
X104626Y1679083D01*
X104792Y1679417D01*
X104834Y1679792D01*
X104792Y1680125D01*
X104584Y1680458D01*
X104334Y1680667D01*
X104084Y1680708D01*
X103792Y1680625D01*
X103584Y1680333D01*
X103501Y1680042D01*
Y1679667D01*
G01Y1680042D02*
X103376Y1680292D01*
X103167Y1680500D01*
X102917Y1680583D01*
X102667Y1680500D01*
X102459Y1680292D01*
X102334Y1679917D01*
X102376Y1679542D01*
X102542Y1679167D01*
G01X112800Y1663617D02*
X110300D01*
Y1664617D01*
X110425Y1664950D01*
X110717Y1665200D01*
X111050Y1665283D01*
X111383Y1665200D01*
X111633Y1664992D01*
X111758Y1664617D01*
Y1663617D01*
G01X110508Y1668467D02*
X110383Y1668217D01*
X110300Y1667925D01*
Y1667592D01*
X110425Y1667217D01*
X110633Y1666925D01*
X110883Y1666717D01*
X111300Y1666550D01*
X111675Y1666508D01*
X112050Y1666592D01*
X112300Y1666717D01*
X112550Y1666967D01*
X112717Y1667258D01*
X112800Y1667550D01*
Y1667842D01*
X112717Y1668133D01*
X112592Y1668383D01*
X112425Y1668592D01*
G01X112800Y1670650D02*
X110300D01*
X110800Y1670150D01*
G01X112800D02*
Y1671150D01*
G01Y1673750D02*
X110300D01*
X110800Y1673250D01*
G01X112800D02*
Y1674250D01*
G01Y1676850D02*
X112758Y1677142D01*
X112633Y1677475D01*
X112425Y1677683D01*
X112133Y1677767D01*
X111842Y1677683D01*
X111592Y1677433D01*
X111467Y1677058D01*
Y1676642D01*
X111383Y1676392D01*
X111175Y1676183D01*
X110883Y1676100D01*
X110592Y1676225D01*
X110383Y1676517D01*
X110300Y1676850D01*
X110383Y1677183D01*
X110592Y1677475D01*
X110883Y1677600D01*
X111175Y1677517D01*
X111383Y1677308D01*
X111467Y1677058D01*
Y1676642D01*
X111592Y1676267D01*
X111842Y1676017D01*
X112133Y1675933D01*
X112425Y1676017D01*
X112633Y1676225D01*
X112758Y1676558D01*
X112800Y1676850D01*
G01X110300Y1679950D02*
X110383Y1679617D01*
X110592Y1679367D01*
X110842Y1679200D01*
X111175Y1679075D01*
X111550Y1679033D01*
X111925Y1679075D01*
X112258Y1679200D01*
X112508Y1679367D01*
X112717Y1679617D01*
X112800Y1679950D01*
X112717Y1680283D01*
X112508Y1680533D01*
X112258Y1680700D01*
X111925Y1680825D01*
X111550Y1680867D01*
X111175Y1680825D01*
X110842Y1680700D01*
X110592Y1680533D01*
X110383Y1680283D01*
X110300Y1679950D01*
G01X103000Y1728567D02*
X103250Y1728775D01*
X103417Y1729025D01*
X103500Y1729317D01*
X103417Y1729650D01*
X103250Y1729900D01*
X103000Y1730150D01*
X102667Y1730233D01*
X101000D01*
G01X103500Y1732500D02*
X101000D01*
X101500Y1732000D01*
G01X103500D02*
Y1733000D01*
G01X101000Y1735600D02*
X101083Y1735267D01*
X101292Y1735017D01*
X101542Y1734850D01*
X101875Y1734725D01*
X102250Y1734683D01*
X102625Y1734725D01*
X102958Y1734850D01*
X103208Y1735017D01*
X103417Y1735267D01*
X103500Y1735600D01*
X103417Y1735933D01*
X103208Y1736183D01*
X102958Y1736350D01*
X102625Y1736475D01*
X102250Y1736517D01*
X101875Y1736475D01*
X101542Y1736350D01*
X101292Y1736183D01*
X101083Y1735933D01*
X101000Y1735600D01*
G01X107000Y1750917D02*
X104500D01*
Y1751917D01*
X104625Y1752250D01*
X104917Y1752500D01*
X105250Y1752583D01*
X105583Y1752500D01*
X105833Y1752292D01*
X105958Y1751917D01*
Y1750917D01*
G01X104708Y1755767D02*
X104583Y1755517D01*
X104500Y1755225D01*
Y1754892D01*
X104625Y1754517D01*
X104833Y1754225D01*
X105083Y1754017D01*
X105500Y1753850D01*
X105875Y1753808D01*
X106250Y1753892D01*
X106500Y1754017D01*
X106750Y1754267D01*
X106917Y1754558D01*
X107000Y1754850D01*
Y1755142D01*
X106917Y1755433D01*
X106792Y1755683D01*
X106625Y1755892D01*
G01X107000Y1757950D02*
X104500D01*
X105000Y1757450D01*
G01X107000D02*
Y1758450D01*
G01Y1761050D02*
X104500D01*
X105000Y1760550D01*
G01X107000D02*
Y1761550D01*
G01Y1764150D02*
X106958Y1764442D01*
X106833Y1764775D01*
X106625Y1764983D01*
X106333Y1765067D01*
X106042Y1764983D01*
X105792Y1764733D01*
X105667Y1764358D01*
Y1763942D01*
X105583Y1763692D01*
X105375Y1763483D01*
X105083Y1763400D01*
X104792Y1763525D01*
X104583Y1763817D01*
X104500Y1764150D01*
X104583Y1764483D01*
X104792Y1764775D01*
X105083Y1764900D01*
X105375Y1764817D01*
X105583Y1764608D01*
X105667Y1764358D01*
Y1763942D01*
X105792Y1763567D01*
X106042Y1763317D01*
X106333Y1763233D01*
X106625Y1763317D01*
X106833Y1763525D01*
X106958Y1763858D01*
X107000Y1764150D01*
G01Y1767750D02*
X104500D01*
X106292Y1766208D01*
Y1768292D01*
G01X92138Y1812175D02*
X92471Y1811967D01*
X92846Y1811842D01*
X93180D01*
X93513Y1811967D01*
X93763Y1812175D01*
X93888Y1812467D01*
X93805Y1812759D01*
X93596Y1813009D01*
X93221Y1813175D01*
X92721Y1813259D01*
X92430Y1813425D01*
X92305Y1813717D01*
X92388Y1814009D01*
X92596Y1814217D01*
X92888Y1814342D01*
X93180D01*
X93471Y1814259D01*
X93721Y1814050D01*
G01X95196Y1811842D02*
Y1814342D01*
X96030D01*
X96363Y1814217D01*
X96613Y1814050D01*
X96821Y1813800D01*
X96988Y1813509D01*
X97030Y1813092D01*
X96988Y1812675D01*
X96821Y1812384D01*
X96613Y1812134D01*
X96363Y1811967D01*
X96030Y1811842D01*
X95196D01*
G01X98296D02*
Y1814342D01*
X99130D01*
X99463Y1814217D01*
X99713Y1814050D01*
X99921Y1813800D01*
X100088Y1813509D01*
X100130Y1813092D01*
X100088Y1812675D01*
X99921Y1812384D01*
X99713Y1812134D01*
X99463Y1811967D01*
X99130Y1811842D01*
X98296D01*
G01X104371D02*
X105413Y1814342D01*
X106455Y1811842D01*
G01X106080Y1812717D02*
X104746D01*
G01X109430Y1814134D02*
X109180Y1814259D01*
X108888Y1814342D01*
X108555D01*
X108180Y1814217D01*
X107888Y1814009D01*
X107680Y1813759D01*
X107513Y1813342D01*
X107471Y1812967D01*
X107555Y1812592D01*
X107680Y1812342D01*
X107930Y1812092D01*
X108221Y1811925D01*
X108513Y1811842D01*
X108805D01*
X109096Y1811925D01*
X109346Y1812050D01*
X109555Y1812217D01*
G01X111613Y1814342D02*
Y1811842D01*
G01X110655Y1814342D02*
X112571D01*
G01X114713Y1811842D02*
Y1814342D01*
X114213Y1813842D01*
G01Y1811842D02*
X115213D01*
G01X117813Y1814342D02*
X117480Y1814259D01*
X117230Y1814050D01*
X117063Y1813800D01*
X116938Y1813467D01*
X116896Y1813092D01*
X116938Y1812717D01*
X117063Y1812384D01*
X117230Y1812134D01*
X117480Y1811925D01*
X117813Y1811842D01*
X118146Y1811925D01*
X118396Y1812134D01*
X118563Y1812384D01*
X118688Y1812717D01*
X118730Y1813092D01*
X118688Y1813467D01*
X118563Y1813800D01*
X118396Y1814050D01*
X118146Y1814259D01*
X117813Y1814342D01*
G01X92526Y1815765D02*
Y1818265D01*
X93526D01*
X93859Y1818140D01*
X94109Y1817848D01*
X94192Y1817515D01*
X94109Y1817182D01*
X93901Y1816932D01*
X93526Y1816807D01*
X92526D01*
G01X97292Y1815765D02*
X95626D01*
Y1818265D01*
X97292D01*
G01X96626Y1817057D02*
X95626D01*
G01X99892Y1817098D02*
X100059Y1817223D01*
X100184Y1817432D01*
X100267Y1817723D01*
X100184Y1817973D01*
X100017Y1818140D01*
X99726Y1818265D01*
X98601D01*
Y1815765D01*
X99976D01*
X100267Y1815932D01*
X100434Y1816182D01*
X100517Y1816473D01*
X100434Y1816765D01*
X100184Y1817015D01*
X99892Y1817098D01*
X98601D01*
G01X104717Y1815765D02*
X105759Y1818265D01*
X106801Y1815765D01*
G01X106426Y1816640D02*
X105092D01*
G01X108859Y1818265D02*
Y1815765D01*
G01X107901Y1818265D02*
X109817D01*
G01X111959D02*
Y1815765D01*
G01X111001Y1818265D02*
X112917D01*
G01X114101Y1815765D02*
Y1818265D01*
X116017Y1815765D01*
Y1818265D01*
G01X118159Y1815765D02*
Y1818265D01*
X117659Y1817765D01*
G01Y1815765D02*
X118659D01*
G01X121259Y1818265D02*
X120926Y1818182D01*
X120676Y1817973D01*
X120509Y1817723D01*
X120384Y1817390D01*
X120342Y1817015D01*
X120384Y1816640D01*
X120509Y1816307D01*
X120676Y1816057D01*
X120926Y1815848D01*
X121259Y1815765D01*
X121592Y1815848D01*
X121842Y1816057D01*
X122009Y1816307D01*
X122134Y1816640D01*
X122176Y1817015D01*
X122134Y1817390D01*
X122009Y1817723D01*
X121842Y1817973D01*
X121592Y1818182D01*
X121259Y1818265D01*
G01X48767Y1832467D02*
Y1829967D01*
X50433D01*
G01X53533D02*
X51867D01*
Y1832467D01*
X53533D01*
G01X52867Y1831259D02*
X51867D01*
G01X54883Y1829967D02*
Y1832467D01*
X55717D01*
X56050Y1832342D01*
X56300Y1832175D01*
X56508Y1831925D01*
X56675Y1831634D01*
X56717Y1831217D01*
X56675Y1830800D01*
X56508Y1830509D01*
X56300Y1830259D01*
X56050Y1830092D01*
X55717Y1829967D01*
X54883D01*
G01X58900D02*
Y1832467D01*
X58400Y1831967D01*
G01Y1829967D02*
X59400D01*
G01X62000Y1832467D02*
X61667Y1832384D01*
X61417Y1832175D01*
X61250Y1831925D01*
X61125Y1831592D01*
X61083Y1831217D01*
X61125Y1830842D01*
X61250Y1830509D01*
X61417Y1830259D01*
X61667Y1830050D01*
X62000Y1829967D01*
X62333Y1830050D01*
X62583Y1830259D01*
X62750Y1830509D01*
X62875Y1830842D01*
X62917Y1831217D01*
X62875Y1831592D01*
X62750Y1831925D01*
X62583Y1832175D01*
X62333Y1832384D01*
X62000Y1832467D01*
G01X67135Y1826515D02*
Y1834115D01*
X78535D01*
Y1826515D01*
X67135D01*
G01X47717Y1857692D02*
X47467Y1857817D01*
X47175Y1857900D01*
X46842D01*
X46467Y1857775D01*
X46175Y1857567D01*
X45967Y1857317D01*
X45800Y1856900D01*
X45758Y1856525D01*
X45842Y1856150D01*
X45967Y1855900D01*
X46217Y1855650D01*
X46508Y1855483D01*
X46800Y1855400D01*
X47092D01*
X47383Y1855483D01*
X47633Y1855608D01*
X47842Y1855775D01*
G01X49192Y1855692D02*
X49483Y1855483D01*
X49817Y1855400D01*
X50150Y1855483D01*
X50442Y1855733D01*
X50650Y1856108D01*
X50733Y1856483D01*
Y1856942D01*
X50650Y1857317D01*
X50442Y1857650D01*
X50192Y1857817D01*
X49900Y1857900D01*
X49567Y1857817D01*
X49317Y1857650D01*
X49150Y1857400D01*
X49067Y1857067D01*
X49150Y1856775D01*
X49358Y1856483D01*
X49608Y1856317D01*
X49900Y1856275D01*
X50233Y1856358D01*
X50483Y1856567D01*
X50733Y1856942D01*
G01X52083Y1855775D02*
X52333Y1855567D01*
X52625Y1855442D01*
X53000Y1855400D01*
X53375Y1855483D01*
X53667Y1855650D01*
X53875Y1855942D01*
X53917Y1856275D01*
X53833Y1856608D01*
X53625Y1856817D01*
X53333Y1856983D01*
X53042Y1857025D01*
X52750Y1856983D01*
X52375Y1856817D01*
X52500Y1857900D01*
X53625D01*
G01X55308Y1857483D02*
X55558Y1857733D01*
X55850Y1857858D01*
X56183Y1857900D01*
X56600Y1857817D01*
X56892Y1857608D01*
X56975Y1857358D01*
X56933Y1857108D01*
X56767Y1856900D01*
X55933Y1856483D01*
X55558Y1856192D01*
X55308Y1855775D01*
X55225Y1855400D01*
X56975D01*
G01X59200D02*
X59492Y1855442D01*
X59825Y1855567D01*
X60033Y1855775D01*
X60117Y1856067D01*
X60033Y1856358D01*
X59783Y1856608D01*
X59408Y1856733D01*
X58992D01*
X58742Y1856817D01*
X58533Y1857025D01*
X58450Y1857317D01*
X58575Y1857608D01*
X58867Y1857817D01*
X59200Y1857900D01*
X59533Y1857817D01*
X59825Y1857608D01*
X59950Y1857317D01*
X59867Y1857025D01*
X59658Y1856817D01*
X59408Y1856733D01*
X58992D01*
X58617Y1856608D01*
X58367Y1856358D01*
X58283Y1856067D01*
X58367Y1855775D01*
X58575Y1855567D01*
X58908Y1855442D01*
X59200Y1855400D01*
G01X40617Y1812800D02*
Y1815300D01*
X41617D01*
X41950Y1815175D01*
X42200Y1814883D01*
X42283Y1814550D01*
X42200Y1814217D01*
X41992Y1813967D01*
X41617Y1813842D01*
X40617D01*
G01X45467Y1815092D02*
X45217Y1815217D01*
X44925Y1815300D01*
X44592D01*
X44217Y1815175D01*
X43925Y1814967D01*
X43717Y1814717D01*
X43550Y1814300D01*
X43508Y1813925D01*
X43592Y1813550D01*
X43717Y1813300D01*
X43967Y1813050D01*
X44258Y1812883D01*
X44550Y1812800D01*
X44842D01*
X45133Y1812883D01*
X45383Y1813008D01*
X45592Y1813175D01*
G01X47650Y1812800D02*
Y1815300D01*
X47150Y1814800D01*
G01Y1812800D02*
X48150D01*
G01X50750D02*
Y1815300D01*
X50250Y1814800D01*
G01Y1812800D02*
X51250D01*
G01X53058Y1813842D02*
X53350Y1814133D01*
X53600Y1814300D01*
X53933Y1814383D01*
X54225Y1814300D01*
X54433Y1814133D01*
X54600Y1813883D01*
X54642Y1813592D01*
X54600Y1813342D01*
X54433Y1813092D01*
X54183Y1812883D01*
X53892Y1812800D01*
X53558Y1812883D01*
X53267Y1813133D01*
X53100Y1813508D01*
X53058Y1813925D01*
X53142Y1814467D01*
X53267Y1814758D01*
X53475Y1815050D01*
X53767Y1815258D01*
X54058Y1815300D01*
X54350Y1815217D01*
X54558Y1815008D01*
G01X56033Y1813175D02*
X56283Y1812967D01*
X56575Y1812842D01*
X56950Y1812800D01*
X57325Y1812883D01*
X57617Y1813050D01*
X57825Y1813342D01*
X57867Y1813675D01*
X57783Y1814008D01*
X57575Y1814217D01*
X57283Y1814383D01*
X56992Y1814425D01*
X56700Y1814383D01*
X56325Y1814217D01*
X56450Y1815300D01*
X57575D01*
G01X40617Y1808800D02*
Y1811300D01*
X41617D01*
X41950Y1811175D01*
X42200Y1810883D01*
X42283Y1810550D01*
X42200Y1810217D01*
X41992Y1809967D01*
X41617Y1809842D01*
X40617D01*
G01X45467Y1811092D02*
X45217Y1811217D01*
X44925Y1811300D01*
X44592D01*
X44217Y1811175D01*
X43925Y1810967D01*
X43717Y1810717D01*
X43550Y1810300D01*
X43508Y1809925D01*
X43592Y1809550D01*
X43717Y1809300D01*
X43967Y1809050D01*
X44258Y1808883D01*
X44550Y1808800D01*
X44842D01*
X45133Y1808883D01*
X45383Y1809008D01*
X45592Y1809175D01*
G01X47650Y1808800D02*
Y1811300D01*
X47150Y1810800D01*
G01Y1808800D02*
X48150D01*
G01X50750D02*
Y1811300D01*
X50250Y1810800D01*
G01Y1808800D02*
X51250D01*
G01X53058Y1809842D02*
X53350Y1810133D01*
X53600Y1810300D01*
X53933Y1810383D01*
X54225Y1810300D01*
X54433Y1810133D01*
X54600Y1809883D01*
X54642Y1809592D01*
X54600Y1809342D01*
X54433Y1809092D01*
X54183Y1808883D01*
X53892Y1808800D01*
X53558Y1808883D01*
X53267Y1809133D01*
X53100Y1809508D01*
X53058Y1809925D01*
X53142Y1810467D01*
X53267Y1810758D01*
X53475Y1811050D01*
X53767Y1811258D01*
X54058Y1811300D01*
X54350Y1811217D01*
X54558Y1811008D01*
G01X56242Y1809092D02*
X56533Y1808883D01*
X56867Y1808800D01*
X57200Y1808883D01*
X57492Y1809133D01*
X57700Y1809508D01*
X57783Y1809883D01*
Y1810342D01*
X57700Y1810717D01*
X57492Y1811050D01*
X57242Y1811217D01*
X56950Y1811300D01*
X56617Y1811217D01*
X56367Y1811050D01*
X56200Y1810800D01*
X56117Y1810467D01*
X56200Y1810175D01*
X56408Y1809883D01*
X56658Y1809717D01*
X56950Y1809675D01*
X57283Y1809758D01*
X57533Y1809967D01*
X57783Y1810342D01*
G01X40617Y1820800D02*
Y1823300D01*
X41617D01*
X41950Y1823175D01*
X42200Y1822883D01*
X42283Y1822550D01*
X42200Y1822217D01*
X41992Y1821967D01*
X41617Y1821842D01*
X40617D01*
G01X45467Y1823092D02*
X45217Y1823217D01*
X44925Y1823300D01*
X44592D01*
X44217Y1823175D01*
X43925Y1822967D01*
X43717Y1822717D01*
X43550Y1822300D01*
X43508Y1821925D01*
X43592Y1821550D01*
X43717Y1821300D01*
X43967Y1821050D01*
X44258Y1820883D01*
X44550Y1820800D01*
X44842D01*
X45133Y1820883D01*
X45383Y1821008D01*
X45592Y1821175D01*
G01X47650Y1820800D02*
Y1823300D01*
X47150Y1822800D01*
G01Y1820800D02*
X48150D01*
G01X50750D02*
Y1823300D01*
X50250Y1822800D01*
G01Y1820800D02*
X51250D01*
G01X53058Y1821842D02*
X53350Y1822133D01*
X53600Y1822300D01*
X53933Y1822383D01*
X54225Y1822300D01*
X54433Y1822133D01*
X54600Y1821883D01*
X54642Y1821592D01*
X54600Y1821342D01*
X54433Y1821092D01*
X54183Y1820883D01*
X53892Y1820800D01*
X53558Y1820883D01*
X53267Y1821133D01*
X53100Y1821508D01*
X53058Y1821925D01*
X53142Y1822467D01*
X53267Y1822758D01*
X53475Y1823050D01*
X53767Y1823258D01*
X54058Y1823300D01*
X54350Y1823217D01*
X54558Y1823008D01*
G01X56033Y1821300D02*
X56283Y1821008D01*
X56617Y1820842D01*
X56992Y1820800D01*
X57325Y1820842D01*
X57658Y1821050D01*
X57867Y1821300D01*
X57908Y1821550D01*
X57825Y1821842D01*
X57533Y1822050D01*
X57242Y1822133D01*
X56867D01*
G01X57242D02*
X57492Y1822258D01*
X57700Y1822467D01*
X57783Y1822717D01*
X57700Y1822967D01*
X57492Y1823175D01*
X57117Y1823300D01*
X56742Y1823258D01*
X56367Y1823092D01*
G01X40617Y1816800D02*
Y1819300D01*
X41617D01*
X41950Y1819175D01*
X42200Y1818883D01*
X42283Y1818550D01*
X42200Y1818217D01*
X41992Y1817967D01*
X41617Y1817842D01*
X40617D01*
G01X45467Y1819092D02*
X45217Y1819217D01*
X44925Y1819300D01*
X44592D01*
X44217Y1819175D01*
X43925Y1818967D01*
X43717Y1818717D01*
X43550Y1818300D01*
X43508Y1817925D01*
X43592Y1817550D01*
X43717Y1817300D01*
X43967Y1817050D01*
X44258Y1816883D01*
X44550Y1816800D01*
X44842D01*
X45133Y1816883D01*
X45383Y1817008D01*
X45592Y1817175D01*
G01X47650Y1816800D02*
Y1819300D01*
X47150Y1818800D01*
G01Y1816800D02*
X48150D01*
G01X50750D02*
Y1819300D01*
X50250Y1818800D01*
G01Y1816800D02*
X51250D01*
G01X53058Y1817842D02*
X53350Y1818133D01*
X53600Y1818300D01*
X53933Y1818383D01*
X54225Y1818300D01*
X54433Y1818133D01*
X54600Y1817883D01*
X54642Y1817592D01*
X54600Y1817342D01*
X54433Y1817092D01*
X54183Y1816883D01*
X53892Y1816800D01*
X53558Y1816883D01*
X53267Y1817133D01*
X53100Y1817508D01*
X53058Y1817925D01*
X53142Y1818467D01*
X53267Y1818758D01*
X53475Y1819050D01*
X53767Y1819258D01*
X54058Y1819300D01*
X54350Y1819217D01*
X54558Y1819008D01*
G01X57450Y1816800D02*
Y1819300D01*
X55908Y1817508D01*
X57992D01*
G01X94800Y1863900D02*
Y1849900D01*
G01X107800Y1863900D02*
X94800D01*
G01X107800Y1849900D02*
Y1863900D01*
G01X94800Y1849900D02*
X107800D01*
G01X66600Y1870400D02*
Y1856400D01*
G01X79600D02*
Y1870400D01*
G01X66600Y1856400D02*
X79600D01*
G01X55500Y1846800D02*
X55458Y1846467D01*
X55292Y1846175D01*
X55042Y1845925D01*
X54750Y1845758D01*
X54417Y1845675D01*
X54083D01*
X53750Y1845758D01*
X53458Y1845925D01*
X53208Y1846175D01*
X53042Y1846467D01*
X53000Y1846800D01*
X53042Y1847133D01*
X53208Y1847425D01*
X53458Y1847675D01*
X53750Y1847842D01*
X54083Y1847925D01*
X54417D01*
X54750Y1847842D01*
X55042Y1847675D01*
X55292Y1847425D01*
X55458Y1847133D01*
X55500Y1846800D01*
G01X54833Y1847133D02*
X55500Y1847633D01*
G01Y1849900D02*
X55458Y1850192D01*
X55333Y1850525D01*
X55125Y1850733D01*
X54833Y1850817D01*
X54542Y1850733D01*
X54292Y1850483D01*
X54167Y1850108D01*
Y1849692D01*
X54083Y1849442D01*
X53875Y1849233D01*
X53583Y1849150D01*
X53292Y1849275D01*
X53083Y1849567D01*
X53000Y1849900D01*
X53083Y1850233D01*
X53292Y1850525D01*
X53583Y1850650D01*
X53875Y1850567D01*
X54083Y1850358D01*
X54167Y1850108D01*
Y1849692D01*
X54292Y1849317D01*
X54542Y1849067D01*
X54833Y1848983D01*
X55125Y1849067D01*
X55333Y1849275D01*
X55458Y1849608D01*
X55500Y1849900D01*
G01X53000Y1853000D02*
X53083Y1852667D01*
X53292Y1852417D01*
X53542Y1852250D01*
X53875Y1852125D01*
X54250Y1852083D01*
X54625Y1852125D01*
X54958Y1852250D01*
X55208Y1852417D01*
X55417Y1852667D01*
X55500Y1853000D01*
X55417Y1853333D01*
X55208Y1853583D01*
X54958Y1853750D01*
X54625Y1853875D01*
X54250Y1853917D01*
X53875Y1853875D01*
X53542Y1853750D01*
X53292Y1853583D01*
X53083Y1853333D01*
X53000Y1853000D01*
G01X74100Y1841400D02*
Y1855400D01*
G01X61100Y1841400D02*
X74100D01*
G01X61100Y1855400D02*
Y1841400D01*
G01X74100Y1855400D02*
X61100D01*
G01X106017Y1828200D02*
Y1830700D01*
X107058D01*
X107392Y1830575D01*
X107600Y1830408D01*
X107683Y1830075D01*
X107600Y1829742D01*
X107350Y1829533D01*
X107058Y1829408D01*
X106017D01*
G01X107058D02*
X107683Y1828200D01*
G01X109950D02*
Y1830700D01*
X109450Y1830200D01*
G01Y1828200D02*
X110450D01*
G01X113050D02*
Y1830700D01*
X112550Y1830200D01*
G01Y1828200D02*
X113550D01*
G01X116067D02*
X116150Y1828742D01*
X116275Y1829200D01*
X116442Y1829617D01*
X116650Y1830075D01*
X116983Y1830700D01*
X115317D01*
G01X99200Y1828000D02*
Y1832000D01*
X91800D01*
G01X82900Y1869400D02*
Y1865400D01*
X90300D01*
G01X82400Y1842600D02*
Y1838600D01*
X89800D01*
G01X107300Y1837900D02*
Y1841900D01*
X99900D01*
G01X59167Y1837275D02*
X59375Y1837608D01*
X59500Y1837983D01*
Y1838317D01*
X59375Y1838650D01*
X59167Y1838900D01*
X58875Y1839025D01*
X58583Y1838942D01*
X58333Y1838733D01*
X58167Y1838358D01*
X58083Y1837858D01*
X57917Y1837567D01*
X57625Y1837442D01*
X57333Y1837525D01*
X57125Y1837733D01*
X57000Y1838025D01*
Y1838317D01*
X57083Y1838608D01*
X57292Y1838858D01*
G01X59500Y1840417D02*
X57000D01*
Y1841458D01*
X57125Y1841792D01*
X57292Y1842000D01*
X57625Y1842083D01*
X57958Y1842000D01*
X58167Y1841750D01*
X58292Y1841458D01*
Y1840417D01*
G01Y1841458D02*
X59500Y1842083D01*
G01Y1844350D02*
X57000D01*
X57500Y1843850D01*
G01X59500D02*
Y1844850D01*
G01Y1847450D02*
X57000D01*
X57500Y1846950D01*
G01X59500D02*
Y1847950D01*
G01Y1851050D02*
X57000D01*
X58792Y1849508D01*
Y1851592D01*
G01X59500Y1853650D02*
X57000D01*
X57500Y1853150D01*
G01X59500D02*
Y1854150D01*
G01X79100Y1851600D02*
X75100D01*
Y1844200D01*
G01X92400Y1841900D02*
Y1837900D01*
X99800D01*
G01X106017Y1820200D02*
Y1822700D01*
X107058D01*
X107392Y1822575D01*
X107600Y1822408D01*
X107683Y1822075D01*
X107600Y1821742D01*
X107350Y1821533D01*
X107058Y1821408D01*
X106017D01*
G01X107058D02*
X107683Y1820200D01*
G01X109242Y1820492D02*
X109533Y1820283D01*
X109867Y1820200D01*
X110200Y1820283D01*
X110492Y1820533D01*
X110700Y1820908D01*
X110783Y1821283D01*
Y1821742D01*
X110700Y1822117D01*
X110492Y1822450D01*
X110242Y1822617D01*
X109950Y1822700D01*
X109617Y1822617D01*
X109367Y1822450D01*
X109200Y1822200D01*
X109117Y1821867D01*
X109200Y1821575D01*
X109408Y1821283D01*
X109658Y1821117D01*
X109950Y1821075D01*
X110283Y1821158D01*
X110533Y1821367D01*
X110783Y1821742D01*
G01X112342Y1820492D02*
X112633Y1820283D01*
X112967Y1820200D01*
X113300Y1820283D01*
X113592Y1820533D01*
X113800Y1820908D01*
X113883Y1821283D01*
Y1821742D01*
X113800Y1822117D01*
X113592Y1822450D01*
X113342Y1822617D01*
X113050Y1822700D01*
X112717Y1822617D01*
X112467Y1822450D01*
X112300Y1822200D01*
X112217Y1821867D01*
X112300Y1821575D01*
X112508Y1821283D01*
X112758Y1821117D01*
X113050Y1821075D01*
X113383Y1821158D01*
X113633Y1821367D01*
X113883Y1821742D01*
G01X116150Y1822700D02*
X115817Y1822617D01*
X115567Y1822408D01*
X115400Y1822158D01*
X115275Y1821825D01*
X115233Y1821450D01*
X115275Y1821075D01*
X115400Y1820742D01*
X115567Y1820492D01*
X115817Y1820283D01*
X116150Y1820200D01*
X116483Y1820283D01*
X116733Y1820492D01*
X116900Y1820742D01*
X117025Y1821075D01*
X117067Y1821450D01*
X117025Y1821825D01*
X116900Y1822158D01*
X116733Y1822408D01*
X116483Y1822617D01*
X116150Y1822700D01*
G01X118458Y1822283D02*
X118708Y1822533D01*
X119000Y1822658D01*
X119333Y1822700D01*
X119750Y1822617D01*
X120042Y1822408D01*
X120125Y1822158D01*
X120083Y1821908D01*
X119917Y1821700D01*
X119083Y1821283D01*
X118708Y1820992D01*
X118458Y1820575D01*
X118375Y1820200D01*
X120125D01*
G01X99200Y1819500D02*
Y1823500D01*
X91800D01*
G01X109967Y1834667D02*
Y1837167D01*
X111008D01*
X111342Y1837042D01*
X111550Y1836875D01*
X111633Y1836542D01*
X111550Y1836209D01*
X111300Y1836000D01*
X111008Y1835875D01*
X109967D01*
G01X111008D02*
X111633Y1834667D01*
G01X113192Y1834959D02*
X113483Y1834750D01*
X113817Y1834667D01*
X114150Y1834750D01*
X114442Y1835000D01*
X114650Y1835375D01*
X114733Y1835750D01*
Y1836209D01*
X114650Y1836584D01*
X114442Y1836917D01*
X114192Y1837084D01*
X113900Y1837167D01*
X113567Y1837084D01*
X113317Y1836917D01*
X113150Y1836667D01*
X113067Y1836334D01*
X113150Y1836042D01*
X113358Y1835750D01*
X113608Y1835584D01*
X113900Y1835542D01*
X114233Y1835625D01*
X114483Y1835834D01*
X114733Y1836209D01*
G01X116292Y1834959D02*
X116583Y1834750D01*
X116917Y1834667D01*
X117250Y1834750D01*
X117542Y1835000D01*
X117750Y1835375D01*
X117833Y1835750D01*
Y1836209D01*
X117750Y1836584D01*
X117542Y1836917D01*
X117292Y1837084D01*
X117000Y1837167D01*
X116667Y1837084D01*
X116417Y1836917D01*
X116250Y1836667D01*
X116167Y1836334D01*
X116250Y1836042D01*
X116458Y1835750D01*
X116708Y1835584D01*
X117000Y1835542D01*
X117333Y1835625D01*
X117583Y1835834D01*
X117833Y1836209D01*
G01X119308Y1836750D02*
X119558Y1837000D01*
X119850Y1837125D01*
X120183Y1837167D01*
X120600Y1837084D01*
X120892Y1836875D01*
X120975Y1836625D01*
X120933Y1836375D01*
X120767Y1836167D01*
X119933Y1835750D01*
X119558Y1835459D01*
X119308Y1835042D01*
X119225Y1834667D01*
X120975D01*
G01X122408Y1836750D02*
X122658Y1837000D01*
X122950Y1837125D01*
X123283Y1837167D01*
X123700Y1837084D01*
X123992Y1836875D01*
X124075Y1836625D01*
X124033Y1836375D01*
X123867Y1836167D01*
X123033Y1835750D01*
X122658Y1835459D01*
X122408Y1835042D01*
X122325Y1834667D01*
X124075D01*
G01X82400Y1838300D02*
Y1834300D01*
X89800D01*
G01X45867Y1825867D02*
Y1828367D01*
X46908D01*
X47242Y1828242D01*
X47450Y1828075D01*
X47533Y1827742D01*
X47450Y1827409D01*
X47200Y1827200D01*
X46908Y1827075D01*
X45867D01*
G01X46908D02*
X47533Y1825867D01*
G01X49092Y1826159D02*
X49383Y1825950D01*
X49717Y1825867D01*
X50050Y1825950D01*
X50342Y1826200D01*
X50550Y1826575D01*
X50633Y1826950D01*
Y1827409D01*
X50550Y1827784D01*
X50342Y1828117D01*
X50092Y1828284D01*
X49800Y1828367D01*
X49467Y1828284D01*
X49217Y1828117D01*
X49050Y1827867D01*
X48967Y1827534D01*
X49050Y1827242D01*
X49258Y1826950D01*
X49508Y1826784D01*
X49800Y1826742D01*
X50133Y1826825D01*
X50383Y1827034D01*
X50633Y1827409D01*
G01X52192Y1826159D02*
X52483Y1825950D01*
X52817Y1825867D01*
X53150Y1825950D01*
X53442Y1826200D01*
X53650Y1826575D01*
X53733Y1826950D01*
Y1827409D01*
X53650Y1827784D01*
X53442Y1828117D01*
X53192Y1828284D01*
X52900Y1828367D01*
X52567Y1828284D01*
X52317Y1828117D01*
X52150Y1827867D01*
X52067Y1827534D01*
X52150Y1827242D01*
X52358Y1826950D01*
X52608Y1826784D01*
X52900Y1826742D01*
X53233Y1826825D01*
X53483Y1827034D01*
X53733Y1827409D01*
G01X56500Y1825867D02*
Y1828367D01*
X54958Y1826575D01*
X57042D01*
G01X59100Y1825867D02*
X59392Y1825909D01*
X59725Y1826034D01*
X59933Y1826242D01*
X60017Y1826534D01*
X59933Y1826825D01*
X59683Y1827075D01*
X59308Y1827200D01*
X58892D01*
X58642Y1827284D01*
X58433Y1827492D01*
X58350Y1827784D01*
X58475Y1828075D01*
X58767Y1828284D01*
X59100Y1828367D01*
X59433Y1828284D01*
X59725Y1828075D01*
X59850Y1827784D01*
X59767Y1827492D01*
X59558Y1827284D01*
X59308Y1827200D01*
X58892D01*
X58517Y1827075D01*
X58267Y1826825D01*
X58183Y1826534D01*
X58267Y1826242D01*
X58475Y1826034D01*
X58808Y1825909D01*
X59100Y1825867D01*
G01X73675Y1821331D02*
Y1825331D01*
X66275D01*
G01X48767Y1833667D02*
Y1836167D01*
X49808D01*
X50142Y1836042D01*
X50350Y1835875D01*
X50433Y1835542D01*
X50350Y1835209D01*
X50100Y1835000D01*
X49808Y1834875D01*
X48767D01*
G01X49808D02*
X50433Y1833667D01*
G01X51992Y1833959D02*
X52283Y1833750D01*
X52617Y1833667D01*
X52950Y1833750D01*
X53242Y1834000D01*
X53450Y1834375D01*
X53533Y1834750D01*
Y1835209D01*
X53450Y1835584D01*
X53242Y1835917D01*
X52992Y1836084D01*
X52700Y1836167D01*
X52367Y1836084D01*
X52117Y1835917D01*
X51950Y1835667D01*
X51867Y1835334D01*
X51950Y1835042D01*
X52158Y1834750D01*
X52408Y1834584D01*
X52700Y1834542D01*
X53033Y1834625D01*
X53283Y1834834D01*
X53533Y1835209D01*
G01X55092Y1833959D02*
X55383Y1833750D01*
X55717Y1833667D01*
X56050Y1833750D01*
X56342Y1834000D01*
X56550Y1834375D01*
X56633Y1834750D01*
Y1835209D01*
X56550Y1835584D01*
X56342Y1835917D01*
X56092Y1836084D01*
X55800Y1836167D01*
X55467Y1836084D01*
X55217Y1835917D01*
X55050Y1835667D01*
X54967Y1835334D01*
X55050Y1835042D01*
X55258Y1834750D01*
X55508Y1834584D01*
X55800Y1834542D01*
X56133Y1834625D01*
X56383Y1834834D01*
X56633Y1835209D01*
G01X59400Y1833667D02*
Y1836167D01*
X57858Y1834375D01*
X59942D01*
G01X61917Y1833667D02*
X62000Y1834209D01*
X62125Y1834667D01*
X62292Y1835084D01*
X62500Y1835542D01*
X62833Y1836167D01*
X61167D01*
G01X75510Y1835270D02*
Y1839270D01*
X68110D01*
G01X106017Y1824200D02*
Y1826700D01*
X107058D01*
X107392Y1826575D01*
X107600Y1826408D01*
X107683Y1826075D01*
X107600Y1825742D01*
X107350Y1825533D01*
X107058Y1825408D01*
X106017D01*
G01X107058D02*
X107683Y1824200D01*
G01X109950D02*
Y1826700D01*
X109450Y1826200D01*
G01Y1824200D02*
X110450D01*
G01X113050D02*
Y1826700D01*
X112550Y1826200D01*
G01Y1824200D02*
X113550D01*
G01X115233Y1824575D02*
X115483Y1824367D01*
X115775Y1824242D01*
X116150Y1824200D01*
X116525Y1824283D01*
X116817Y1824450D01*
X117025Y1824742D01*
X117067Y1825075D01*
X116983Y1825408D01*
X116775Y1825617D01*
X116483Y1825783D01*
X116192Y1825825D01*
X115900Y1825783D01*
X115525Y1825617D01*
X115650Y1826700D01*
X116775D01*
G01X99187Y1823915D02*
Y1827915D01*
X91787D01*
G01X109100Y1855833D02*
X110892D01*
X111267Y1856000D01*
X111517Y1856333D01*
X111600Y1856750D01*
X111517Y1857167D01*
X111267Y1857500D01*
X110892Y1857667D01*
X109100D01*
G01X109517Y1859058D02*
X109267Y1859308D01*
X109142Y1859600D01*
X109100Y1859933D01*
X109183Y1860350D01*
X109392Y1860642D01*
X109642Y1860725D01*
X109892Y1860683D01*
X110100Y1860517D01*
X110517Y1859683D01*
X110808Y1859308D01*
X111225Y1859058D01*
X111600Y1858975D01*
Y1860725D01*
G01X109100Y1862950D02*
X109183Y1862617D01*
X109392Y1862367D01*
X109642Y1862200D01*
X109975Y1862075D01*
X110350Y1862033D01*
X110725Y1862075D01*
X111058Y1862200D01*
X111308Y1862367D01*
X111517Y1862617D01*
X111600Y1862950D01*
X111517Y1863283D01*
X111308Y1863533D01*
X111058Y1863700D01*
X110725Y1863825D01*
X110350Y1863867D01*
X109975Y1863825D01*
X109642Y1863700D01*
X109392Y1863533D01*
X109183Y1863283D01*
X109100Y1862950D01*
G01X111600Y1865967D02*
X111058Y1866050D01*
X110600Y1866175D01*
X110183Y1866342D01*
X109725Y1866550D01*
X109100Y1866883D01*
Y1865217D01*
G01X93200Y1857100D02*
Y1843700D01*
G01X83200Y1857100D02*
X93200D01*
G01X83200Y1843700D02*
Y1857100D01*
G01X93200Y1843700D02*
X83200D01*
G01X45717Y1864300D02*
Y1866800D01*
X46717D01*
X47050Y1866675D01*
X47300Y1866383D01*
X47383Y1866050D01*
X47300Y1865717D01*
X47092Y1865467D01*
X46717Y1865342D01*
X45717D01*
G01X50567Y1866592D02*
X50317Y1866717D01*
X50025Y1866800D01*
X49692D01*
X49317Y1866675D01*
X49025Y1866467D01*
X48817Y1866217D01*
X48650Y1865800D01*
X48608Y1865425D01*
X48692Y1865050D01*
X48817Y1864800D01*
X49067Y1864550D01*
X49358Y1864383D01*
X49650Y1864300D01*
X49942D01*
X50233Y1864383D01*
X50483Y1864508D01*
X50692Y1864675D01*
G01X52750Y1864300D02*
Y1866800D01*
X52250Y1866300D01*
G01Y1864300D02*
X53250D01*
G01X55850D02*
Y1866800D01*
X55350Y1866300D01*
G01Y1864300D02*
X56350D01*
G01X58158Y1865342D02*
X58450Y1865633D01*
X58700Y1865800D01*
X59033Y1865883D01*
X59325Y1865800D01*
X59533Y1865633D01*
X59700Y1865383D01*
X59742Y1865092D01*
X59700Y1864842D01*
X59533Y1864592D01*
X59283Y1864383D01*
X58992Y1864300D01*
X58658Y1864383D01*
X58367Y1864633D01*
X58200Y1865008D01*
X58158Y1865425D01*
X58242Y1865967D01*
X58367Y1866258D01*
X58575Y1866550D01*
X58867Y1866758D01*
X59158Y1866800D01*
X59450Y1866717D01*
X59658Y1866508D01*
G01X61258Y1865342D02*
X61550Y1865633D01*
X61800Y1865800D01*
X62133Y1865883D01*
X62425Y1865800D01*
X62633Y1865633D01*
X62800Y1865383D01*
X62842Y1865092D01*
X62800Y1864842D01*
X62633Y1864592D01*
X62383Y1864383D01*
X62092Y1864300D01*
X61758Y1864383D01*
X61467Y1864633D01*
X61300Y1865008D01*
X61258Y1865425D01*
X61342Y1865967D01*
X61467Y1866258D01*
X61675Y1866550D01*
X61967Y1866758D01*
X62258Y1866800D01*
X62550Y1866717D01*
X62758Y1866508D01*
G01X45717Y1860300D02*
Y1862800D01*
X46717D01*
X47050Y1862675D01*
X47300Y1862383D01*
X47383Y1862050D01*
X47300Y1861717D01*
X47092Y1861467D01*
X46717Y1861342D01*
X45717D01*
G01X50567Y1862592D02*
X50317Y1862717D01*
X50025Y1862800D01*
X49692D01*
X49317Y1862675D01*
X49025Y1862467D01*
X48817Y1862217D01*
X48650Y1861800D01*
X48608Y1861425D01*
X48692Y1861050D01*
X48817Y1860800D01*
X49067Y1860550D01*
X49358Y1860383D01*
X49650Y1860300D01*
X49942D01*
X50233Y1860383D01*
X50483Y1860508D01*
X50692Y1860675D01*
G01X52750Y1860300D02*
Y1862800D01*
X52250Y1862300D01*
G01Y1860300D02*
X53250D01*
G01X55850D02*
Y1862800D01*
X55350Y1862300D01*
G01Y1860300D02*
X56350D01*
G01X58158Y1861342D02*
X58450Y1861633D01*
X58700Y1861800D01*
X59033Y1861883D01*
X59325Y1861800D01*
X59533Y1861633D01*
X59700Y1861383D01*
X59742Y1861092D01*
X59700Y1860842D01*
X59533Y1860592D01*
X59283Y1860383D01*
X58992Y1860300D01*
X58658Y1860383D01*
X58367Y1860633D01*
X58200Y1861008D01*
X58158Y1861425D01*
X58242Y1861967D01*
X58367Y1862258D01*
X58575Y1862550D01*
X58867Y1862758D01*
X59158Y1862800D01*
X59450Y1862717D01*
X59658Y1862508D01*
G01X62050Y1860300D02*
X62342Y1860342D01*
X62675Y1860467D01*
X62883Y1860675D01*
X62967Y1860967D01*
X62883Y1861258D01*
X62633Y1861508D01*
X62258Y1861633D01*
X61842D01*
X61592Y1861717D01*
X61383Y1861925D01*
X61300Y1862217D01*
X61425Y1862508D01*
X61717Y1862717D01*
X62050Y1862800D01*
X62383Y1862717D01*
X62675Y1862508D01*
X62800Y1862217D01*
X62717Y1861925D01*
X62508Y1861717D01*
X62258Y1861633D01*
X61842D01*
X61467Y1861508D01*
X61217Y1861258D01*
X61133Y1860967D01*
X61217Y1860675D01*
X61425Y1860467D01*
X61758Y1860342D01*
X62050Y1860300D01*
G01X71518Y1914707D02*
X71393Y1914457D01*
X71310Y1914165D01*
Y1913832D01*
X71435Y1913457D01*
X71643Y1913165D01*
X71893Y1912957D01*
X72310Y1912790D01*
X72685Y1912748D01*
X73060Y1912832D01*
X73310Y1912957D01*
X73560Y1913207D01*
X73727Y1913498D01*
X73810Y1913790D01*
Y1914082D01*
X73727Y1914373D01*
X73602Y1914623D01*
X73435Y1914832D01*
G01X73310Y1915973D02*
X73602Y1916223D01*
X73768Y1916557D01*
X73810Y1916932D01*
X73768Y1917265D01*
X73560Y1917598D01*
X73310Y1917807D01*
X73060Y1917848D01*
X72768Y1917765D01*
X72560Y1917473D01*
X72477Y1917182D01*
Y1916807D01*
G01Y1917182D02*
X72352Y1917432D01*
X72143Y1917640D01*
X71893Y1917723D01*
X71643Y1917640D01*
X71435Y1917432D01*
X71310Y1917057D01*
X71352Y1916682D01*
X71518Y1916307D01*
G01X73810Y1919990D02*
X73768Y1920282D01*
X73643Y1920615D01*
X73435Y1920823D01*
X73143Y1920907D01*
X72852Y1920823D01*
X72602Y1920573D01*
X72477Y1920198D01*
Y1919782D01*
X72393Y1919532D01*
X72185Y1919323D01*
X71893Y1919240D01*
X71602Y1919365D01*
X71393Y1919657D01*
X71310Y1919990D01*
X71393Y1920323D01*
X71602Y1920615D01*
X71893Y1920740D01*
X72185Y1920657D01*
X72393Y1920448D01*
X72477Y1920198D01*
Y1919782D01*
X72602Y1919407D01*
X72852Y1919157D01*
X73143Y1919073D01*
X73435Y1919157D01*
X73643Y1919365D01*
X73768Y1919698D01*
X73810Y1919990D01*
G01Y1923007D02*
X73268Y1923090D01*
X72810Y1923215D01*
X72393Y1923382D01*
X71935Y1923590D01*
X71310Y1923923D01*
Y1922257D01*
G01X70400Y1871800D02*
X70067Y1871842D01*
X69775Y1872008D01*
X69525Y1872258D01*
X69358Y1872550D01*
X69275Y1872883D01*
Y1873217D01*
X69358Y1873550D01*
X69525Y1873842D01*
X69775Y1874092D01*
X70067Y1874258D01*
X70400Y1874300D01*
X70733Y1874258D01*
X71025Y1874092D01*
X71275Y1873842D01*
X71442Y1873550D01*
X71525Y1873217D01*
Y1872883D01*
X71442Y1872550D01*
X71275Y1872258D01*
X71025Y1872008D01*
X70733Y1871842D01*
X70400Y1871800D01*
G01X70733Y1872467D02*
X71233Y1871800D01*
G01X73417D02*
X73500Y1872342D01*
X73625Y1872800D01*
X73792Y1873217D01*
X74000Y1873675D01*
X74333Y1874300D01*
X72667D01*
G01X75892Y1872092D02*
X76183Y1871883D01*
X76517Y1871800D01*
X76850Y1871883D01*
X77142Y1872133D01*
X77350Y1872508D01*
X77433Y1872883D01*
Y1873342D01*
X77350Y1873717D01*
X77142Y1874050D01*
X76892Y1874217D01*
X76600Y1874300D01*
X76267Y1874217D01*
X76017Y1874050D01*
X75850Y1873800D01*
X75767Y1873467D01*
X75850Y1873175D01*
X76058Y1872883D01*
X76308Y1872717D01*
X76600Y1872675D01*
X76933Y1872758D01*
X77183Y1872967D01*
X77433Y1873342D01*
G01X79600Y1870400D02*
X66600D01*
G01X62657Y1926360D02*
Y1928860D01*
X63698D01*
X64032Y1928735D01*
X64240Y1928568D01*
X64323Y1928235D01*
X64240Y1927902D01*
X63990Y1927693D01*
X63698Y1927568D01*
X62657D01*
G01X63698D02*
X64323Y1926360D01*
G01X66590D02*
Y1928860D01*
X66090Y1928360D01*
G01Y1926360D02*
X67090D01*
G01X70190D02*
Y1928860D01*
X68648Y1927068D01*
X70732D01*
G01X71873Y1926860D02*
X72123Y1926568D01*
X72457Y1926402D01*
X72832Y1926360D01*
X73165Y1926402D01*
X73498Y1926610D01*
X73707Y1926860D01*
X73748Y1927110D01*
X73665Y1927402D01*
X73373Y1927610D01*
X73082Y1927693D01*
X72707D01*
G01X73082D02*
X73332Y1927818D01*
X73540Y1928027D01*
X73623Y1928277D01*
X73540Y1928527D01*
X73332Y1928735D01*
X72957Y1928860D01*
X72582Y1928818D01*
X72207Y1928652D01*
G01X71200Y1938500D02*
Y1942500D01*
X63800D01*
G01X64519Y1913787D02*
X62019D01*
Y1914828D01*
X62144Y1915162D01*
X62311Y1915370D01*
X62644Y1915453D01*
X62977Y1915370D01*
X63186Y1915120D01*
X63311Y1914828D01*
Y1913787D01*
G01Y1914828D02*
X64519Y1915453D01*
G01X64144Y1916803D02*
X64352Y1917053D01*
X64477Y1917345D01*
X64519Y1917720D01*
X64436Y1918095D01*
X64269Y1918387D01*
X63977Y1918595D01*
X63644Y1918637D01*
X63311Y1918553D01*
X63102Y1918345D01*
X62936Y1918053D01*
X62894Y1917762D01*
X62936Y1917470D01*
X63102Y1917095D01*
X62019Y1917220D01*
Y1918345D01*
G01X64144Y1919903D02*
X64352Y1920153D01*
X64477Y1920445D01*
X64519Y1920820D01*
X64436Y1921195D01*
X64269Y1921487D01*
X63977Y1921695D01*
X63644Y1921737D01*
X63311Y1921653D01*
X63102Y1921445D01*
X62936Y1921153D01*
X62894Y1920862D01*
X62936Y1920570D01*
X63102Y1920195D01*
X62019Y1920320D01*
Y1921445D01*
G01X63477Y1923128D02*
X63186Y1923420D01*
X63019Y1923670D01*
X62936Y1924003D01*
X63019Y1924295D01*
X63186Y1924503D01*
X63436Y1924670D01*
X63727Y1924712D01*
X63977Y1924670D01*
X64227Y1924503D01*
X64436Y1924253D01*
X64519Y1923962D01*
X64436Y1923628D01*
X64186Y1923337D01*
X63811Y1923170D01*
X63394Y1923128D01*
X62852Y1923212D01*
X62561Y1923337D01*
X62269Y1923545D01*
X62061Y1923837D01*
X62019Y1924128D01*
X62102Y1924420D01*
X62311Y1924628D01*
G01X63000Y1938200D02*
X59000D01*
Y1930800D01*
G01X69019Y1913787D02*
X66519D01*
Y1914828D01*
X66644Y1915162D01*
X66811Y1915370D01*
X67144Y1915453D01*
X67477Y1915370D01*
X67686Y1915120D01*
X67811Y1914828D01*
Y1913787D01*
G01Y1914828D02*
X69019Y1915453D01*
G01X68644Y1916803D02*
X68852Y1917053D01*
X68977Y1917345D01*
X69019Y1917720D01*
X68936Y1918095D01*
X68769Y1918387D01*
X68477Y1918595D01*
X68144Y1918637D01*
X67811Y1918553D01*
X67602Y1918345D01*
X67436Y1918053D01*
X67394Y1917762D01*
X67436Y1917470D01*
X67602Y1917095D01*
X66519Y1917220D01*
Y1918345D01*
G01X69019Y1920737D02*
X68477Y1920820D01*
X68019Y1920945D01*
X67602Y1921112D01*
X67144Y1921320D01*
X66519Y1921653D01*
Y1919987D01*
G01X69019Y1923920D02*
X66519D01*
X67019Y1923420D01*
G01X69019D02*
Y1924420D01*
G01X63500Y1930800D02*
X67500D01*
Y1938200D01*
G01X57530Y1889367D02*
X55030D01*
Y1890408D01*
X55155Y1890742D01*
X55322Y1890950D01*
X55655Y1891033D01*
X55988Y1890950D01*
X56197Y1890700D01*
X56322Y1890408D01*
Y1889367D01*
G01Y1890408D02*
X57530Y1891033D01*
G01Y1893800D02*
X55030D01*
X56822Y1892258D01*
Y1894342D01*
G01X55030Y1896400D02*
X55113Y1896067D01*
X55322Y1895817D01*
X55572Y1895650D01*
X55905Y1895525D01*
X56280Y1895483D01*
X56655Y1895525D01*
X56988Y1895650D01*
X57238Y1895817D01*
X57447Y1896067D01*
X57530Y1896400D01*
X57447Y1896733D01*
X57238Y1896983D01*
X56988Y1897150D01*
X56655Y1897275D01*
X56280Y1897317D01*
X55905Y1897275D01*
X55572Y1897150D01*
X55322Y1896983D01*
X55113Y1896733D01*
X55030Y1896400D01*
G01X56488Y1898708D02*
X56197Y1899000D01*
X56030Y1899250D01*
X55947Y1899583D01*
X56030Y1899875D01*
X56197Y1900083D01*
X56447Y1900250D01*
X56738Y1900292D01*
X56988Y1900250D01*
X57238Y1900083D01*
X57447Y1899833D01*
X57530Y1899542D01*
X57447Y1899208D01*
X57197Y1898917D01*
X56822Y1898750D01*
X56405Y1898708D01*
X55863Y1898792D01*
X55572Y1898917D01*
X55280Y1899125D01*
X55072Y1899417D01*
X55030Y1899708D01*
X55113Y1900000D01*
X55322Y1900208D01*
G01X58000Y1886200D02*
X54000D01*
Y1878800D01*
G01X49530Y1889367D02*
X47030D01*
Y1890408D01*
X47155Y1890742D01*
X47322Y1890950D01*
X47655Y1891033D01*
X47988Y1890950D01*
X48197Y1890700D01*
X48322Y1890408D01*
Y1889367D01*
G01Y1890408D02*
X49530Y1891033D01*
G01X49238Y1892592D02*
X49447Y1892883D01*
X49530Y1893217D01*
X49447Y1893550D01*
X49197Y1893842D01*
X48822Y1894050D01*
X48447Y1894133D01*
X47988D01*
X47613Y1894050D01*
X47280Y1893842D01*
X47113Y1893592D01*
X47030Y1893300D01*
X47113Y1892967D01*
X47280Y1892717D01*
X47530Y1892550D01*
X47863Y1892467D01*
X48155Y1892550D01*
X48447Y1892758D01*
X48613Y1893008D01*
X48655Y1893300D01*
X48572Y1893633D01*
X48363Y1893883D01*
X47988Y1894133D01*
G01X47030Y1896400D02*
X47113Y1896067D01*
X47322Y1895817D01*
X47572Y1895650D01*
X47905Y1895525D01*
X48280Y1895483D01*
X48655Y1895525D01*
X48988Y1895650D01*
X49238Y1895817D01*
X49447Y1896067D01*
X49530Y1896400D01*
X49447Y1896733D01*
X49238Y1896983D01*
X48988Y1897150D01*
X48655Y1897275D01*
X48280Y1897317D01*
X47905Y1897275D01*
X47572Y1897150D01*
X47322Y1896983D01*
X47113Y1896733D01*
X47030Y1896400D01*
G01X49030Y1898583D02*
X49322Y1898833D01*
X49488Y1899167D01*
X49530Y1899542D01*
X49488Y1899875D01*
X49280Y1900208D01*
X49030Y1900417D01*
X48780Y1900458D01*
X48488Y1900375D01*
X48280Y1900083D01*
X48197Y1899792D01*
Y1899417D01*
G01Y1899792D02*
X48072Y1900042D01*
X47863Y1900250D01*
X47613Y1900333D01*
X47363Y1900250D01*
X47155Y1900042D01*
X47030Y1899667D01*
X47072Y1899292D01*
X47238Y1898917D01*
G01X48488Y1901808D02*
X48197Y1902100D01*
X48030Y1902350D01*
X47947Y1902683D01*
X48030Y1902975D01*
X48197Y1903183D01*
X48447Y1903350D01*
X48738Y1903392D01*
X48988Y1903350D01*
X49238Y1903183D01*
X49447Y1902933D01*
X49530Y1902642D01*
X49447Y1902308D01*
X49197Y1902017D01*
X48822Y1901850D01*
X48405Y1901808D01*
X47863Y1901892D01*
X47572Y1902017D01*
X47280Y1902225D01*
X47072Y1902517D01*
X47030Y1902808D01*
X47113Y1903100D01*
X47322Y1903308D01*
G01X46000Y1878800D02*
X50000D01*
Y1886200D01*
G01X82067Y1871400D02*
Y1873900D01*
X83108D01*
X83442Y1873775D01*
X83650Y1873608D01*
X83733Y1873275D01*
X83650Y1872942D01*
X83400Y1872733D01*
X83108Y1872608D01*
X82067D01*
G01X83108D02*
X83733Y1871400D01*
G01X85292Y1871692D02*
X85583Y1871483D01*
X85917Y1871400D01*
X86250Y1871483D01*
X86542Y1871733D01*
X86750Y1872108D01*
X86833Y1872483D01*
Y1872942D01*
X86750Y1873317D01*
X86542Y1873650D01*
X86292Y1873817D01*
X86000Y1873900D01*
X85667Y1873817D01*
X85417Y1873650D01*
X85250Y1873400D01*
X85167Y1873067D01*
X85250Y1872775D01*
X85458Y1872483D01*
X85708Y1872317D01*
X86000Y1872275D01*
X86333Y1872358D01*
X86583Y1872567D01*
X86833Y1872942D01*
G01X89100Y1871400D02*
X89392Y1871442D01*
X89725Y1871567D01*
X89933Y1871775D01*
X90017Y1872067D01*
X89933Y1872358D01*
X89683Y1872608D01*
X89308Y1872733D01*
X88892D01*
X88642Y1872817D01*
X88433Y1873025D01*
X88350Y1873317D01*
X88475Y1873608D01*
X88767Y1873817D01*
X89100Y1873900D01*
X89433Y1873817D01*
X89725Y1873608D01*
X89850Y1873317D01*
X89767Y1873025D01*
X89558Y1872817D01*
X89308Y1872733D01*
X88892D01*
X88517Y1872608D01*
X88267Y1872358D01*
X88183Y1872067D01*
X88267Y1871775D01*
X88475Y1871567D01*
X88808Y1871442D01*
X89100Y1871400D01*
G01X92700D02*
Y1873900D01*
X91158Y1872108D01*
X93242D01*
G01X95217Y1871400D02*
X95300Y1871942D01*
X95425Y1872400D01*
X95592Y1872817D01*
X95800Y1873275D01*
X96133Y1873900D01*
X94467D01*
G01X82983Y1929500D02*
Y1927708D01*
X83150Y1927333D01*
X83483Y1927083D01*
X83900Y1927000D01*
X84317Y1927083D01*
X84650Y1927333D01*
X84817Y1927708D01*
Y1929500D01*
G01X87000Y1927000D02*
Y1929500D01*
X86500Y1929000D01*
G01Y1927000D02*
X87500D01*
G01X90600D02*
Y1929500D01*
X89058Y1927708D01*
X91142D01*
G01X83900Y1952300D02*
Y1933100D01*
X95100D01*
Y1952300D01*
X83900D01*
G01X53530Y1889367D02*
X51030D01*
Y1890408D01*
X51155Y1890742D01*
X51322Y1890950D01*
X51655Y1891033D01*
X51988Y1890950D01*
X52197Y1890700D01*
X52322Y1890408D01*
Y1889367D01*
G01Y1890408D02*
X53530Y1891033D01*
G01Y1893800D02*
X51030D01*
X52822Y1892258D01*
Y1894342D01*
G01X53530Y1896400D02*
X51030D01*
X51530Y1895900D01*
G01X53530D02*
Y1896900D01*
G01Y1899500D02*
X51030D01*
X51530Y1899000D01*
G01X53530D02*
Y1900000D01*
G01X50000Y1878800D02*
X54000D01*
Y1886200D01*
G01X45717Y1868300D02*
Y1870800D01*
X46717D01*
X47050Y1870675D01*
X47300Y1870383D01*
X47383Y1870050D01*
X47300Y1869717D01*
X47092Y1869467D01*
X46717Y1869342D01*
X45717D01*
G01X50567Y1870592D02*
X50317Y1870717D01*
X50025Y1870800D01*
X49692D01*
X49317Y1870675D01*
X49025Y1870467D01*
X48817Y1870217D01*
X48650Y1869800D01*
X48608Y1869425D01*
X48692Y1869050D01*
X48817Y1868800D01*
X49067Y1868550D01*
X49358Y1868383D01*
X49650Y1868300D01*
X49942D01*
X50233Y1868383D01*
X50483Y1868508D01*
X50692Y1868675D01*
G01X52750Y1868300D02*
Y1870800D01*
X52250Y1870300D01*
G01Y1868300D02*
X53250D01*
G01X55850Y1870800D02*
X55517Y1870717D01*
X55267Y1870508D01*
X55100Y1870258D01*
X54975Y1869925D01*
X54933Y1869550D01*
X54975Y1869175D01*
X55100Y1868842D01*
X55267Y1868592D01*
X55517Y1868383D01*
X55850Y1868300D01*
X56183Y1868383D01*
X56433Y1868592D01*
X56600Y1868842D01*
X56725Y1869175D01*
X56767Y1869550D01*
X56725Y1869925D01*
X56600Y1870258D01*
X56433Y1870508D01*
X56183Y1870717D01*
X55850Y1870800D01*
G01X58242Y1868592D02*
X58533Y1868383D01*
X58867Y1868300D01*
X59200Y1868383D01*
X59492Y1868633D01*
X59700Y1869008D01*
X59783Y1869383D01*
Y1869842D01*
X59700Y1870217D01*
X59492Y1870550D01*
X59242Y1870717D01*
X58950Y1870800D01*
X58617Y1870717D01*
X58367Y1870550D01*
X58200Y1870300D01*
X58117Y1869967D01*
X58200Y1869675D01*
X58408Y1869383D01*
X58658Y1869217D01*
X58950Y1869175D01*
X59283Y1869258D01*
X59533Y1869467D01*
X59783Y1869842D01*
G01X61258Y1869342D02*
X61550Y1869633D01*
X61800Y1869800D01*
X62133Y1869883D01*
X62425Y1869800D01*
X62633Y1869633D01*
X62800Y1869383D01*
X62842Y1869092D01*
X62800Y1868842D01*
X62633Y1868592D01*
X62383Y1868383D01*
X62092Y1868300D01*
X61758Y1868383D01*
X61467Y1868633D01*
X61300Y1869008D01*
X61258Y1869425D01*
X61342Y1869967D01*
X61467Y1870258D01*
X61675Y1870550D01*
X61967Y1870758D01*
X62258Y1870800D01*
X62550Y1870717D01*
X62758Y1870508D01*
G01X45717Y1872300D02*
Y1874800D01*
X46717D01*
X47050Y1874675D01*
X47300Y1874383D01*
X47383Y1874050D01*
X47300Y1873717D01*
X47092Y1873467D01*
X46717Y1873342D01*
X45717D01*
G01X50567Y1874592D02*
X50317Y1874717D01*
X50025Y1874800D01*
X49692D01*
X49317Y1874675D01*
X49025Y1874467D01*
X48817Y1874217D01*
X48650Y1873800D01*
X48608Y1873425D01*
X48692Y1873050D01*
X48817Y1872800D01*
X49067Y1872550D01*
X49358Y1872383D01*
X49650Y1872300D01*
X49942D01*
X50233Y1872383D01*
X50483Y1872508D01*
X50692Y1872675D01*
G01X52750Y1872300D02*
Y1874800D01*
X52250Y1874300D01*
G01Y1872300D02*
X53250D01*
G01X55850D02*
Y1874800D01*
X55350Y1874300D01*
G01Y1872300D02*
X56350D01*
G01X58158Y1873342D02*
X58450Y1873633D01*
X58700Y1873800D01*
X59033Y1873883D01*
X59325Y1873800D01*
X59533Y1873633D01*
X59700Y1873383D01*
X59742Y1873092D01*
X59700Y1872842D01*
X59533Y1872592D01*
X59283Y1872383D01*
X58992Y1872300D01*
X58658Y1872383D01*
X58367Y1872633D01*
X58200Y1873008D01*
X58158Y1873425D01*
X58242Y1873967D01*
X58367Y1874258D01*
X58575Y1874550D01*
X58867Y1874758D01*
X59158Y1874800D01*
X59450Y1874717D01*
X59658Y1874508D01*
G01X61967Y1872300D02*
X62050Y1872842D01*
X62175Y1873300D01*
X62342Y1873717D01*
X62550Y1874175D01*
X62883Y1874800D01*
X61217D01*
G01X51000Y1935500D02*
Y1951600D01*
G01X58000Y1935500D02*
X51000D01*
G01X58000Y1951600D02*
Y1935500D01*
G01X50000Y1943400D02*
X49958Y1943067D01*
X49792Y1942775D01*
X49542Y1942525D01*
X49250Y1942358D01*
X48917Y1942275D01*
X48583D01*
X48250Y1942358D01*
X47958Y1942525D01*
X47708Y1942775D01*
X47542Y1943067D01*
X47500Y1943400D01*
X47542Y1943733D01*
X47708Y1944025D01*
X47958Y1944275D01*
X48250Y1944442D01*
X48583Y1944525D01*
X48917D01*
X49250Y1944442D01*
X49542Y1944275D01*
X49792Y1944025D01*
X49958Y1943733D01*
X50000Y1943400D01*
G01X49333Y1943733D02*
X50000Y1944233D01*
G01Y1946500D02*
X47500D01*
X48000Y1946000D01*
G01X50000D02*
Y1947000D01*
G01X49500Y1948683D02*
X49792Y1948933D01*
X49958Y1949267D01*
X50000Y1949642D01*
X49958Y1949975D01*
X49750Y1950308D01*
X49500Y1950517D01*
X49250Y1950558D01*
X48958Y1950475D01*
X48750Y1950183D01*
X48667Y1949892D01*
Y1949517D01*
G01Y1949892D02*
X48542Y1950142D01*
X48333Y1950350D01*
X48083Y1950433D01*
X47833Y1950350D01*
X47625Y1950142D01*
X47500Y1949767D01*
X47542Y1949392D01*
X47708Y1949017D01*
G01X72000Y1943500D02*
Y1957500D01*
G01X59000Y1943500D02*
X72000D01*
G01X59000Y1957500D02*
Y1943500D01*
G01X72000Y1957500D02*
X59000D01*
G01X69600Y1973800D02*
X69267Y1973842D01*
X68975Y1974008D01*
X68725Y1974258D01*
X68558Y1974550D01*
X68475Y1974883D01*
Y1975217D01*
X68558Y1975550D01*
X68725Y1975842D01*
X68975Y1976092D01*
X69267Y1976258D01*
X69600Y1976300D01*
X69933Y1976258D01*
X70225Y1976092D01*
X70475Y1975842D01*
X70642Y1975550D01*
X70725Y1975217D01*
Y1974883D01*
X70642Y1974550D01*
X70475Y1974258D01*
X70225Y1974008D01*
X69933Y1973842D01*
X69600Y1973800D01*
G01X69933Y1974467D02*
X70433Y1973800D01*
G01X71783Y1974175D02*
X72033Y1973967D01*
X72325Y1973842D01*
X72700Y1973800D01*
X73075Y1973883D01*
X73367Y1974050D01*
X73575Y1974342D01*
X73617Y1974675D01*
X73533Y1975008D01*
X73325Y1975217D01*
X73033Y1975383D01*
X72742Y1975425D01*
X72450Y1975383D01*
X72075Y1975217D01*
X72200Y1976300D01*
X73325D01*
G01X75800Y1973800D02*
Y1976300D01*
X75300Y1975800D01*
G01Y1973800D02*
X76300D01*
G01X77700Y1971700D02*
X63700D01*
G01X77700Y1958700D02*
Y1971700D01*
G01X63700Y1958700D02*
X77700D01*
G01X63700Y1971700D02*
Y1958700D01*
G01X44000Y1973900D02*
X43667Y1973942D01*
X43375Y1974108D01*
X43125Y1974358D01*
X42958Y1974650D01*
X42875Y1974983D01*
Y1975317D01*
X42958Y1975650D01*
X43125Y1975942D01*
X43375Y1976192D01*
X43667Y1976358D01*
X44000Y1976400D01*
X44333Y1976358D01*
X44625Y1976192D01*
X44875Y1975942D01*
X45042Y1975650D01*
X45125Y1975317D01*
Y1974983D01*
X45042Y1974650D01*
X44875Y1974358D01*
X44625Y1974108D01*
X44333Y1973942D01*
X44000Y1973900D01*
G01X44333Y1974567D02*
X44833Y1973900D01*
G01X46183Y1974275D02*
X46433Y1974067D01*
X46725Y1973942D01*
X47100Y1973900D01*
X47475Y1973983D01*
X47767Y1974150D01*
X47975Y1974442D01*
X48017Y1974775D01*
X47933Y1975108D01*
X47725Y1975317D01*
X47433Y1975483D01*
X47142Y1975525D01*
X46850Y1975483D01*
X46475Y1975317D01*
X46600Y1976400D01*
X47725D01*
G01X49408Y1975983D02*
X49658Y1976233D01*
X49950Y1976358D01*
X50283Y1976400D01*
X50700Y1976317D01*
X50992Y1976108D01*
X51075Y1975858D01*
X51033Y1975608D01*
X50867Y1975400D01*
X50033Y1974983D01*
X49658Y1974692D01*
X49408Y1974275D01*
X49325Y1973900D01*
X51075D01*
G01X58600Y1971800D02*
X44600D01*
G01X58600Y1958800D02*
Y1971800D01*
G01X44600Y1958800D02*
X58600D01*
G01X44600Y1971800D02*
Y1958800D01*
G01X43800Y1966000D02*
X39800D01*
Y1958600D01*
G01X52867Y1973900D02*
Y1976400D01*
X53908D01*
X54242Y1976275D01*
X54450Y1976108D01*
X54533Y1975775D01*
X54450Y1975442D01*
X54200Y1975233D01*
X53908Y1975108D01*
X52867D01*
G01X53908D02*
X54533Y1973900D01*
G01X56092Y1974192D02*
X56383Y1973983D01*
X56717Y1973900D01*
X57050Y1973983D01*
X57342Y1974233D01*
X57550Y1974608D01*
X57633Y1974983D01*
Y1975442D01*
X57550Y1975817D01*
X57342Y1976150D01*
X57092Y1976317D01*
X56800Y1976400D01*
X56467Y1976317D01*
X56217Y1976150D01*
X56050Y1975900D01*
X55967Y1975567D01*
X56050Y1975275D01*
X56258Y1974983D01*
X56508Y1974817D01*
X56800Y1974775D01*
X57133Y1974858D01*
X57383Y1975067D01*
X57633Y1975442D01*
G01X59900Y1973900D02*
X60192Y1973942D01*
X60525Y1974067D01*
X60733Y1974275D01*
X60817Y1974567D01*
X60733Y1974858D01*
X60483Y1975108D01*
X60108Y1975233D01*
X59692D01*
X59442Y1975317D01*
X59233Y1975525D01*
X59150Y1975817D01*
X59275Y1976108D01*
X59567Y1976317D01*
X59900Y1976400D01*
X60233Y1976317D01*
X60525Y1976108D01*
X60650Y1975817D01*
X60567Y1975525D01*
X60358Y1975317D01*
X60108Y1975233D01*
X59692D01*
X59317Y1975108D01*
X59067Y1974858D01*
X58983Y1974567D01*
X59067Y1974275D01*
X59275Y1974067D01*
X59608Y1973942D01*
X59900Y1973900D01*
G01X63000D02*
Y1976400D01*
X62500Y1975900D01*
G01Y1973900D02*
X63500D01*
G01X66600D02*
Y1976400D01*
X65058Y1974608D01*
X67142D01*
G01X59050Y1959850D02*
X63050D01*
Y1967250D01*
G01X105675Y1949933D02*
X106008Y1949725D01*
X106383Y1949600D01*
X106717D01*
X107050Y1949725D01*
X107300Y1949933D01*
X107425Y1950225D01*
X107342Y1950517D01*
X107133Y1950767D01*
X106758Y1950933D01*
X106258Y1951017D01*
X105967Y1951183D01*
X105842Y1951475D01*
X105925Y1951767D01*
X106133Y1951975D01*
X106425Y1952100D01*
X106717D01*
X107008Y1952017D01*
X107258Y1951808D01*
G01X108817Y1949600D02*
Y1952100D01*
X109858D01*
X110192Y1951975D01*
X110400Y1951808D01*
X110483Y1951475D01*
X110400Y1951142D01*
X110150Y1950933D01*
X109858Y1950808D01*
X108817D01*
G01X109858D02*
X110483Y1949600D01*
G01X112750D02*
Y1952100D01*
X112250Y1951600D01*
G01Y1949600D02*
X113250D01*
G01X115850D02*
Y1952100D01*
X115350Y1951600D01*
G01Y1949600D02*
X116350D01*
G01X118950Y1952100D02*
X118617Y1952017D01*
X118367Y1951808D01*
X118200Y1951558D01*
X118075Y1951225D01*
X118033Y1950850D01*
X118075Y1950475D01*
X118200Y1950142D01*
X118367Y1949892D01*
X118617Y1949683D01*
X118950Y1949600D01*
X119283Y1949683D01*
X119533Y1949892D01*
X119700Y1950142D01*
X119825Y1950475D01*
X119867Y1950850D01*
X119825Y1951225D01*
X119700Y1951558D01*
X119533Y1951808D01*
X119283Y1952017D01*
X118950Y1952100D01*
G01X122050Y1949600D02*
Y1952100D01*
X121550Y1951600D01*
G01Y1949600D02*
X122550D01*
G01X78467Y1973600D02*
Y1976100D01*
X79508D01*
X79842Y1975975D01*
X80050Y1975808D01*
X80133Y1975475D01*
X80050Y1975142D01*
X79800Y1974933D01*
X79508Y1974808D01*
X78467D01*
G01X79508D02*
X80133Y1973600D01*
G01X81692Y1973892D02*
X81983Y1973683D01*
X82317Y1973600D01*
X82650Y1973683D01*
X82942Y1973933D01*
X83150Y1974308D01*
X83233Y1974683D01*
Y1975142D01*
X83150Y1975517D01*
X82942Y1975850D01*
X82692Y1976017D01*
X82400Y1976100D01*
X82067Y1976017D01*
X81817Y1975850D01*
X81650Y1975600D01*
X81567Y1975267D01*
X81650Y1974975D01*
X81858Y1974683D01*
X82108Y1974517D01*
X82400Y1974475D01*
X82733Y1974558D01*
X82983Y1974767D01*
X83233Y1975142D01*
G01X85500Y1973600D02*
X85792Y1973642D01*
X86125Y1973767D01*
X86333Y1973975D01*
X86417Y1974267D01*
X86333Y1974558D01*
X86083Y1974808D01*
X85708Y1974933D01*
X85292D01*
X85042Y1975017D01*
X84833Y1975225D01*
X84750Y1975517D01*
X84875Y1975808D01*
X85167Y1976017D01*
X85500Y1976100D01*
X85833Y1976017D01*
X86125Y1975808D01*
X86250Y1975517D01*
X86167Y1975225D01*
X85958Y1975017D01*
X85708Y1974933D01*
X85292D01*
X84917Y1974808D01*
X84667Y1974558D01*
X84583Y1974267D01*
X84667Y1973975D01*
X84875Y1973767D01*
X85208Y1973642D01*
X85500Y1973600D01*
G01X88600D02*
Y1976100D01*
X88100Y1975600D01*
G01Y1973600D02*
X89100D01*
G01X90908Y1975683D02*
X91158Y1975933D01*
X91450Y1976058D01*
X91783Y1976100D01*
X92200Y1976017D01*
X92492Y1975808D01*
X92575Y1975558D01*
X92533Y1975308D01*
X92367Y1975100D01*
X91533Y1974683D01*
X91158Y1974392D01*
X90908Y1973975D01*
X90825Y1973600D01*
X92575D01*
G01X90700Y1970900D02*
Y1965700D01*
G01X83700Y1970900D02*
Y1963100D01*
G01X90700Y1970900D02*
X83700D01*
G01X90700Y1957500D02*
Y1966200D01*
G01X83700Y1957500D02*
X90700D01*
G01X83700Y1963900D02*
Y1957500D01*
G01X91500Y1952300D02*
X89500Y1950300D01*
X87500Y1952300D01*
G01X107167Y1980100D02*
Y1982600D01*
X108167D01*
X108500Y1982475D01*
X108750Y1982183D01*
X108833Y1981850D01*
X108750Y1981517D01*
X108542Y1981267D01*
X108167Y1981142D01*
X107167D01*
G01X112017Y1982392D02*
X111767Y1982517D01*
X111475Y1982600D01*
X111142D01*
X110767Y1982475D01*
X110475Y1982267D01*
X110267Y1982017D01*
X110100Y1981600D01*
X110058Y1981225D01*
X110142Y1980850D01*
X110267Y1980600D01*
X110517Y1980350D01*
X110808Y1980183D01*
X111100Y1980100D01*
X111392D01*
X111683Y1980183D01*
X111933Y1980308D01*
X112142Y1980475D01*
G01X114200Y1980100D02*
Y1982600D01*
X113700Y1982100D01*
G01Y1980100D02*
X114700D01*
G01X116508Y1982183D02*
X116758Y1982433D01*
X117050Y1982558D01*
X117383Y1982600D01*
X117800Y1982517D01*
X118092Y1982308D01*
X118175Y1982058D01*
X118133Y1981808D01*
X117967Y1981600D01*
X117133Y1981183D01*
X116758Y1980892D01*
X116508Y1980475D01*
X116425Y1980100D01*
X118175D01*
G01X120400Y1982600D02*
X120067Y1982517D01*
X119817Y1982308D01*
X119650Y1982058D01*
X119525Y1981725D01*
X119483Y1981350D01*
X119525Y1980975D01*
X119650Y1980642D01*
X119817Y1980392D01*
X120067Y1980183D01*
X120400Y1980100D01*
X120733Y1980183D01*
X120983Y1980392D01*
X121150Y1980642D01*
X121275Y1980975D01*
X121317Y1981350D01*
X121275Y1981725D01*
X121150Y1982058D01*
X120983Y1982308D01*
X120733Y1982517D01*
X120400Y1982600D01*
G01X122583Y1980475D02*
X122833Y1980267D01*
X123125Y1980142D01*
X123500Y1980100D01*
X123875Y1980183D01*
X124167Y1980350D01*
X124375Y1980642D01*
X124417Y1980975D01*
X124333Y1981308D01*
X124125Y1981517D01*
X123833Y1981683D01*
X123542Y1981725D01*
X123250Y1981683D01*
X122875Y1981517D01*
X123000Y1982600D01*
X124125D01*
G01X115050Y1972050D02*
Y1953350D01*
X104750D01*
Y1972050D01*
X115050D01*
G01X94067Y1976100D02*
Y1978600D01*
X95067D01*
X95400Y1978475D01*
X95650Y1978183D01*
X95733Y1977850D01*
X95650Y1977517D01*
X95442Y1977267D01*
X95067Y1977142D01*
X94067D01*
G01X98917Y1978392D02*
X98667Y1978517D01*
X98375Y1978600D01*
X98042D01*
X97667Y1978475D01*
X97375Y1978267D01*
X97167Y1978017D01*
X97000Y1977600D01*
X96958Y1977225D01*
X97042Y1976850D01*
X97167Y1976600D01*
X97417Y1976350D01*
X97708Y1976183D01*
X98000Y1976100D01*
X98292D01*
X98583Y1976183D01*
X98833Y1976308D01*
X99042Y1976475D01*
G01X101100Y1976100D02*
Y1978600D01*
X100600Y1978100D01*
G01Y1976100D02*
X101600D01*
G01X103408Y1978183D02*
X103658Y1978433D01*
X103950Y1978558D01*
X104283Y1978600D01*
X104700Y1978517D01*
X104992Y1978308D01*
X105075Y1978058D01*
X105033Y1977808D01*
X104867Y1977600D01*
X104033Y1977183D01*
X103658Y1976892D01*
X103408Y1976475D01*
X103325Y1976100D01*
X105075D01*
G01X107300Y1978600D02*
X106967Y1978517D01*
X106717Y1978308D01*
X106550Y1978058D01*
X106425Y1977725D01*
X106383Y1977350D01*
X106425Y1976975D01*
X106550Y1976642D01*
X106717Y1976392D01*
X106967Y1976183D01*
X107300Y1976100D01*
X107633Y1976183D01*
X107883Y1976392D01*
X108050Y1976642D01*
X108175Y1976975D01*
X108217Y1977350D01*
X108175Y1977725D01*
X108050Y1978058D01*
X107883Y1978308D01*
X107633Y1978517D01*
X107300Y1978600D01*
G01X109608Y1977142D02*
X109900Y1977433D01*
X110150Y1977600D01*
X110483Y1977683D01*
X110775Y1977600D01*
X110983Y1977433D01*
X111150Y1977183D01*
X111192Y1976892D01*
X111150Y1976642D01*
X110983Y1976392D01*
X110733Y1976183D01*
X110442Y1976100D01*
X110108Y1976183D01*
X109817Y1976433D01*
X109650Y1976808D01*
X109608Y1977225D01*
X109692Y1977767D01*
X109817Y1978058D01*
X110025Y1978350D01*
X110317Y1978558D01*
X110608Y1978600D01*
X110900Y1978517D01*
X111108Y1978308D01*
G01X102550Y1972050D02*
Y1953350D01*
X92250D01*
Y1972050D01*
X102550D01*
G01X45834Y1942983D02*
X43334D01*
Y1943817D01*
X43459Y1944150D01*
X43626Y1944400D01*
X43876Y1944608D01*
X44167Y1944775D01*
X44584Y1944817D01*
X45001Y1944775D01*
X45292Y1944608D01*
X45542Y1944400D01*
X45709Y1944150D01*
X45834Y1943817D01*
Y1942983D01*
G01X43751Y1946208D02*
X43501Y1946458D01*
X43376Y1946750D01*
X43334Y1947083D01*
X43417Y1947500D01*
X43626Y1947792D01*
X43876Y1947875D01*
X44126Y1947833D01*
X44334Y1947667D01*
X44751Y1946833D01*
X45042Y1946458D01*
X45459Y1946208D01*
X45834Y1946125D01*
Y1947875D01*
G01X45334Y1949183D02*
X45626Y1949433D01*
X45792Y1949767D01*
X45834Y1950142D01*
X45792Y1950475D01*
X45584Y1950808D01*
X45334Y1951017D01*
X45084Y1951058D01*
X44792Y1950975D01*
X44584Y1950683D01*
X44501Y1950392D01*
Y1950017D01*
G01Y1950392D02*
X44376Y1950642D01*
X44167Y1950850D01*
X43917Y1950933D01*
X43667Y1950850D01*
X43459Y1950642D01*
X43334Y1950267D01*
X43376Y1949892D01*
X43542Y1949517D01*
G01X51000Y1951600D02*
X58000D01*
G01X162000Y21400D02*
X161958Y21067D01*
X161792Y20775D01*
X161542Y20525D01*
X161250Y20358D01*
X160917Y20275D01*
X160583D01*
X160250Y20358D01*
X159958Y20525D01*
X159708Y20775D01*
X159542Y21067D01*
X159500Y21400D01*
X159542Y21733D01*
X159708Y22025D01*
X159958Y22275D01*
X160250Y22442D01*
X160583Y22525D01*
X160917D01*
X161250Y22442D01*
X161542Y22275D01*
X161792Y22025D01*
X161958Y21733D01*
X162000Y21400D01*
G01X161333Y21733D02*
X162000Y22233D01*
G01X161708Y23792D02*
X161917Y24083D01*
X162000Y24417D01*
X161917Y24750D01*
X161667Y25042D01*
X161292Y25250D01*
X160917Y25333D01*
X160458D01*
X160083Y25250D01*
X159750Y25042D01*
X159583Y24792D01*
X159500Y24500D01*
X159583Y24167D01*
X159750Y23917D01*
X160000Y23750D01*
X160333Y23667D01*
X160625Y23750D01*
X160917Y23958D01*
X161083Y24208D01*
X161125Y24500D01*
X161042Y24833D01*
X160833Y25083D01*
X160458Y25333D01*
G01X160958Y26808D02*
X160667Y27100D01*
X160500Y27350D01*
X160417Y27683D01*
X160500Y27975D01*
X160667Y28183D01*
X160917Y28350D01*
X161208Y28392D01*
X161458Y28350D01*
X161708Y28183D01*
X161917Y27933D01*
X162000Y27642D01*
X161917Y27308D01*
X161667Y27017D01*
X161292Y26850D01*
X160875Y26808D01*
X160333Y26892D01*
X160042Y27017D01*
X159750Y27225D01*
X159542Y27517D01*
X159500Y27808D01*
X159583Y28100D01*
X159792Y28308D01*
G01X164000Y21100D02*
X178000D01*
G01X164000Y34100D02*
Y21100D01*
G01X178000Y34100D02*
X164000D01*
G01X178000Y21100D02*
Y34100D01*
G01X183500Y21100D02*
X197500D01*
G01X183500Y34100D02*
Y21100D01*
G01X197500Y34100D02*
X183500D01*
G01X173967Y17000D02*
Y19500D01*
X175008D01*
X175342Y19375D01*
X175550Y19208D01*
X175633Y18875D01*
X175550Y18542D01*
X175300Y18333D01*
X175008Y18208D01*
X173967D01*
G01X175008D02*
X175633Y17000D01*
G01X177192Y17292D02*
X177483Y17083D01*
X177817Y17000D01*
X178150Y17083D01*
X178442Y17333D01*
X178650Y17708D01*
X178733Y18083D01*
Y18542D01*
X178650Y18917D01*
X178442Y19250D01*
X178192Y19417D01*
X177900Y19500D01*
X177567Y19417D01*
X177317Y19250D01*
X177150Y19000D01*
X177067Y18667D01*
X177150Y18375D01*
X177358Y18083D01*
X177608Y17917D01*
X177900Y17875D01*
X178233Y17958D01*
X178483Y18167D01*
X178733Y18542D01*
G01X181000Y17000D02*
X181292Y17042D01*
X181625Y17167D01*
X181833Y17375D01*
X181917Y17667D01*
X181833Y17958D01*
X181583Y18208D01*
X181208Y18333D01*
X180792D01*
X180542Y18417D01*
X180333Y18625D01*
X180250Y18917D01*
X180375Y19208D01*
X180667Y19417D01*
X181000Y19500D01*
X181333Y19417D01*
X181625Y19208D01*
X181750Y18917D01*
X181667Y18625D01*
X181458Y18417D01*
X181208Y18333D01*
X180792D01*
X180417Y18208D01*
X180167Y17958D01*
X180083Y17667D01*
X180167Y17375D01*
X180375Y17167D01*
X180708Y17042D01*
X181000Y17000D01*
G01X184017D02*
X184100Y17542D01*
X184225Y18000D01*
X184392Y18417D01*
X184600Y18875D01*
X184933Y19500D01*
X183267D01*
G01X186408Y19083D02*
X186658Y19333D01*
X186950Y19458D01*
X187283Y19500D01*
X187700Y19417D01*
X187992Y19208D01*
X188075Y18958D01*
X188033Y18708D01*
X187867Y18500D01*
X187033Y18083D01*
X186658Y17792D01*
X186408Y17375D01*
X186325Y17000D01*
X188075D01*
G01X182850Y33050D02*
X178850D01*
Y25650D01*
G01X127700Y53300D02*
X123700D01*
Y45900D01*
G01X119600D02*
X123600D01*
Y53300D01*
G01X169324Y36007D02*
Y38507D01*
X170365D01*
X170699Y38382D01*
X170907Y38215D01*
X170990Y37882D01*
X170907Y37549D01*
X170657Y37340D01*
X170365Y37215D01*
X169324D01*
G01X170365D02*
X170990Y36007D01*
G01X172549Y36299D02*
X172840Y36090D01*
X173174Y36007D01*
X173507Y36090D01*
X173799Y36340D01*
X174007Y36715D01*
X174090Y37090D01*
Y37549D01*
X174007Y37924D01*
X173799Y38257D01*
X173549Y38424D01*
X173257Y38507D01*
X172924Y38424D01*
X172674Y38257D01*
X172507Y38007D01*
X172424Y37674D01*
X172507Y37382D01*
X172715Y37090D01*
X172965Y36924D01*
X173257Y36882D01*
X173590Y36965D01*
X173840Y37174D01*
X174090Y37549D01*
G01X176357Y36007D02*
X176649Y36049D01*
X176982Y36174D01*
X177190Y36382D01*
X177274Y36674D01*
X177190Y36965D01*
X176940Y37215D01*
X176565Y37340D01*
X176149D01*
X175899Y37424D01*
X175690Y37632D01*
X175607Y37924D01*
X175732Y38215D01*
X176024Y38424D01*
X176357Y38507D01*
X176690Y38424D01*
X176982Y38215D01*
X177107Y37924D01*
X177024Y37632D01*
X176815Y37424D01*
X176565Y37340D01*
X176149D01*
X175774Y37215D01*
X175524Y36965D01*
X175440Y36674D01*
X175524Y36382D01*
X175732Y36174D01*
X176065Y36049D01*
X176357Y36007D01*
G01X179374D02*
X179457Y36549D01*
X179582Y37007D01*
X179749Y37424D01*
X179957Y37882D01*
X180290Y38507D01*
X178624D01*
G01X182557D02*
X182224Y38424D01*
X181974Y38215D01*
X181807Y37965D01*
X181682Y37632D01*
X181640Y37257D01*
X181682Y36882D01*
X181807Y36549D01*
X181974Y36299D01*
X182224Y36090D01*
X182557Y36007D01*
X182890Y36090D01*
X183140Y36299D01*
X183307Y36549D01*
X183432Y36882D01*
X183474Y37257D01*
X183432Y37632D01*
X183307Y37965D01*
X183140Y38215D01*
X182890Y38424D01*
X182557Y38507D01*
G01X149900Y40100D02*
X155100D01*
G01X149900Y33100D02*
X157700D01*
G01X149900Y40100D02*
Y33100D01*
G01X163300Y40100D02*
X154600D01*
G01X163300Y33100D02*
Y40100D01*
G01X156900Y33100D02*
X163300D01*
G01X173500Y40700D02*
X175500Y42700D01*
X177500Y40700D01*
G01X181100D02*
Y59900D01*
X169900D01*
Y40700D01*
X181100D01*
G01X111900Y20100D02*
Y46100D01*
G01X144750Y63150D02*
Y44450D01*
X134450D01*
Y63150D01*
X144750D01*
G01X157250D02*
Y44450D01*
X146950D01*
Y63150D01*
X157250D01*
G01X120725Y39667D02*
Y42167D01*
G01X122475D02*
Y39667D01*
G01Y40917D02*
X120725D01*
G01X124700Y39667D02*
Y42167D01*
X124200Y41667D01*
G01Y39667D02*
X125200D01*
G01X126883Y40167D02*
X127133Y39875D01*
X127467Y39709D01*
X127842Y39667D01*
X128175Y39709D01*
X128508Y39917D01*
X128717Y40167D01*
X128758Y40417D01*
X128675Y40709D01*
X128383Y40917D01*
X128092Y41000D01*
X127717D01*
G01X128092D02*
X128342Y41125D01*
X128550Y41334D01*
X128633Y41584D01*
X128550Y41834D01*
X128342Y42042D01*
X127967Y42167D01*
X127592Y42125D01*
X127217Y41959D01*
G01X175317Y122992D02*
X175067Y123117D01*
X174775Y123200D01*
X174442D01*
X174067Y123075D01*
X173775Y122867D01*
X173567Y122617D01*
X173400Y122200D01*
X173358Y121825D01*
X173442Y121450D01*
X173567Y121200D01*
X173817Y120950D01*
X174108Y120783D01*
X174400Y120700D01*
X174692D01*
X174983Y120783D01*
X175233Y120908D01*
X175442Y121075D01*
G01X176792Y120992D02*
X177083Y120783D01*
X177417Y120700D01*
X177750Y120783D01*
X178042Y121033D01*
X178250Y121408D01*
X178333Y121783D01*
Y122242D01*
X178250Y122617D01*
X178042Y122950D01*
X177792Y123117D01*
X177500Y123200D01*
X177167Y123117D01*
X176917Y122950D01*
X176750Y122700D01*
X176667Y122367D01*
X176750Y122075D01*
X176958Y121783D01*
X177208Y121617D01*
X177500Y121575D01*
X177833Y121658D01*
X178083Y121867D01*
X178333Y122242D01*
G01X179683Y121075D02*
X179933Y120867D01*
X180225Y120742D01*
X180600Y120700D01*
X180975Y120783D01*
X181267Y120950D01*
X181475Y121242D01*
X181517Y121575D01*
X181433Y121908D01*
X181225Y122117D01*
X180933Y122283D01*
X180642Y122325D01*
X180350Y122283D01*
X179975Y122117D01*
X180100Y123200D01*
X181225D01*
G01X182908Y122783D02*
X183158Y123033D01*
X183450Y123158D01*
X183783Y123200D01*
X184200Y123117D01*
X184492Y122908D01*
X184575Y122658D01*
X184533Y122408D01*
X184367Y122200D01*
X183533Y121783D01*
X183158Y121492D01*
X182908Y121075D01*
X182825Y120700D01*
X184575D01*
G01X186717D02*
X186800Y121242D01*
X186925Y121700D01*
X187092Y122117D01*
X187300Y122575D01*
X187633Y123200D01*
X185967D01*
G01X133000Y63117D02*
X130500D01*
Y64117D01*
X130625Y64450D01*
X130917Y64700D01*
X131250Y64783D01*
X131583Y64700D01*
X131833Y64492D01*
X131958Y64117D01*
Y63117D01*
G01X130708Y67967D02*
X130583Y67717D01*
X130500Y67425D01*
Y67092D01*
X130625Y66717D01*
X130833Y66425D01*
X131083Y66217D01*
X131500Y66050D01*
X131875Y66008D01*
X132250Y66092D01*
X132500Y66217D01*
X132750Y66467D01*
X132917Y66758D01*
X133000Y67050D01*
Y67342D01*
X132917Y67633D01*
X132792Y67883D01*
X132625Y68092D01*
G01X133000Y70150D02*
X130500D01*
X131000Y69650D01*
G01X133000D02*
Y70650D01*
G01X130917Y72458D02*
X130667Y72708D01*
X130542Y73000D01*
X130500Y73333D01*
X130583Y73750D01*
X130792Y74042D01*
X131042Y74125D01*
X131292Y74083D01*
X131500Y73917D01*
X131917Y73083D01*
X132208Y72708D01*
X132625Y72458D01*
X133000Y72375D01*
Y74125D01*
G01X132500Y75433D02*
X132792Y75683D01*
X132958Y76017D01*
X133000Y76392D01*
X132958Y76725D01*
X132750Y77058D01*
X132500Y77267D01*
X132250Y77308D01*
X131958Y77225D01*
X131750Y76933D01*
X131667Y76642D01*
Y76267D01*
G01Y76642D02*
X131542Y76892D01*
X131333Y77100D01*
X131083Y77183D01*
X130833Y77100D01*
X130625Y76892D01*
X130500Y76517D01*
X130542Y76142D01*
X130708Y75767D01*
G01X130917Y78658D02*
X130667Y78908D01*
X130542Y79200D01*
X130500Y79533D01*
X130583Y79950D01*
X130792Y80242D01*
X131042Y80325D01*
X131292Y80283D01*
X131500Y80117D01*
X131917Y79283D01*
X132208Y78908D01*
X132625Y78658D01*
X133000Y78575D01*
Y80325D01*
G01X112300Y63800D02*
X116300D01*
Y71200D01*
G01X117300Y63800D02*
X121300D01*
Y71200D01*
G01X146134Y113867D02*
X143634D01*
Y114908D01*
X143759Y115242D01*
X143926Y115450D01*
X144259Y115533D01*
X144592Y115450D01*
X144801Y115200D01*
X144926Y114908D01*
Y113867D01*
G01Y114908D02*
X146134Y115533D01*
G01X145842Y117092D02*
X146051Y117383D01*
X146134Y117717D01*
X146051Y118050D01*
X145801Y118342D01*
X145426Y118550D01*
X145051Y118633D01*
X144592D01*
X144217Y118550D01*
X143884Y118342D01*
X143717Y118092D01*
X143634Y117800D01*
X143717Y117467D01*
X143884Y117217D01*
X144134Y117050D01*
X144467Y116967D01*
X144759Y117050D01*
X145051Y117258D01*
X145217Y117508D01*
X145259Y117800D01*
X145176Y118133D01*
X144967Y118383D01*
X144592Y118633D01*
G01X146134Y120900D02*
X146092Y121192D01*
X145967Y121525D01*
X145759Y121733D01*
X145467Y121817D01*
X145176Y121733D01*
X144926Y121483D01*
X144801Y121108D01*
Y120692D01*
X144717Y120442D01*
X144509Y120233D01*
X144217Y120150D01*
X143926Y120275D01*
X143717Y120567D01*
X143634Y120900D01*
X143717Y121233D01*
X143926Y121525D01*
X144217Y121650D01*
X144509Y121567D01*
X144717Y121358D01*
X144801Y121108D01*
Y120692D01*
X144926Y120317D01*
X145176Y120067D01*
X145467Y119983D01*
X145759Y120067D01*
X145967Y120275D01*
X146092Y120608D01*
X146134Y120900D01*
G01Y124500D02*
X143634D01*
X145426Y122958D01*
Y125042D01*
G01X144051Y126308D02*
X143801Y126558D01*
X143676Y126850D01*
X143634Y127183D01*
X143717Y127600D01*
X143926Y127892D01*
X144176Y127975D01*
X144426Y127933D01*
X144634Y127767D01*
X145051Y126933D01*
X145342Y126558D01*
X145759Y126308D01*
X146134Y126225D01*
Y127975D01*
G01X128667Y63075D02*
X128875Y63408D01*
X129000Y63783D01*
Y64117D01*
X128875Y64450D01*
X128667Y64700D01*
X128375Y64825D01*
X128083Y64742D01*
X127833Y64533D01*
X127667Y64158D01*
X127583Y63658D01*
X127417Y63367D01*
X127125Y63242D01*
X126833Y63325D01*
X126625Y63533D01*
X126500Y63825D01*
Y64117D01*
X126583Y64408D01*
X126792Y64658D01*
G01X129000Y66217D02*
X126500D01*
Y67258D01*
X126625Y67592D01*
X126792Y67800D01*
X127125Y67883D01*
X127458Y67800D01*
X127667Y67550D01*
X127792Y67258D01*
Y66217D01*
G01Y67258D02*
X129000Y67883D01*
G01Y70150D02*
X126500D01*
X127000Y69650D01*
G01X129000D02*
Y70650D01*
G01Y73250D02*
X126500D01*
X127000Y72750D01*
G01X129000D02*
Y73750D01*
G01Y76350D02*
X126500D01*
X127000Y75850D01*
G01X129000D02*
Y76850D01*
G01X128708Y78742D02*
X128917Y79033D01*
X129000Y79367D01*
X128917Y79700D01*
X128667Y79992D01*
X128292Y80200D01*
X127917Y80283D01*
X127458D01*
X127083Y80200D01*
X126750Y79992D01*
X126583Y79742D01*
X126500Y79450D01*
X126583Y79117D01*
X126750Y78867D01*
X127000Y78700D01*
X127333Y78617D01*
X127625Y78700D01*
X127917Y78908D01*
X128083Y79158D01*
X128125Y79450D01*
X128042Y79783D01*
X127833Y80033D01*
X127458Y80283D01*
G01X124667Y63075D02*
X124875Y63408D01*
X125000Y63783D01*
Y64117D01*
X124875Y64450D01*
X124667Y64700D01*
X124375Y64825D01*
X124083Y64742D01*
X123833Y64533D01*
X123667Y64158D01*
X123583Y63658D01*
X123417Y63367D01*
X123125Y63242D01*
X122833Y63325D01*
X122625Y63533D01*
X122500Y63825D01*
Y64117D01*
X122583Y64408D01*
X122792Y64658D01*
G01X125000Y66217D02*
X122500D01*
Y67258D01*
X122625Y67592D01*
X122792Y67800D01*
X123125Y67883D01*
X123458Y67800D01*
X123667Y67550D01*
X123792Y67258D01*
Y66217D01*
G01Y67258D02*
X125000Y67883D01*
G01Y70150D02*
X122500D01*
X123000Y69650D01*
G01X125000D02*
Y70650D01*
G01Y73250D02*
X122500D01*
X123000Y72750D01*
G01X125000D02*
Y73750D01*
G01X122917Y75558D02*
X122667Y75808D01*
X122542Y76100D01*
X122500Y76433D01*
X122583Y76850D01*
X122792Y77142D01*
X123042Y77225D01*
X123292Y77183D01*
X123500Y77017D01*
X123917Y76183D01*
X124208Y75808D01*
X124625Y75558D01*
X125000Y75475D01*
Y77225D01*
G01X122500Y79450D02*
X122583Y79117D01*
X122792Y78867D01*
X123042Y78700D01*
X123375Y78575D01*
X123750Y78533D01*
X124125Y78575D01*
X124458Y78700D01*
X124708Y78867D01*
X124917Y79117D01*
X125000Y79450D01*
X124917Y79783D01*
X124708Y80033D01*
X124458Y80200D01*
X124125Y80325D01*
X123750Y80367D01*
X123375Y80325D01*
X123042Y80200D01*
X122792Y80033D01*
X122583Y79783D01*
X122500Y79450D01*
G01X150633Y114367D02*
X148133D01*
Y115408D01*
X148258Y115742D01*
X148425Y115950D01*
X148758Y116033D01*
X149091Y115950D01*
X149300Y115700D01*
X149425Y115408D01*
Y114367D01*
G01Y115408D02*
X150633Y116033D01*
G01X150341Y117592D02*
X150550Y117883D01*
X150633Y118217D01*
X150550Y118550D01*
X150300Y118842D01*
X149925Y119050D01*
X149550Y119133D01*
X149091D01*
X148716Y119050D01*
X148383Y118842D01*
X148216Y118592D01*
X148133Y118300D01*
X148216Y117967D01*
X148383Y117717D01*
X148633Y117550D01*
X148966Y117467D01*
X149258Y117550D01*
X149550Y117758D01*
X149716Y118008D01*
X149758Y118300D01*
X149675Y118633D01*
X149466Y118883D01*
X149091Y119133D01*
G01X150341Y120692D02*
X150550Y120983D01*
X150633Y121317D01*
X150550Y121650D01*
X150300Y121942D01*
X149925Y122150D01*
X149550Y122233D01*
X149091D01*
X148716Y122150D01*
X148383Y121942D01*
X148216Y121692D01*
X148133Y121400D01*
X148216Y121067D01*
X148383Y120817D01*
X148633Y120650D01*
X148966Y120567D01*
X149258Y120650D01*
X149550Y120858D01*
X149716Y121108D01*
X149758Y121400D01*
X149675Y121733D01*
X149466Y121983D01*
X149091Y122233D01*
G01X148550Y123708D02*
X148300Y123958D01*
X148175Y124250D01*
X148133Y124583D01*
X148216Y125000D01*
X148425Y125292D01*
X148675Y125375D01*
X148925Y125333D01*
X149133Y125167D01*
X149550Y124333D01*
X149841Y123958D01*
X150258Y123708D01*
X150633Y123625D01*
Y125375D01*
G01Y127600D02*
X148133D01*
X148633Y127100D01*
G01X150633D02*
Y128100D01*
G01X173793Y66350D02*
Y64558D01*
X173960Y64183D01*
X174293Y63933D01*
X174710Y63850D01*
X175127Y63933D01*
X175460Y64183D01*
X175627Y64558D01*
Y66350D01*
G01X177018Y65933D02*
X177268Y66183D01*
X177560Y66308D01*
X177893Y66350D01*
X178310Y66267D01*
X178602Y66058D01*
X178685Y65808D01*
X178643Y65558D01*
X178477Y65350D01*
X177643Y64933D01*
X177268Y64642D01*
X177018Y64225D01*
X176935Y63850D01*
X178685D01*
G01X179993Y64350D02*
X180243Y64058D01*
X180577Y63892D01*
X180952Y63850D01*
X181285Y63892D01*
X181618Y64100D01*
X181827Y64350D01*
X181868Y64600D01*
X181785Y64892D01*
X181493Y65100D01*
X181202Y65183D01*
X180827D01*
G01X181202D02*
X181452Y65308D01*
X181660Y65517D01*
X181743Y65767D01*
X181660Y66017D01*
X181452Y66225D01*
X181077Y66350D01*
X180702Y66308D01*
X180327Y66142D01*
G01X154533Y123600D02*
Y121808D01*
X154700Y121433D01*
X155033Y121183D01*
X155450Y121100D01*
X155867Y121183D01*
X156200Y121433D01*
X156367Y121808D01*
Y123600D01*
G01X157758Y123183D02*
X158008Y123433D01*
X158300Y123558D01*
X158633Y123600D01*
X159050Y123517D01*
X159342Y123308D01*
X159425Y123058D01*
X159383Y122808D01*
X159217Y122600D01*
X158383Y122183D01*
X158008Y121892D01*
X157758Y121475D01*
X157675Y121100D01*
X159425D01*
G01X161650Y123600D02*
X161317Y123517D01*
X161067Y123308D01*
X160900Y123058D01*
X160775Y122725D01*
X160733Y122350D01*
X160775Y121975D01*
X160900Y121642D01*
X161067Y121392D01*
X161317Y121183D01*
X161650Y121100D01*
X161983Y121183D01*
X162233Y121392D01*
X162400Y121642D01*
X162525Y121975D01*
X162567Y122350D01*
X162525Y122725D01*
X162400Y123058D01*
X162233Y123308D01*
X161983Y123517D01*
X161650Y123600D01*
G01X163958Y122142D02*
X164250Y122433D01*
X164500Y122600D01*
X164833Y122683D01*
X165125Y122600D01*
X165333Y122433D01*
X165500Y122183D01*
X165542Y121892D01*
X165500Y121642D01*
X165333Y121392D01*
X165083Y121183D01*
X164792Y121100D01*
X164458Y121183D01*
X164167Y121433D01*
X164000Y121808D01*
X163958Y122225D01*
X164042Y122767D01*
X164167Y123058D01*
X164375Y123350D01*
X164667Y123558D01*
X164958Y123600D01*
X165250Y123517D01*
X165458Y123308D01*
G01X145100Y66317D02*
X142600D01*
Y67317D01*
X142725Y67650D01*
X143017Y67900D01*
X143350Y67983D01*
X143683Y67900D01*
X143933Y67692D01*
X144058Y67317D01*
Y66317D01*
G01X142808Y71167D02*
X142683Y70917D01*
X142600Y70625D01*
Y70292D01*
X142725Y69917D01*
X142933Y69625D01*
X143183Y69417D01*
X143600Y69250D01*
X143975Y69208D01*
X144350Y69292D01*
X144600Y69417D01*
X144850Y69667D01*
X145017Y69958D01*
X145100Y70250D01*
Y70542D01*
X145017Y70833D01*
X144892Y71083D01*
X144725Y71292D01*
G01X145100Y73350D02*
X142600D01*
X143100Y72850D01*
G01X145100D02*
Y73850D01*
G01X143017Y75658D02*
X142767Y75908D01*
X142642Y76200D01*
X142600Y76533D01*
X142683Y76950D01*
X142892Y77242D01*
X143142Y77325D01*
X143392Y77283D01*
X143600Y77117D01*
X144017Y76283D01*
X144308Y75908D01*
X144725Y75658D01*
X145100Y75575D01*
Y77325D01*
G01X144600Y78633D02*
X144892Y78883D01*
X145058Y79217D01*
X145100Y79592D01*
X145058Y79925D01*
X144850Y80258D01*
X144600Y80467D01*
X144350Y80508D01*
X144058Y80425D01*
X143850Y80133D01*
X143767Y79842D01*
Y79467D01*
G01Y79842D02*
X143642Y80092D01*
X143433Y80300D01*
X143183Y80383D01*
X142933Y80300D01*
X142725Y80092D01*
X142600Y79717D01*
X142642Y79342D01*
X142808Y78967D01*
G01X142600Y82650D02*
X142683Y82317D01*
X142892Y82067D01*
X143142Y81900D01*
X143475Y81775D01*
X143850Y81733D01*
X144225Y81775D01*
X144558Y81900D01*
X144808Y82067D01*
X145017Y82317D01*
X145100Y82650D01*
X145017Y82983D01*
X144808Y83233D01*
X144558Y83400D01*
X144225Y83525D01*
X143850Y83567D01*
X143475Y83525D01*
X143142Y83400D01*
X142892Y83233D01*
X142683Y82983D01*
X142600Y82650D01*
G01X149100Y66317D02*
X146600D01*
Y67317D01*
X146725Y67650D01*
X147017Y67900D01*
X147350Y67983D01*
X147683Y67900D01*
X147933Y67692D01*
X148058Y67317D01*
Y66317D01*
G01X146808Y71167D02*
X146683Y70917D01*
X146600Y70625D01*
Y70292D01*
X146725Y69917D01*
X146933Y69625D01*
X147183Y69417D01*
X147600Y69250D01*
X147975Y69208D01*
X148350Y69292D01*
X148600Y69417D01*
X148850Y69667D01*
X149017Y69958D01*
X149100Y70250D01*
Y70542D01*
X149017Y70833D01*
X148892Y71083D01*
X148725Y71292D01*
G01X149100Y73350D02*
X146600D01*
X147100Y72850D01*
G01X149100D02*
Y73850D01*
G01X147017Y75658D02*
X146767Y75908D01*
X146642Y76200D01*
X146600Y76533D01*
X146683Y76950D01*
X146892Y77242D01*
X147142Y77325D01*
X147392Y77283D01*
X147600Y77117D01*
X148017Y76283D01*
X148308Y75908D01*
X148725Y75658D01*
X149100Y75575D01*
Y77325D01*
G01X148600Y78633D02*
X148892Y78883D01*
X149058Y79217D01*
X149100Y79592D01*
X149058Y79925D01*
X148850Y80258D01*
X148600Y80467D01*
X148350Y80508D01*
X148058Y80425D01*
X147850Y80133D01*
X147767Y79842D01*
Y79467D01*
G01Y79842D02*
X147642Y80092D01*
X147433Y80300D01*
X147183Y80383D01*
X146933Y80300D01*
X146725Y80092D01*
X146600Y79717D01*
X146642Y79342D01*
X146808Y78967D01*
G01X149100Y82650D02*
X146600D01*
X147100Y82150D01*
G01X149100D02*
Y83150D01*
G01X182417Y171000D02*
Y173500D01*
X183417D01*
X183750Y173375D01*
X184000Y173083D01*
X184083Y172750D01*
X184000Y172417D01*
X183792Y172167D01*
X183417Y172042D01*
X182417D01*
G01X187183Y171000D02*
X185517D01*
Y173500D01*
X187183D01*
G01X186517Y172292D02*
X185517D01*
G01X189783Y172333D02*
X189950Y172458D01*
X190075Y172667D01*
X190158Y172958D01*
X190075Y173208D01*
X189908Y173375D01*
X189617Y173500D01*
X188492D01*
Y171000D01*
X189867D01*
X190158Y171167D01*
X190325Y171417D01*
X190408Y171708D01*
X190325Y172000D01*
X190075Y172250D01*
X189783Y172333D01*
X188492D01*
G01X194608Y171000D02*
X195650Y173500D01*
X196692Y171000D01*
G01X196317Y171875D02*
X194983D01*
G01X198750Y173500D02*
Y171000D01*
G01X197792Y173500D02*
X199708D01*
G01X201850D02*
Y171000D01*
G01X200892Y173500D02*
X202808D01*
G01X203992Y171000D02*
Y173500D01*
X205908Y171000D01*
Y173500D01*
G01X207342Y171292D02*
X207633Y171083D01*
X207967Y171000D01*
X208300Y171083D01*
X208592Y171333D01*
X208800Y171708D01*
X208883Y172083D01*
Y172542D01*
X208800Y172917D01*
X208592Y173250D01*
X208342Y173417D01*
X208050Y173500D01*
X207717Y173417D01*
X207467Y173250D01*
X207300Y173000D01*
X207217Y172667D01*
X207300Y172375D01*
X207508Y172083D01*
X207758Y171917D01*
X208050Y171875D01*
X208383Y171958D01*
X208633Y172167D01*
X208883Y172542D01*
G01X209308Y185817D02*
X180408D01*
Y172917D01*
X162108D01*
Y185817D01*
X148608D01*
Y347017D01*
X162108D01*
Y359917D01*
X180408D01*
Y347017D01*
X209308D01*
Y336667D01*
X202608D01*
Y196167D01*
X209308D01*
Y185817D01*
G01X174717Y169367D02*
Y166867D01*
X176383D01*
G01X179483D02*
X177817D01*
Y169367D01*
X179483D01*
G01X178817Y168159D02*
X177817D01*
G01X180833Y166867D02*
Y169367D01*
X181667D01*
X182000Y169242D01*
X182250Y169075D01*
X182458Y168825D01*
X182625Y168534D01*
X182667Y168117D01*
X182625Y167700D01*
X182458Y167409D01*
X182250Y167159D01*
X182000Y166992D01*
X181667Y166867D01*
X180833D01*
G01X184142Y167159D02*
X184433Y166950D01*
X184767Y166867D01*
X185100Y166950D01*
X185392Y167200D01*
X185600Y167575D01*
X185683Y167950D01*
Y168409D01*
X185600Y168784D01*
X185392Y169117D01*
X185142Y169284D01*
X184850Y169367D01*
X184517Y169284D01*
X184267Y169117D01*
X184100Y168867D01*
X184017Y168534D01*
X184100Y168242D01*
X184308Y167950D01*
X184558Y167784D01*
X184850Y167742D01*
X185183Y167825D01*
X185433Y168034D01*
X185683Y168409D01*
G01X165560Y158011D02*
Y165611D01*
X176960D01*
Y158011D01*
X165560D01*
G01X144400Y161667D02*
X144067Y161709D01*
X143775Y161875D01*
X143525Y162125D01*
X143358Y162417D01*
X143275Y162750D01*
Y163084D01*
X143358Y163417D01*
X143525Y163709D01*
X143775Y163959D01*
X144067Y164125D01*
X144400Y164167D01*
X144733Y164125D01*
X145025Y163959D01*
X145275Y163709D01*
X145442Y163417D01*
X145525Y163084D01*
Y162750D01*
X145442Y162417D01*
X145275Y162125D01*
X145025Y161875D01*
X144733Y161709D01*
X144400Y161667D01*
G01X144733Y162334D02*
X145233Y161667D01*
G01X147417D02*
X147500Y162209D01*
X147625Y162667D01*
X147792Y163084D01*
X148000Y163542D01*
X148333Y164167D01*
X146667D01*
G01X151100Y161667D02*
Y164167D01*
X149558Y162375D01*
X151642D01*
G01X157500Y145500D02*
Y159500D01*
G01X144500Y145500D02*
X157500D01*
G01X144500Y159500D02*
Y145500D01*
G01X157500Y159500D02*
X144500D01*
G01X131400Y141666D02*
X131067Y141708D01*
X130775Y141874D01*
X130525Y142124D01*
X130358Y142416D01*
X130275Y142749D01*
Y143083D01*
X130358Y143416D01*
X130525Y143708D01*
X130775Y143958D01*
X131067Y144124D01*
X131400Y144166D01*
X131733Y144124D01*
X132025Y143958D01*
X132275Y143708D01*
X132442Y143416D01*
X132525Y143083D01*
Y142749D01*
X132442Y142416D01*
X132275Y142124D01*
X132025Y141874D01*
X131733Y141708D01*
X131400Y141666D01*
G01X131733Y142333D02*
X132233Y141666D01*
G01X134417D02*
X134500Y142208D01*
X134625Y142666D01*
X134792Y143083D01*
X135000Y143541D01*
X135333Y144166D01*
X133667D01*
G01X136683Y142041D02*
X136933Y141833D01*
X137225Y141708D01*
X137600Y141666D01*
X137975Y141749D01*
X138267Y141916D01*
X138475Y142208D01*
X138517Y142541D01*
X138433Y142874D01*
X138225Y143083D01*
X137933Y143249D01*
X137642Y143291D01*
X137350Y143249D01*
X136975Y143083D01*
X137100Y144166D01*
X138225D01*
G01X130000Y159500D02*
Y145500D01*
G01X143000Y159500D02*
X130000D01*
G01X143000Y145500D02*
Y159500D01*
G01X130000Y145500D02*
X143000D01*
G01X148400Y141700D02*
X144400D01*
Y134300D01*
G01X173567Y125100D02*
Y127600D01*
X174608D01*
X174942Y127475D01*
X175150Y127308D01*
X175233Y126975D01*
X175150Y126642D01*
X174900Y126433D01*
X174608Y126308D01*
X173567D01*
G01X174608D02*
X175233Y125100D01*
G01X176792Y125392D02*
X177083Y125183D01*
X177417Y125100D01*
X177750Y125183D01*
X178042Y125433D01*
X178250Y125808D01*
X178333Y126183D01*
Y126642D01*
X178250Y127017D01*
X178042Y127350D01*
X177792Y127517D01*
X177500Y127600D01*
X177167Y127517D01*
X176917Y127350D01*
X176750Y127100D01*
X176667Y126767D01*
X176750Y126475D01*
X176958Y126183D01*
X177208Y126017D01*
X177500Y125975D01*
X177833Y126058D01*
X178083Y126267D01*
X178333Y126642D01*
G01X180600Y125100D02*
X180892Y125142D01*
X181225Y125267D01*
X181433Y125475D01*
X181517Y125767D01*
X181433Y126058D01*
X181183Y126308D01*
X180808Y126433D01*
X180392D01*
X180142Y126517D01*
X179933Y126725D01*
X179850Y127017D01*
X179975Y127308D01*
X180267Y127517D01*
X180600Y127600D01*
X180933Y127517D01*
X181225Y127308D01*
X181350Y127017D01*
X181267Y126725D01*
X181058Y126517D01*
X180808Y126433D01*
X180392D01*
X180017Y126308D01*
X179767Y126058D01*
X179683Y125767D01*
X179767Y125475D01*
X179975Y125267D01*
X180308Y125142D01*
X180600Y125100D01*
G01X184200D02*
Y127600D01*
X182658Y125808D01*
X184742D01*
G01X185883Y125600D02*
X186133Y125308D01*
X186467Y125142D01*
X186842Y125100D01*
X187175Y125142D01*
X187508Y125350D01*
X187717Y125600D01*
X187758Y125850D01*
X187675Y126142D01*
X187383Y126350D01*
X187092Y126433D01*
X186717D01*
G01X187092D02*
X187342Y126558D01*
X187550Y126767D01*
X187633Y127017D01*
X187550Y127267D01*
X187342Y127475D01*
X186967Y127600D01*
X186592Y127558D01*
X186217Y127392D01*
G01X183354Y145453D02*
Y149453D01*
X175954D01*
G01X126875Y166500D02*
X127208Y166292D01*
X127583Y166167D01*
X127917D01*
X128250Y166292D01*
X128500Y166500D01*
X128625Y166792D01*
X128542Y167084D01*
X128333Y167334D01*
X127958Y167500D01*
X127458Y167584D01*
X127167Y167750D01*
X127042Y168042D01*
X127125Y168334D01*
X127333Y168542D01*
X127625Y168667D01*
X127917D01*
X128208Y168584D01*
X128458Y168375D01*
G01X130017Y166167D02*
Y168667D01*
X131058D01*
X131392Y168542D01*
X131600Y168375D01*
X131683Y168042D01*
X131600Y167709D01*
X131350Y167500D01*
X131058Y167375D01*
X130017D01*
G01X131058D02*
X131683Y166167D01*
G01X133950D02*
Y168667D01*
X133450Y168167D01*
G01Y166167D02*
X134450D01*
G01X137050D02*
Y168667D01*
X136550Y168167D01*
G01Y166167D02*
X137550D01*
G01X139233Y166667D02*
X139483Y166375D01*
X139817Y166209D01*
X140192Y166167D01*
X140525Y166209D01*
X140858Y166417D01*
X141067Y166667D01*
X141108Y166917D01*
X141025Y167209D01*
X140733Y167417D01*
X140442Y167500D01*
X140067D01*
G01X140442D02*
X140692Y167625D01*
X140900Y167834D01*
X140983Y168084D01*
X140900Y168334D01*
X140692Y168542D01*
X140317Y168667D01*
X139942Y168625D01*
X139567Y168459D01*
G01X142542Y166459D02*
X142833Y166250D01*
X143167Y166167D01*
X143500Y166250D01*
X143792Y166500D01*
X144000Y166875D01*
X144083Y167250D01*
Y167709D01*
X144000Y168084D01*
X143792Y168417D01*
X143542Y168584D01*
X143250Y168667D01*
X142917Y168584D01*
X142667Y168417D01*
X142500Y168167D01*
X142417Y167834D01*
X142500Y167542D01*
X142708Y167250D01*
X142958Y167084D01*
X143250Y167042D01*
X143583Y167125D01*
X143833Y167334D01*
X144083Y167709D01*
G01X138075Y160475D02*
Y164475D01*
X130675D01*
G01X153975Y125433D02*
X154308Y125225D01*
X154683Y125100D01*
X155017D01*
X155350Y125225D01*
X155600Y125433D01*
X155725Y125725D01*
X155642Y126017D01*
X155433Y126267D01*
X155058Y126433D01*
X154558Y126517D01*
X154267Y126683D01*
X154142Y126975D01*
X154225Y127267D01*
X154433Y127475D01*
X154725Y127600D01*
X155017D01*
X155308Y127517D01*
X155558Y127308D01*
G01X157117Y125100D02*
Y127600D01*
X158158D01*
X158492Y127475D01*
X158700Y127308D01*
X158783Y126975D01*
X158700Y126642D01*
X158450Y126433D01*
X158158Y126308D01*
X157117D01*
G01X158158D02*
X158783Y125100D01*
G01X161050D02*
Y127600D01*
X160550Y127100D01*
G01Y125100D02*
X161550D01*
G01X164150D02*
Y127600D01*
X163650Y127100D01*
G01Y125100D02*
X164650D01*
G01X167750D02*
Y127600D01*
X166208Y125808D01*
X168292D01*
G01X170350Y127600D02*
X170017Y127517D01*
X169767Y127308D01*
X169600Y127058D01*
X169475Y126725D01*
X169433Y126350D01*
X169475Y125975D01*
X169600Y125642D01*
X169767Y125392D01*
X170017Y125183D01*
X170350Y125100D01*
X170683Y125183D01*
X170933Y125392D01*
X171100Y125642D01*
X171225Y125975D01*
X171267Y126350D01*
X171225Y126725D01*
X171100Y127058D01*
X170933Y127308D01*
X170683Y127517D01*
X170350Y127600D01*
G01X168402Y145753D02*
X172402D01*
Y153153D01*
G01X152557Y141700D02*
X148557D01*
Y134300D01*
G01X161334Y146467D02*
X158834D01*
Y147508D01*
X158959Y147842D01*
X159126Y148050D01*
X159459Y148133D01*
X159792Y148050D01*
X160001Y147800D01*
X160126Y147508D01*
Y146467D01*
G01Y147508D02*
X161334Y148133D01*
G01X161042Y149692D02*
X161251Y149983D01*
X161334Y150317D01*
X161251Y150650D01*
X161001Y150942D01*
X160626Y151150D01*
X160251Y151233D01*
X159792D01*
X159417Y151150D01*
X159084Y150942D01*
X158917Y150692D01*
X158834Y150400D01*
X158917Y150067D01*
X159084Y149817D01*
X159334Y149650D01*
X159667Y149567D01*
X159959Y149650D01*
X160251Y149858D01*
X160417Y150108D01*
X160459Y150400D01*
X160376Y150733D01*
X160167Y150983D01*
X159792Y151233D01*
G01X161042Y152792D02*
X161251Y153083D01*
X161334Y153417D01*
X161251Y153750D01*
X161001Y154042D01*
X160626Y154250D01*
X160251Y154333D01*
X159792D01*
X159417Y154250D01*
X159084Y154042D01*
X158917Y153792D01*
X158834Y153500D01*
X158917Y153167D01*
X159084Y152917D01*
X159334Y152750D01*
X159667Y152667D01*
X159959Y152750D01*
X160251Y152958D01*
X160417Y153208D01*
X160459Y153500D01*
X160376Y153833D01*
X160167Y154083D01*
X159792Y154333D01*
G01X161334Y157100D02*
X158834D01*
X160626Y155558D01*
Y157642D01*
G01X160292Y158908D02*
X160001Y159200D01*
X159834Y159450D01*
X159751Y159783D01*
X159834Y160075D01*
X160001Y160283D01*
X160251Y160450D01*
X160542Y160492D01*
X160792Y160450D01*
X161042Y160283D01*
X161251Y160033D01*
X161334Y159742D01*
X161251Y159408D01*
X161001Y159117D01*
X160626Y158950D01*
X160209Y158908D01*
X159667Y158992D01*
X159376Y159117D01*
X159084Y159325D01*
X158876Y159617D01*
X158834Y159908D01*
X158917Y160200D01*
X159126Y160408D01*
G01X161994Y149336D02*
X165994D01*
Y156736D01*
G01X148467Y167867D02*
Y170367D01*
X149508D01*
X149842Y170242D01*
X150050Y170075D01*
X150133Y169742D01*
X150050Y169409D01*
X149800Y169200D01*
X149508Y169075D01*
X148467D01*
G01X149508D02*
X150133Y167867D01*
G01X151692Y168159D02*
X151983Y167950D01*
X152317Y167867D01*
X152650Y167950D01*
X152942Y168200D01*
X153150Y168575D01*
X153233Y168950D01*
Y169409D01*
X153150Y169784D01*
X152942Y170117D01*
X152692Y170284D01*
X152400Y170367D01*
X152067Y170284D01*
X151817Y170117D01*
X151650Y169867D01*
X151567Y169534D01*
X151650Y169242D01*
X151858Y168950D01*
X152108Y168784D01*
X152400Y168742D01*
X152733Y168825D01*
X152983Y169034D01*
X153233Y169409D01*
G01X154792Y168159D02*
X155083Y167950D01*
X155417Y167867D01*
X155750Y167950D01*
X156042Y168200D01*
X156250Y168575D01*
X156333Y168950D01*
Y169409D01*
X156250Y169784D01*
X156042Y170117D01*
X155792Y170284D01*
X155500Y170367D01*
X155167Y170284D01*
X154917Y170117D01*
X154750Y169867D01*
X154667Y169534D01*
X154750Y169242D01*
X154958Y168950D01*
X155208Y168784D01*
X155500Y168742D01*
X155833Y168825D01*
X156083Y169034D01*
X156333Y169409D01*
G01X159100Y167867D02*
Y170367D01*
X157558Y168575D01*
X159642D01*
G01X160783Y168242D02*
X161033Y168034D01*
X161325Y167909D01*
X161700Y167867D01*
X162075Y167950D01*
X162367Y168117D01*
X162575Y168409D01*
X162617Y168742D01*
X162533Y169075D01*
X162325Y169284D01*
X162033Y169450D01*
X161742Y169492D01*
X161450Y169450D01*
X161075Y169284D01*
X161200Y170367D01*
X162325D01*
G01X173056Y166811D02*
Y170811D01*
X165656D01*
G01X172854Y133453D02*
X159454D01*
G01X172854Y143453D02*
Y133453D01*
G01X159454Y143453D02*
X172854D01*
G01X159454Y133453D02*
Y143453D01*
G01X124414Y305679D02*
X123581Y304346D01*
X123081Y302846D01*
Y301512D01*
X123581Y300179D01*
X124414Y299179D01*
X125581Y298679D01*
X126747Y299012D01*
X127748Y299846D01*
X128414Y301346D01*
X128748Y303346D01*
X129414Y304512D01*
X130581Y305012D01*
X131748Y304679D01*
X132581Y303846D01*
X133081Y302679D01*
Y301512D01*
X132748Y300346D01*
X131914Y299346D01*
G01X124414Y295079D02*
X123581Y293746D01*
X123081Y292246D01*
Y290912D01*
X123581Y289579D01*
X124414Y288579D01*
X125581Y288079D01*
X126747Y288412D01*
X127748Y289246D01*
X128414Y290746D01*
X128748Y292746D01*
X129414Y293912D01*
X130581Y294412D01*
X131748Y294079D01*
X132581Y293246D01*
X133081Y292079D01*
Y290912D01*
X132748Y289746D01*
X131914Y288746D01*
G01X123081Y284646D02*
X133081D01*
Y281312D01*
X132581Y279979D01*
X131914Y278979D01*
X130914Y278146D01*
X129747Y277479D01*
X128081Y277312D01*
X126414Y277479D01*
X125248Y278146D01*
X124247Y278979D01*
X123581Y279979D01*
X123081Y281312D01*
Y284646D01*
G01X124247Y273212D02*
X123414Y272046D01*
X123081Y270712D01*
X123414Y269379D01*
X124414Y268212D01*
X125914Y267379D01*
X127414Y267046D01*
X129248D01*
X130748Y267379D01*
X132081Y268212D01*
X132748Y269212D01*
X133081Y270379D01*
X132748Y271713D01*
X132081Y272712D01*
X131081Y273379D01*
X129747Y273712D01*
X128581Y273379D01*
X127414Y272546D01*
X126747Y271546D01*
X126581Y270379D01*
X126914Y269046D01*
X127748Y268046D01*
X129248Y267046D01*
G01X144200Y257117D02*
X144450Y257325D01*
X144617Y257575D01*
X144700Y257867D01*
X144617Y258200D01*
X144450Y258450D01*
X144200Y258700D01*
X143867Y258783D01*
X142200D01*
G01X144408Y260342D02*
X144617Y260633D01*
X144700Y260967D01*
X144617Y261300D01*
X144367Y261592D01*
X143992Y261800D01*
X143617Y261883D01*
X143158D01*
X142783Y261800D01*
X142450Y261592D01*
X142283Y261342D01*
X142200Y261050D01*
X142283Y260717D01*
X142450Y260467D01*
X142700Y260300D01*
X143033Y260217D01*
X143325Y260300D01*
X143617Y260508D01*
X143783Y260758D01*
X143825Y261050D01*
X143742Y261383D01*
X143533Y261633D01*
X143158Y261883D01*
G01X139500Y226417D02*
X137000D01*
Y227417D01*
X137125Y227750D01*
X137417Y228000D01*
X137750Y228083D01*
X138083Y228000D01*
X138333Y227792D01*
X138458Y227417D01*
Y226417D01*
G01X137208Y231267D02*
X137083Y231017D01*
X137000Y230725D01*
Y230392D01*
X137125Y230017D01*
X137333Y229725D01*
X137583Y229517D01*
X138000Y229350D01*
X138375Y229308D01*
X138750Y229392D01*
X139000Y229517D01*
X139250Y229767D01*
X139417Y230058D01*
X139500Y230350D01*
Y230642D01*
X139417Y230933D01*
X139292Y231183D01*
X139125Y231392D01*
G01X139500Y233450D02*
X137000D01*
X137500Y232950D01*
G01X139500D02*
Y233950D01*
G01Y236550D02*
X137000D01*
X137500Y236050D01*
G01X139500D02*
Y237050D01*
G01X139208Y238942D02*
X139417Y239233D01*
X139500Y239567D01*
X139417Y239900D01*
X139167Y240192D01*
X138792Y240400D01*
X138417Y240483D01*
X137958D01*
X137583Y240400D01*
X137250Y240192D01*
X137083Y239942D01*
X137000Y239650D01*
X137083Y239317D01*
X137250Y239067D01*
X137500Y238900D01*
X137833Y238817D01*
X138125Y238900D01*
X138417Y239108D01*
X138583Y239358D01*
X138625Y239650D01*
X138542Y239983D01*
X138333Y240233D01*
X137958Y240483D01*
G01X139208Y242042D02*
X139417Y242333D01*
X139500Y242667D01*
X139417Y243000D01*
X139167Y243292D01*
X138792Y243500D01*
X138417Y243583D01*
X137958D01*
X137583Y243500D01*
X137250Y243292D01*
X137083Y243042D01*
X137000Y242750D01*
X137083Y242417D01*
X137250Y242167D01*
X137500Y242000D01*
X137833Y241917D01*
X138125Y242000D01*
X138417Y242208D01*
X138583Y242458D01*
X138625Y242750D01*
X138542Y243083D01*
X138333Y243333D01*
X137958Y243583D01*
G01X141400Y311817D02*
X138900D01*
Y312817D01*
X139025Y313150D01*
X139317Y313400D01*
X139650Y313483D01*
X139983Y313400D01*
X140233Y313192D01*
X140358Y312817D01*
Y311817D01*
G01X139108Y316667D02*
X138983Y316417D01*
X138900Y316125D01*
Y315792D01*
X139025Y315417D01*
X139233Y315125D01*
X139483Y314917D01*
X139900Y314750D01*
X140275Y314708D01*
X140650Y314792D01*
X140900Y314917D01*
X141150Y315167D01*
X141317Y315458D01*
X141400Y315750D01*
Y316042D01*
X141317Y316333D01*
X141192Y316583D01*
X141025Y316792D01*
G01X141400Y318850D02*
X138900D01*
X139400Y318350D01*
G01X141400D02*
Y319350D01*
G01Y321950D02*
X138900D01*
X139400Y321450D01*
G01X141400D02*
Y322450D01*
G01X141108Y324342D02*
X141317Y324633D01*
X141400Y324967D01*
X141317Y325300D01*
X141067Y325592D01*
X140692Y325800D01*
X140317Y325883D01*
X139858D01*
X139483Y325800D01*
X139150Y325592D01*
X138983Y325342D01*
X138900Y325050D01*
X138983Y324717D01*
X139150Y324467D01*
X139400Y324300D01*
X139733Y324217D01*
X140025Y324300D01*
X140317Y324508D01*
X140483Y324758D01*
X140525Y325050D01*
X140442Y325383D01*
X140233Y325633D01*
X139858Y325883D01*
G01X141400Y328150D02*
X141358Y328442D01*
X141233Y328775D01*
X141025Y328983D01*
X140733Y329067D01*
X140442Y328983D01*
X140192Y328733D01*
X140067Y328358D01*
Y327942D01*
X139983Y327692D01*
X139775Y327483D01*
X139483Y327400D01*
X139192Y327525D01*
X138983Y327817D01*
X138900Y328150D01*
X138983Y328483D01*
X139192Y328775D01*
X139483Y328900D01*
X139775Y328817D01*
X139983Y328608D01*
X140067Y328358D01*
Y327942D01*
X140192Y327567D01*
X140442Y327317D01*
X140733Y327233D01*
X141025Y327317D01*
X141233Y327525D01*
X141358Y327858D01*
X141400Y328150D01*
G01X118277Y309061D02*
Y311561D01*
X119318D01*
X119652Y311436D01*
X119860Y311269D01*
X119943Y310936D01*
X119860Y310603D01*
X119610Y310394D01*
X119318Y310269D01*
X118277D01*
G01X119318D02*
X119943Y309061D01*
G01X122710D02*
Y311561D01*
X121168Y309769D01*
X123252D01*
G01X125310Y311561D02*
X124977Y311478D01*
X124727Y311269D01*
X124560Y311019D01*
X124435Y310686D01*
X124393Y310311D01*
X124435Y309936D01*
X124560Y309603D01*
X124727Y309353D01*
X124977Y309144D01*
X125310Y309061D01*
X125643Y309144D01*
X125893Y309353D01*
X126060Y309603D01*
X126185Y309936D01*
X126227Y310311D01*
X126185Y310686D01*
X126060Y311019D01*
X125893Y311269D01*
X125643Y311478D01*
X125310Y311561D01*
G01X127493Y309436D02*
X127743Y309228D01*
X128035Y309103D01*
X128410Y309061D01*
X128785Y309144D01*
X129077Y309311D01*
X129285Y309603D01*
X129327Y309936D01*
X129243Y310269D01*
X129035Y310478D01*
X128743Y310644D01*
X128452Y310686D01*
X128160Y310644D01*
X127785Y310478D01*
X127910Y311561D01*
X129035D01*
G01X130200Y319000D02*
Y323000D01*
X122800D01*
G01X118277Y314061D02*
Y316561D01*
X119318D01*
X119652Y316436D01*
X119860Y316269D01*
X119943Y315936D01*
X119860Y315603D01*
X119610Y315394D01*
X119318Y315269D01*
X118277D01*
G01X119318D02*
X119943Y314061D01*
G01X122710D02*
Y316561D01*
X121168Y314769D01*
X123252D01*
G01X125310Y316561D02*
X124977Y316478D01*
X124727Y316269D01*
X124560Y316019D01*
X124435Y315686D01*
X124393Y315311D01*
X124435Y314936D01*
X124560Y314603D01*
X124727Y314353D01*
X124977Y314144D01*
X125310Y314061D01*
X125643Y314144D01*
X125893Y314353D01*
X126060Y314603D01*
X126185Y314936D01*
X126227Y315311D01*
X126185Y315686D01*
X126060Y316019D01*
X125893Y316269D01*
X125643Y316478D01*
X125310Y316561D01*
G01X128327Y314061D02*
X128410Y314603D01*
X128535Y315061D01*
X128702Y315478D01*
X128910Y315936D01*
X129243Y316561D01*
X127577D01*
G01X130200Y324000D02*
Y328000D01*
X122800D01*
G01X116295Y337017D02*
X112295D01*
Y329617D01*
G01X114667Y309375D02*
X114875Y309708D01*
X115000Y310083D01*
Y310417D01*
X114875Y310750D01*
X114667Y311000D01*
X114375Y311125D01*
X114083Y311042D01*
X113833Y310833D01*
X113667Y310458D01*
X113583Y309958D01*
X113417Y309667D01*
X113125Y309542D01*
X112833Y309625D01*
X112625Y309833D01*
X112500Y310125D01*
Y310417D01*
X112583Y310708D01*
X112792Y310958D01*
G01X115000Y312517D02*
X112500D01*
Y313558D01*
X112625Y313892D01*
X112792Y314100D01*
X113125Y314183D01*
X113458Y314100D01*
X113667Y313850D01*
X113792Y313558D01*
Y312517D01*
G01Y313558D02*
X115000Y314183D01*
G01Y316450D02*
X112500D01*
X113000Y315950D01*
G01X115000D02*
Y316950D01*
G01Y319550D02*
X112500D01*
X113000Y319050D01*
G01X115000D02*
Y320050D01*
G01Y322650D02*
X112500D01*
X113000Y322150D01*
G01X115000D02*
Y323150D01*
G01X112500Y325750D02*
X112583Y325417D01*
X112792Y325167D01*
X113042Y325000D01*
X113375Y324875D01*
X113750Y324833D01*
X114125Y324875D01*
X114458Y325000D01*
X114708Y325167D01*
X114917Y325417D01*
X115000Y325750D01*
X114917Y326083D01*
X114708Y326333D01*
X114458Y326500D01*
X114125Y326625D01*
X113750Y326667D01*
X113375Y326625D01*
X113042Y326500D01*
X112792Y326333D01*
X112583Y326083D01*
X112500Y325750D01*
G01X124445Y329617D02*
X128445D01*
Y337017D01*
G01X134100Y311817D02*
X131600D01*
Y312817D01*
X131725Y313150D01*
X132017Y313400D01*
X132350Y313483D01*
X132683Y313400D01*
X132933Y313192D01*
X133058Y312817D01*
Y311817D01*
G01X131808Y316667D02*
X131683Y316417D01*
X131600Y316125D01*
Y315792D01*
X131725Y315417D01*
X131933Y315125D01*
X132183Y314917D01*
X132600Y314750D01*
X132975Y314708D01*
X133350Y314792D01*
X133600Y314917D01*
X133850Y315167D01*
X134017Y315458D01*
X134100Y315750D01*
Y316042D01*
X134017Y316333D01*
X133892Y316583D01*
X133725Y316792D01*
G01X134100Y318850D02*
X131600D01*
X132100Y318350D01*
G01X134100D02*
Y319350D01*
G01Y321950D02*
X131600D01*
X132100Y321450D01*
G01X134100D02*
Y322450D01*
G01X133808Y324342D02*
X134017Y324633D01*
X134100Y324967D01*
X134017Y325300D01*
X133767Y325592D01*
X133392Y325800D01*
X133017Y325883D01*
X132558D01*
X132183Y325800D01*
X131850Y325592D01*
X131683Y325342D01*
X131600Y325050D01*
X131683Y324717D01*
X131850Y324467D01*
X132100Y324300D01*
X132433Y324217D01*
X132725Y324300D01*
X133017Y324508D01*
X133183Y324758D01*
X133225Y325050D01*
X133142Y325383D01*
X132933Y325633D01*
X132558Y325883D01*
G01X133058Y327358D02*
X132767Y327650D01*
X132600Y327900D01*
X132517Y328233D01*
X132600Y328525D01*
X132767Y328733D01*
X133017Y328900D01*
X133308Y328942D01*
X133558Y328900D01*
X133808Y328733D01*
X134017Y328483D01*
X134100Y328192D01*
X134017Y327858D01*
X133767Y327567D01*
X133392Y327400D01*
X132975Y327358D01*
X132433Y327442D01*
X132142Y327567D01*
X131850Y327775D01*
X131642Y328067D01*
X131600Y328358D01*
X131683Y328650D01*
X131892Y328858D01*
G01X132650Y330550D02*
Y349250D01*
X142950D01*
Y330550D01*
X132650D01*
G01X155600Y349117D02*
X153100D01*
Y350117D01*
X153225Y350450D01*
X153517Y350700D01*
X153850Y350783D01*
X154183Y350700D01*
X154433Y350492D01*
X154558Y350117D01*
Y349117D01*
G01X153308Y353967D02*
X153183Y353717D01*
X153100Y353425D01*
Y353092D01*
X153225Y352717D01*
X153433Y352425D01*
X153683Y352217D01*
X154100Y352050D01*
X154475Y352008D01*
X154850Y352092D01*
X155100Y352217D01*
X155350Y352467D01*
X155517Y352758D01*
X155600Y353050D01*
Y353342D01*
X155517Y353633D01*
X155392Y353883D01*
X155225Y354092D01*
G01X155600Y356150D02*
X153100D01*
X153600Y355650D01*
G01X155600D02*
Y356650D01*
G01Y359250D02*
X153100D01*
X153600Y358750D01*
G01X155600D02*
Y359750D01*
G01X155308Y361642D02*
X155517Y361933D01*
X155600Y362267D01*
X155517Y362600D01*
X155267Y362892D01*
X154892Y363100D01*
X154517Y363183D01*
X154058D01*
X153683Y363100D01*
X153350Y362892D01*
X153183Y362642D01*
X153100Y362350D01*
X153183Y362017D01*
X153350Y361767D01*
X153600Y361600D01*
X153933Y361517D01*
X154225Y361600D01*
X154517Y361808D01*
X154683Y362058D01*
X154725Y362350D01*
X154642Y362683D01*
X154433Y362933D01*
X154058Y363183D01*
G01X155600Y365367D02*
X155058Y365450D01*
X154600Y365575D01*
X154183Y365742D01*
X153725Y365950D01*
X153100Y366283D01*
Y364617D01*
G01X141900Y423600D02*
Y409600D01*
G01X154900D02*
Y423600D01*
G01X141900Y409600D02*
X154900D01*
G01X122900Y382500D02*
X122567Y382542D01*
X122275Y382708D01*
X122025Y382958D01*
X121858Y383250D01*
X121775Y383583D01*
Y383917D01*
X121858Y384250D01*
X122025Y384542D01*
X122275Y384792D01*
X122567Y384958D01*
X122900Y385000D01*
X123233Y384958D01*
X123525Y384792D01*
X123775Y384542D01*
X123942Y384250D01*
X124025Y383917D01*
Y383583D01*
X123942Y383250D01*
X123775Y382958D01*
X123525Y382708D01*
X123233Y382542D01*
X122900Y382500D01*
G01X123233Y383167D02*
X123733Y382500D01*
G01X125917D02*
X126000Y383042D01*
X126125Y383500D01*
X126292Y383917D01*
X126500Y384375D01*
X126833Y385000D01*
X125167D01*
G01X128308Y384583D02*
X128558Y384833D01*
X128850Y384958D01*
X129183Y385000D01*
X129600Y384917D01*
X129892Y384708D01*
X129975Y384458D01*
X129933Y384208D01*
X129767Y384000D01*
X128933Y383583D01*
X128558Y383292D01*
X128308Y382875D01*
X128225Y382500D01*
X129975D01*
G01X130500Y380400D02*
X116500D01*
G01X130500Y367400D02*
Y380400D01*
G01X116500Y367400D02*
X130500D01*
G01X116500Y380400D02*
Y367400D01*
G01X114700Y386900D02*
X114367Y386942D01*
X114075Y387108D01*
X113825Y387358D01*
X113658Y387650D01*
X113575Y387983D01*
Y388317D01*
X113658Y388650D01*
X113825Y388942D01*
X114075Y389192D01*
X114367Y389358D01*
X114700Y389400D01*
X115033Y389358D01*
X115325Y389192D01*
X115575Y388942D01*
X115742Y388650D01*
X115825Y388317D01*
Y387983D01*
X115742Y387650D01*
X115575Y387358D01*
X115325Y387108D01*
X115033Y386942D01*
X114700Y386900D01*
G01X115033Y387567D02*
X115533Y386900D01*
G01X117092Y387192D02*
X117383Y386983D01*
X117717Y386900D01*
X118050Y386983D01*
X118342Y387233D01*
X118550Y387608D01*
X118633Y387983D01*
Y388442D01*
X118550Y388817D01*
X118342Y389150D01*
X118092Y389317D01*
X117800Y389400D01*
X117467Y389317D01*
X117217Y389150D01*
X117050Y388900D01*
X116967Y388567D01*
X117050Y388275D01*
X117258Y387983D01*
X117508Y387817D01*
X117800Y387775D01*
X118133Y387858D01*
X118383Y388067D01*
X118633Y388442D01*
G01X120900Y386900D02*
Y389400D01*
X120400Y388900D01*
G01Y386900D02*
X121400D01*
G01X113125Y394725D02*
X127125D01*
G01X113125Y407725D02*
Y394725D01*
G01X127125Y407725D02*
X113125D01*
G01X127125Y394725D02*
Y407725D01*
G01X142200Y386900D02*
X141867Y386942D01*
X141575Y387108D01*
X141325Y387358D01*
X141158Y387650D01*
X141075Y387983D01*
Y388317D01*
X141158Y388650D01*
X141325Y388942D01*
X141575Y389192D01*
X141867Y389358D01*
X142200Y389400D01*
X142533Y389358D01*
X142825Y389192D01*
X143075Y388942D01*
X143242Y388650D01*
X143325Y388317D01*
Y387983D01*
X143242Y387650D01*
X143075Y387358D01*
X142825Y387108D01*
X142533Y386942D01*
X142200Y386900D01*
G01X142533Y387567D02*
X143033Y386900D01*
G01X144592Y387192D02*
X144883Y386983D01*
X145217Y386900D01*
X145550Y386983D01*
X145842Y387233D01*
X146050Y387608D01*
X146133Y387983D01*
Y388442D01*
X146050Y388817D01*
X145842Y389150D01*
X145592Y389317D01*
X145300Y389400D01*
X144967Y389317D01*
X144717Y389150D01*
X144550Y388900D01*
X144467Y388567D01*
X144550Y388275D01*
X144758Y387983D01*
X145008Y387817D01*
X145300Y387775D01*
X145633Y387858D01*
X145883Y388067D01*
X146133Y388442D01*
G01X147608Y388983D02*
X147858Y389233D01*
X148150Y389358D01*
X148483Y389400D01*
X148900Y389317D01*
X149192Y389108D01*
X149275Y388858D01*
X149233Y388608D01*
X149067Y388400D01*
X148233Y387983D01*
X147858Y387692D01*
X147608Y387275D01*
X147525Y386900D01*
X149275D01*
G01X132625Y394725D02*
X146625D01*
G01X132625Y407725D02*
Y394725D01*
G01X146625Y407725D02*
X132625D01*
G01X146625Y394725D02*
Y407725D01*
G01X168500Y396467D02*
X166000D01*
Y397508D01*
X166125Y397842D01*
X166292Y398050D01*
X166625Y398133D01*
X166958Y398050D01*
X167167Y397800D01*
X167292Y397508D01*
Y396467D01*
G01Y397508D02*
X168500Y398133D01*
G01X168208Y399692D02*
X168417Y399983D01*
X168500Y400317D01*
X168417Y400650D01*
X168167Y400942D01*
X167792Y401150D01*
X167417Y401233D01*
X166958D01*
X166583Y401150D01*
X166250Y400942D01*
X166083Y400692D01*
X166000Y400400D01*
X166083Y400067D01*
X166250Y399817D01*
X166500Y399650D01*
X166833Y399567D01*
X167125Y399650D01*
X167417Y399858D01*
X167583Y400108D01*
X167625Y400400D01*
X167542Y400733D01*
X167333Y400983D01*
X166958Y401233D01*
G01X168500Y403417D02*
X167958Y403500D01*
X167500Y403625D01*
X167083Y403792D01*
X166625Y404000D01*
X166000Y404333D01*
Y402667D01*
G01X168125Y405683D02*
X168333Y405933D01*
X168458Y406225D01*
X168500Y406600D01*
X168417Y406975D01*
X168250Y407267D01*
X167958Y407475D01*
X167625Y407517D01*
X167292Y407433D01*
X167083Y407225D01*
X166917Y406933D01*
X166875Y406642D01*
X166917Y406350D01*
X167083Y405975D01*
X166000Y406100D01*
Y407225D01*
G01X168500Y410200D02*
X166000D01*
X167792Y408658D01*
Y410742D01*
G01X155625Y407825D02*
X151625D01*
Y400425D01*
G01X111650Y368450D02*
X115650D01*
Y375850D01*
G01X164500Y396467D02*
X162000D01*
Y397508D01*
X162125Y397842D01*
X162292Y398050D01*
X162625Y398133D01*
X162958Y398050D01*
X163167Y397800D01*
X163292Y397508D01*
Y396467D01*
G01Y397508D02*
X164500Y398133D01*
G01X164208Y399692D02*
X164417Y399983D01*
X164500Y400317D01*
X164417Y400650D01*
X164167Y400942D01*
X163792Y401150D01*
X163417Y401233D01*
X162958D01*
X162583Y401150D01*
X162250Y400942D01*
X162083Y400692D01*
X162000Y400400D01*
X162083Y400067D01*
X162250Y399817D01*
X162500Y399650D01*
X162833Y399567D01*
X163125Y399650D01*
X163417Y399858D01*
X163583Y400108D01*
X163625Y400400D01*
X163542Y400733D01*
X163333Y400983D01*
X162958Y401233D01*
G01X164500Y403417D02*
X163958Y403500D01*
X163500Y403625D01*
X163083Y403792D01*
X162625Y404000D01*
X162000Y404333D01*
Y402667D01*
G01X164500Y406517D02*
X163958Y406600D01*
X163500Y406725D01*
X163083Y406892D01*
X162625Y407100D01*
X162000Y407433D01*
Y405767D01*
G01X164000Y408783D02*
X164292Y409033D01*
X164458Y409367D01*
X164500Y409742D01*
X164458Y410075D01*
X164250Y410408D01*
X164000Y410617D01*
X163750Y410658D01*
X163458Y410575D01*
X163250Y410283D01*
X163167Y409992D01*
Y409617D01*
G01Y409992D02*
X163042Y410242D01*
X162833Y410450D01*
X162583Y410533D01*
X162333Y410450D01*
X162125Y410242D01*
X162000Y409867D01*
X162042Y409492D01*
X162208Y409117D01*
G01X147125Y400425D02*
X151125D01*
Y407825D01*
G01X152867Y386900D02*
Y389400D01*
X153908D01*
X154242Y389275D01*
X154450Y389108D01*
X154533Y388775D01*
X154450Y388442D01*
X154200Y388233D01*
X153908Y388108D01*
X152867D01*
G01X153908D02*
X154533Y386900D01*
G01X156092Y387192D02*
X156383Y386983D01*
X156717Y386900D01*
X157050Y386983D01*
X157342Y387233D01*
X157550Y387608D01*
X157633Y387983D01*
Y388442D01*
X157550Y388817D01*
X157342Y389150D01*
X157092Y389317D01*
X156800Y389400D01*
X156467Y389317D01*
X156217Y389150D01*
X156050Y388900D01*
X155967Y388567D01*
X156050Y388275D01*
X156258Y387983D01*
X156508Y387817D01*
X156800Y387775D01*
X157133Y387858D01*
X157383Y388067D01*
X157633Y388442D01*
G01X159900Y386900D02*
X160192Y386942D01*
X160525Y387067D01*
X160733Y387275D01*
X160817Y387567D01*
X160733Y387858D01*
X160483Y388108D01*
X160108Y388233D01*
X159692D01*
X159442Y388317D01*
X159233Y388525D01*
X159150Y388817D01*
X159275Y389108D01*
X159567Y389317D01*
X159900Y389400D01*
X160233Y389317D01*
X160525Y389108D01*
X160650Y388817D01*
X160567Y388525D01*
X160358Y388317D01*
X160108Y388233D01*
X159692D01*
X159317Y388108D01*
X159067Y387858D01*
X158983Y387567D01*
X159067Y387275D01*
X159275Y387067D01*
X159608Y386942D01*
X159900Y386900D01*
G01X162208Y387942D02*
X162500Y388233D01*
X162750Y388400D01*
X163083Y388483D01*
X163375Y388400D01*
X163583Y388233D01*
X163750Y387983D01*
X163792Y387692D01*
X163750Y387442D01*
X163583Y387192D01*
X163333Y386983D01*
X163042Y386900D01*
X162708Y386983D01*
X162417Y387233D01*
X162250Y387608D01*
X162208Y388025D01*
X162292Y388567D01*
X162417Y388858D01*
X162625Y389150D01*
X162917Y389358D01*
X163208Y389400D01*
X163500Y389317D01*
X163708Y389108D01*
G01X165183Y387275D02*
X165433Y387067D01*
X165725Y386942D01*
X166100Y386900D01*
X166475Y386983D01*
X166767Y387150D01*
X166975Y387442D01*
X167017Y387775D01*
X166933Y388108D01*
X166725Y388317D01*
X166433Y388483D01*
X166142Y388525D01*
X165850Y388483D01*
X165475Y388317D01*
X165600Y389400D01*
X166725D01*
G01X160150Y395350D02*
Y399350D01*
X152750D01*
G01X123767Y386900D02*
Y389400D01*
X124808D01*
X125142Y389275D01*
X125350Y389108D01*
X125433Y388775D01*
X125350Y388442D01*
X125100Y388233D01*
X124808Y388108D01*
X123767D01*
G01X124808D02*
X125433Y386900D01*
G01X126992Y387192D02*
X127283Y386983D01*
X127617Y386900D01*
X127950Y386983D01*
X128242Y387233D01*
X128450Y387608D01*
X128533Y387983D01*
Y388442D01*
X128450Y388817D01*
X128242Y389150D01*
X127992Y389317D01*
X127700Y389400D01*
X127367Y389317D01*
X127117Y389150D01*
X126950Y388900D01*
X126867Y388567D01*
X126950Y388275D01*
X127158Y387983D01*
X127408Y387817D01*
X127700Y387775D01*
X128033Y387858D01*
X128283Y388067D01*
X128533Y388442D01*
G01X130800Y386900D02*
X131092Y386942D01*
X131425Y387067D01*
X131633Y387275D01*
X131717Y387567D01*
X131633Y387858D01*
X131383Y388108D01*
X131008Y388233D01*
X130592D01*
X130342Y388317D01*
X130133Y388525D01*
X130050Y388817D01*
X130175Y389108D01*
X130467Y389317D01*
X130800Y389400D01*
X131133Y389317D01*
X131425Y389108D01*
X131550Y388817D01*
X131467Y388525D01*
X131258Y388317D01*
X131008Y388233D01*
X130592D01*
X130217Y388108D01*
X129967Y387858D01*
X129883Y387567D01*
X129967Y387275D01*
X130175Y387067D01*
X130508Y386942D01*
X130800Y386900D01*
G01X133108Y387942D02*
X133400Y388233D01*
X133650Y388400D01*
X133983Y388483D01*
X134275Y388400D01*
X134483Y388233D01*
X134650Y387983D01*
X134692Y387692D01*
X134650Y387442D01*
X134483Y387192D01*
X134233Y386983D01*
X133942Y386900D01*
X133608Y386983D01*
X133317Y387233D01*
X133150Y387608D01*
X133108Y388025D01*
X133192Y388567D01*
X133317Y388858D01*
X133525Y389150D01*
X133817Y389358D01*
X134108Y389400D01*
X134400Y389317D01*
X134608Y389108D01*
G01X136208Y387942D02*
X136500Y388233D01*
X136750Y388400D01*
X137083Y388483D01*
X137375Y388400D01*
X137583Y388233D01*
X137750Y387983D01*
X137792Y387692D01*
X137750Y387442D01*
X137583Y387192D01*
X137333Y386983D01*
X137042Y386900D01*
X136708Y386983D01*
X136417Y387233D01*
X136250Y387608D01*
X136208Y388025D01*
X136292Y388567D01*
X136417Y388858D01*
X136625Y389150D01*
X136917Y389358D01*
X137208Y389400D01*
X137500Y389317D01*
X137708Y389108D01*
G01X131975Y406675D02*
X127975D01*
Y399275D01*
G01X138017Y380800D02*
Y383300D01*
X139058D01*
X139392Y383175D01*
X139600Y383008D01*
X139683Y382675D01*
X139600Y382342D01*
X139350Y382133D01*
X139058Y382008D01*
X138017D01*
G01X139058D02*
X139683Y380800D01*
G01X141242Y381092D02*
X141533Y380883D01*
X141867Y380800D01*
X142200Y380883D01*
X142492Y381133D01*
X142700Y381508D01*
X142783Y381883D01*
Y382342D01*
X142700Y382717D01*
X142492Y383050D01*
X142242Y383217D01*
X141950Y383300D01*
X141617Y383217D01*
X141367Y383050D01*
X141200Y382800D01*
X141117Y382467D01*
X141200Y382175D01*
X141408Y381883D01*
X141658Y381717D01*
X141950Y381675D01*
X142283Y381758D01*
X142533Y381967D01*
X142783Y382342D01*
G01X145050Y380800D02*
X145342Y380842D01*
X145675Y380967D01*
X145883Y381175D01*
X145967Y381467D01*
X145883Y381758D01*
X145633Y382008D01*
X145258Y382133D01*
X144842D01*
X144592Y382217D01*
X144383Y382425D01*
X144300Y382717D01*
X144425Y383008D01*
X144717Y383217D01*
X145050Y383300D01*
X145383Y383217D01*
X145675Y383008D01*
X145800Y382717D01*
X145717Y382425D01*
X145508Y382217D01*
X145258Y382133D01*
X144842D01*
X144467Y382008D01*
X144217Y381758D01*
X144133Y381467D01*
X144217Y381175D01*
X144425Y380967D01*
X144758Y380842D01*
X145050Y380800D01*
G01X147233Y381300D02*
X147483Y381008D01*
X147817Y380842D01*
X148192Y380800D01*
X148525Y380842D01*
X148858Y381050D01*
X149067Y381300D01*
X149108Y381550D01*
X149025Y381842D01*
X148733Y382050D01*
X148442Y382133D01*
X148067D01*
G01X148442D02*
X148692Y382258D01*
X148900Y382467D01*
X148983Y382717D01*
X148900Y382967D01*
X148692Y383175D01*
X148317Y383300D01*
X147942Y383258D01*
X147567Y383092D01*
G01X151250Y380800D02*
X151542Y380842D01*
X151875Y380967D01*
X152083Y381175D01*
X152167Y381467D01*
X152083Y381758D01*
X151833Y382008D01*
X151458Y382133D01*
X151042D01*
X150792Y382217D01*
X150583Y382425D01*
X150500Y382717D01*
X150625Y383008D01*
X150917Y383217D01*
X151250Y383300D01*
X151583Y383217D01*
X151875Y383008D01*
X152000Y382717D01*
X151917Y382425D01*
X151708Y382217D01*
X151458Y382133D01*
X151042D01*
X150667Y382008D01*
X150417Y381758D01*
X150333Y381467D01*
X150417Y381175D01*
X150625Y380967D01*
X150958Y380842D01*
X151250Y380800D01*
G01X149500Y371800D02*
X144300D01*
G01X149500Y378800D02*
X141700D01*
G01X149500Y371800D02*
Y378800D01*
G01X136100Y371800D02*
X144800D01*
G01X136100Y378800D02*
Y371800D01*
G01X142500Y378800D02*
X136100D01*
G01X120083Y365200D02*
Y363408D01*
X120250Y363033D01*
X120583Y362783D01*
X121000Y362700D01*
X121417Y362783D01*
X121750Y363033D01*
X121917Y363408D01*
Y365200D01*
G01X124100Y362700D02*
Y365200D01*
X123600Y364700D01*
G01Y362700D02*
X124600D01*
G01X127200D02*
X127492Y362742D01*
X127825Y362867D01*
X128033Y363075D01*
X128117Y363367D01*
X128033Y363658D01*
X127783Y363908D01*
X127408Y364033D01*
X126992D01*
X126742Y364117D01*
X126533Y364325D01*
X126450Y364617D01*
X126575Y364908D01*
X126867Y365117D01*
X127200Y365200D01*
X127533Y365117D01*
X127825Y364908D01*
X127950Y364617D01*
X127867Y364325D01*
X127658Y364117D01*
X127408Y364033D01*
X126992D01*
X126617Y363908D01*
X126367Y363658D01*
X126283Y363367D01*
X126367Y363075D01*
X126575Y362867D01*
X126908Y362742D01*
X127200Y362700D01*
G01X119200Y360800D02*
X117200Y358800D01*
X115200Y360800D01*
G01X111600D02*
Y341600D01*
X122800D01*
Y360800D01*
X111600D01*
G01X167967Y375900D02*
Y378400D01*
X169008D01*
X169342Y378275D01*
X169550Y378108D01*
X169633Y377775D01*
X169550Y377442D01*
X169300Y377233D01*
X169008Y377108D01*
X167967D01*
G01X169008D02*
X169633Y375900D01*
G01X171192Y376192D02*
X171483Y375983D01*
X171817Y375900D01*
X172150Y375983D01*
X172442Y376233D01*
X172650Y376608D01*
X172733Y376983D01*
Y377442D01*
X172650Y377817D01*
X172442Y378150D01*
X172192Y378317D01*
X171900Y378400D01*
X171567Y378317D01*
X171317Y378150D01*
X171150Y377900D01*
X171067Y377567D01*
X171150Y377275D01*
X171358Y376983D01*
X171608Y376817D01*
X171900Y376775D01*
X172233Y376858D01*
X172483Y377067D01*
X172733Y377442D01*
G01X174208Y377983D02*
X174458Y378233D01*
X174750Y378358D01*
X175083Y378400D01*
X175500Y378317D01*
X175792Y378108D01*
X175875Y377858D01*
X175833Y377608D01*
X175667Y377400D01*
X174833Y376983D01*
X174458Y376692D01*
X174208Y376275D01*
X174125Y375900D01*
X175875D01*
G01X178600D02*
Y378400D01*
X177058Y376608D01*
X179142D01*
G01X180408Y377983D02*
X180658Y378233D01*
X180950Y378358D01*
X181283Y378400D01*
X181700Y378317D01*
X181992Y378108D01*
X182075Y377858D01*
X182033Y377608D01*
X181867Y377400D01*
X181033Y376983D01*
X180658Y376692D01*
X180408Y376275D01*
X180325Y375900D01*
X182075D01*
G01X182600Y361800D02*
Y374800D01*
G01X156600Y361800D02*
X182600D01*
G01X156600Y374800D02*
Y361800D01*
G01X182600Y374800D02*
X156600D01*
G01X151600Y349117D02*
X149100D01*
Y350117D01*
X149225Y350450D01*
X149517Y350700D01*
X149850Y350783D01*
X150183Y350700D01*
X150433Y350492D01*
X150558Y350117D01*
Y349117D01*
G01X149308Y353967D02*
X149183Y353717D01*
X149100Y353425D01*
Y353092D01*
X149225Y352717D01*
X149433Y352425D01*
X149683Y352217D01*
X150100Y352050D01*
X150475Y352008D01*
X150850Y352092D01*
X151100Y352217D01*
X151350Y352467D01*
X151517Y352758D01*
X151600Y353050D01*
Y353342D01*
X151517Y353633D01*
X151392Y353883D01*
X151225Y354092D01*
G01X151600Y356150D02*
X149100D01*
X149600Y355650D01*
G01X151600D02*
Y356650D01*
G01Y359250D02*
X149100D01*
X149600Y358750D01*
G01X151600D02*
Y359750D01*
G01X151308Y361642D02*
X151517Y361933D01*
X151600Y362267D01*
X151517Y362600D01*
X151267Y362892D01*
X150892Y363100D01*
X150517Y363183D01*
X150058D01*
X149683Y363100D01*
X149350Y362892D01*
X149183Y362642D01*
X149100Y362350D01*
X149183Y362017D01*
X149350Y361767D01*
X149600Y361600D01*
X149933Y361517D01*
X150225Y361600D01*
X150517Y361808D01*
X150683Y362058D01*
X150725Y362350D01*
X150642Y362683D01*
X150433Y362933D01*
X150058Y363183D01*
G01X151225Y364533D02*
X151433Y364783D01*
X151558Y365075D01*
X151600Y365450D01*
X151517Y365825D01*
X151350Y366117D01*
X151058Y366325D01*
X150725Y366367D01*
X150392Y366283D01*
X150183Y366075D01*
X150017Y365783D01*
X149975Y365492D01*
X150017Y365200D01*
X150183Y364825D01*
X149100Y364950D01*
Y366075D01*
G01X143050Y368950D02*
Y350250D01*
X132750D01*
Y368950D01*
X143050D01*
G01X144717Y445627D02*
X144592Y445377D01*
X144509Y445085D01*
Y444752D01*
X144634Y444377D01*
X144842Y444085D01*
X145092Y443877D01*
X145509Y443710D01*
X145884Y443668D01*
X146259Y443752D01*
X146509Y443877D01*
X146759Y444127D01*
X146926Y444418D01*
X147009Y444710D01*
Y445002D01*
X146926Y445293D01*
X146801Y445543D01*
X146634Y445752D01*
G01X146509Y446893D02*
X146801Y447143D01*
X146967Y447477D01*
X147009Y447852D01*
X146967Y448185D01*
X146759Y448518D01*
X146509Y448727D01*
X146259Y448768D01*
X145967Y448685D01*
X145759Y448393D01*
X145676Y448102D01*
Y447727D01*
G01Y448102D02*
X145551Y448352D01*
X145342Y448560D01*
X145092Y448643D01*
X144842Y448560D01*
X144634Y448352D01*
X144509Y447977D01*
X144551Y447602D01*
X144717Y447227D01*
G01X146717Y450202D02*
X146926Y450493D01*
X147009Y450827D01*
X146926Y451160D01*
X146676Y451452D01*
X146301Y451660D01*
X145926Y451743D01*
X145467D01*
X145092Y451660D01*
X144759Y451452D01*
X144592Y451202D01*
X144509Y450910D01*
X144592Y450577D01*
X144759Y450327D01*
X145009Y450160D01*
X145342Y450077D01*
X145634Y450160D01*
X145926Y450368D01*
X146092Y450618D01*
X146134Y450910D01*
X146051Y451243D01*
X145842Y451493D01*
X145467Y451743D01*
G01X146634Y453093D02*
X146842Y453343D01*
X146967Y453635D01*
X147009Y454010D01*
X146926Y454385D01*
X146759Y454677D01*
X146467Y454885D01*
X146134Y454927D01*
X145801Y454843D01*
X145592Y454635D01*
X145426Y454343D01*
X145384Y454052D01*
X145426Y453760D01*
X145592Y453385D01*
X144509Y453510D01*
Y454635D01*
G01X167400Y414000D02*
X167358Y413667D01*
X167192Y413375D01*
X166942Y413125D01*
X166650Y412958D01*
X166317Y412875D01*
X165983D01*
X165650Y412958D01*
X165358Y413125D01*
X165108Y413375D01*
X164942Y413667D01*
X164900Y414000D01*
X164942Y414333D01*
X165108Y414625D01*
X165358Y414875D01*
X165650Y415042D01*
X165983Y415125D01*
X166317D01*
X166650Y415042D01*
X166942Y414875D01*
X167192Y414625D01*
X167358Y414333D01*
X167400Y414000D01*
G01X166733Y414333D02*
X167400Y414833D01*
G01X165317Y416308D02*
X165067Y416558D01*
X164942Y416850D01*
X164900Y417183D01*
X164983Y417600D01*
X165192Y417892D01*
X165442Y417975D01*
X165692Y417933D01*
X165900Y417767D01*
X166317Y416933D01*
X166608Y416558D01*
X167025Y416308D01*
X167400Y416225D01*
Y417975D01*
G01Y420200D02*
X164900D01*
X165400Y419700D01*
G01X167400D02*
Y420700D01*
G01X154900Y423600D02*
X141900D01*
G01X144077Y440010D02*
Y442510D01*
X145118D01*
X145452Y442385D01*
X145660Y442218D01*
X145743Y441885D01*
X145660Y441552D01*
X145410Y441343D01*
X145118Y441218D01*
X144077D01*
G01X145118D02*
X145743Y440010D01*
G01X148010D02*
Y442510D01*
X147510Y442010D01*
G01Y440010D02*
X148510D01*
G01X150193Y440385D02*
X150443Y440177D01*
X150735Y440052D01*
X151110Y440010D01*
X151485Y440093D01*
X151777Y440260D01*
X151985Y440552D01*
X152027Y440885D01*
X151943Y441218D01*
X151735Y441427D01*
X151443Y441593D01*
X151152Y441635D01*
X150860Y441593D01*
X150485Y441427D01*
X150610Y442510D01*
X151735D01*
G01X154210Y440010D02*
Y442510D01*
X153710Y442010D01*
G01Y440010D02*
X154710D01*
G01X142700Y428600D02*
Y424600D01*
X150100D01*
G01X155509Y443877D02*
X153009D01*
Y444918D01*
X153134Y445252D01*
X153301Y445460D01*
X153634Y445543D01*
X153967Y445460D01*
X154176Y445210D01*
X154301Y444918D01*
Y443877D01*
G01Y444918D02*
X155509Y445543D01*
G01X155134Y446893D02*
X155342Y447143D01*
X155467Y447435D01*
X155509Y447810D01*
X155426Y448185D01*
X155259Y448477D01*
X154967Y448685D01*
X154634Y448727D01*
X154301Y448643D01*
X154092Y448435D01*
X153926Y448143D01*
X153884Y447852D01*
X153926Y447560D01*
X154092Y447185D01*
X153009Y447310D01*
Y448435D01*
G01X154467Y450118D02*
X154176Y450410D01*
X154009Y450660D01*
X153926Y450993D01*
X154009Y451285D01*
X154176Y451493D01*
X154426Y451660D01*
X154717Y451702D01*
X154967Y451660D01*
X155217Y451493D01*
X155426Y451243D01*
X155509Y450952D01*
X155426Y450618D01*
X155176Y450327D01*
X154801Y450160D01*
X154384Y450118D01*
X153842Y450202D01*
X153551Y450327D01*
X153259Y450535D01*
X153051Y450827D01*
X153009Y451118D01*
X153092Y451410D01*
X153301Y451618D01*
G01X155509Y454510D02*
X153009D01*
X154801Y452968D01*
Y455052D01*
G01X150900Y428900D02*
X154900D01*
Y436300D01*
G01X151009Y443877D02*
X148509D01*
Y444918D01*
X148634Y445252D01*
X148801Y445460D01*
X149134Y445543D01*
X149467Y445460D01*
X149676Y445210D01*
X149801Y444918D01*
Y443877D01*
G01Y444918D02*
X151009Y445543D01*
G01X150634Y446893D02*
X150842Y447143D01*
X150967Y447435D01*
X151009Y447810D01*
X150926Y448185D01*
X150759Y448477D01*
X150467Y448685D01*
X150134Y448727D01*
X149801Y448643D01*
X149592Y448435D01*
X149426Y448143D01*
X149384Y447852D01*
X149426Y447560D01*
X149592Y447185D01*
X148509Y447310D01*
Y448435D01*
G01X151009Y450910D02*
X150967Y451202D01*
X150842Y451535D01*
X150634Y451743D01*
X150342Y451827D01*
X150051Y451743D01*
X149801Y451493D01*
X149676Y451118D01*
Y450702D01*
X149592Y450452D01*
X149384Y450243D01*
X149092Y450160D01*
X148801Y450285D01*
X148592Y450577D01*
X148509Y450910D01*
X148592Y451243D01*
X148801Y451535D01*
X149092Y451660D01*
X149384Y451577D01*
X149592Y451368D01*
X149676Y451118D01*
Y450702D01*
X149801Y450327D01*
X150051Y450077D01*
X150342Y449993D01*
X150634Y450077D01*
X150842Y450285D01*
X150967Y450618D01*
X151009Y450910D01*
G01Y454010D02*
X148509D01*
X149009Y453510D01*
G01X151009D02*
Y454510D01*
G01X150400Y436300D02*
X146400D01*
Y428900D01*
G01X117117Y461000D02*
Y463500D01*
X118158D01*
X118492Y463375D01*
X118700Y463208D01*
X118783Y462875D01*
X118700Y462542D01*
X118450Y462333D01*
X118158Y462208D01*
X117117D01*
G01X118158D02*
X118783Y461000D01*
G01X121550D02*
Y463500D01*
X120008Y461708D01*
X122092D01*
G01X124150Y461000D02*
Y463500D01*
X123650Y463000D01*
G01Y461000D02*
X124650D01*
G01X126333Y461375D02*
X126583Y461167D01*
X126875Y461042D01*
X127250Y461000D01*
X127625Y461083D01*
X127917Y461250D01*
X128125Y461542D01*
X128167Y461875D01*
X128083Y462208D01*
X127875Y462417D01*
X127583Y462583D01*
X127292Y462625D01*
X127000Y462583D01*
X126625Y462417D01*
X126750Y463500D01*
X127875D01*
G01X113800Y456500D02*
Y452500D01*
X121200D01*
G01X117117Y457000D02*
Y459500D01*
X118158D01*
X118492Y459375D01*
X118700Y459208D01*
X118783Y458875D01*
X118700Y458542D01*
X118450Y458333D01*
X118158Y458208D01*
X117117D01*
G01X118158D02*
X118783Y457000D01*
G01X121550D02*
Y459500D01*
X120008Y457708D01*
X122092D01*
G01X124150Y457000D02*
Y459500D01*
X123650Y459000D01*
G01Y457000D02*
X124650D01*
G01X126458Y458042D02*
X126750Y458333D01*
X127000Y458500D01*
X127333Y458583D01*
X127625Y458500D01*
X127833Y458333D01*
X128000Y458083D01*
X128042Y457792D01*
X128000Y457542D01*
X127833Y457292D01*
X127583Y457083D01*
X127292Y457000D01*
X126958Y457083D01*
X126667Y457333D01*
X126500Y457708D01*
X126458Y458125D01*
X126542Y458667D01*
X126667Y458958D01*
X126875Y459250D01*
X127167Y459458D01*
X127458Y459500D01*
X127750Y459417D01*
X127958Y459208D01*
G01X113800Y451500D02*
Y447500D01*
X121200D01*
G01X137167Y441875D02*
X137375Y442208D01*
X137500Y442583D01*
Y442917D01*
X137375Y443250D01*
X137167Y443500D01*
X136875Y443625D01*
X136583Y443542D01*
X136333Y443333D01*
X136167Y442958D01*
X136083Y442458D01*
X135917Y442167D01*
X135625Y442042D01*
X135333Y442125D01*
X135125Y442333D01*
X135000Y442625D01*
Y442917D01*
X135083Y443208D01*
X135292Y443458D01*
G01X137500Y445017D02*
X135000D01*
Y446058D01*
X135125Y446392D01*
X135292Y446600D01*
X135625Y446683D01*
X135958Y446600D01*
X136167Y446350D01*
X136292Y446058D01*
Y445017D01*
G01Y446058D02*
X137500Y446683D01*
G01Y448950D02*
X135000D01*
X135500Y448450D01*
G01X137500D02*
Y449450D01*
G01Y452050D02*
X135000D01*
X135500Y451550D01*
G01X137500D02*
Y452550D01*
G01Y455150D02*
X135000D01*
X135500Y454650D01*
G01X137500D02*
Y455650D01*
G01Y458167D02*
X136958Y458250D01*
X136500Y458375D01*
X136083Y458542D01*
X135625Y458750D01*
X135000Y459083D01*
Y457417D01*
G01X123300Y439100D02*
X127300D01*
Y446500D01*
G01X132667Y441875D02*
X132875Y442208D01*
X133000Y442583D01*
Y442917D01*
X132875Y443250D01*
X132667Y443500D01*
X132375Y443625D01*
X132083Y443542D01*
X131833Y443333D01*
X131667Y442958D01*
X131583Y442458D01*
X131417Y442167D01*
X131125Y442042D01*
X130833Y442125D01*
X130625Y442333D01*
X130500Y442625D01*
Y442917D01*
X130583Y443208D01*
X130792Y443458D01*
G01X133000Y445017D02*
X130500D01*
Y446058D01*
X130625Y446392D01*
X130792Y446600D01*
X131125Y446683D01*
X131458Y446600D01*
X131667Y446350D01*
X131792Y446058D01*
Y445017D01*
G01Y446058D02*
X133000Y446683D01*
G01Y448950D02*
X130500D01*
X131000Y448450D01*
G01X133000D02*
Y449450D01*
G01Y452050D02*
X130500D01*
X131000Y451550D01*
G01X133000D02*
Y452550D01*
G01Y455150D02*
X130500D01*
X131000Y454650D01*
G01X133000D02*
Y455650D01*
G01Y458250D02*
X132958Y458542D01*
X132833Y458875D01*
X132625Y459083D01*
X132333Y459167D01*
X132042Y459083D01*
X131792Y458833D01*
X131667Y458458D01*
Y458042D01*
X131583Y457792D01*
X131375Y457583D01*
X131083Y457500D01*
X130792Y457625D01*
X130583Y457917D01*
X130500Y458250D01*
X130583Y458583D01*
X130792Y458875D01*
X131083Y459000D01*
X131375Y458917D01*
X131583Y458708D01*
X131667Y458458D01*
Y458042D01*
X131792Y457667D01*
X132042Y457417D01*
X132333Y457333D01*
X132625Y457417D01*
X132833Y457625D01*
X132958Y457958D01*
X133000Y458250D01*
G01X122800Y446500D02*
X118800D01*
Y439100D01*
G01X130483Y440000D02*
Y438208D01*
X130650Y437833D01*
X130983Y437583D01*
X131400Y437500D01*
X131817Y437583D01*
X132150Y437833D01*
X132317Y438208D01*
Y440000D01*
G01X133708Y439583D02*
X133958Y439833D01*
X134250Y439958D01*
X134583Y440000D01*
X135000Y439917D01*
X135292Y439708D01*
X135375Y439458D01*
X135333Y439208D01*
X135167Y439000D01*
X134333Y438583D01*
X133958Y438292D01*
X133708Y437875D01*
X133625Y437500D01*
X135375D01*
G01X136808Y439583D02*
X137058Y439833D01*
X137350Y439958D01*
X137683Y440000D01*
X138100Y439917D01*
X138392Y439708D01*
X138475Y439458D01*
X138433Y439208D01*
X138267Y439000D01*
X137433Y438583D01*
X137058Y438292D01*
X136808Y437875D01*
X136725Y437500D01*
X138475D01*
G01X124900Y414800D02*
X126900Y416800D01*
X128900Y414800D01*
G01X132500D02*
Y434000D01*
X121300D01*
Y414800D01*
X132500D01*
G01X171334Y413483D02*
X168834D01*
Y414317D01*
X168959Y414650D01*
X169126Y414900D01*
X169376Y415108D01*
X169667Y415275D01*
X170084Y415317D01*
X170501Y415275D01*
X170792Y415108D01*
X171042Y414900D01*
X171209Y414650D01*
X171334Y414317D01*
Y413483D01*
G01X170834Y416583D02*
X171126Y416833D01*
X171292Y417167D01*
X171334Y417542D01*
X171292Y417875D01*
X171084Y418208D01*
X170834Y418417D01*
X170584Y418458D01*
X170292Y418375D01*
X170084Y418083D01*
X170001Y417792D01*
Y417417D01*
G01Y417792D02*
X169876Y418042D01*
X169667Y418250D01*
X169417Y418333D01*
X169167Y418250D01*
X168959Y418042D01*
X168834Y417667D01*
X168876Y417292D01*
X169042Y416917D01*
G01X171334Y420600D02*
X168834D01*
X169334Y420100D01*
G01X171334D02*
Y421100D01*
G01X162900Y431600D02*
Y415500D01*
G01X155900Y431600D02*
X162900D01*
G01X155900Y415500D02*
Y431600D01*
G01X162900Y415500D02*
X155900D01*
G01X181775Y549400D02*
X182108Y549192D01*
X182483Y549067D01*
X182817D01*
X183150Y549192D01*
X183400Y549400D01*
X183525Y549692D01*
X183442Y549984D01*
X183233Y550234D01*
X182858Y550400D01*
X182358Y550484D01*
X182067Y550650D01*
X181942Y550942D01*
X182025Y551234D01*
X182233Y551442D01*
X182525Y551567D01*
X182817D01*
X183108Y551484D01*
X183358Y551275D01*
G01X184833Y549067D02*
Y551567D01*
X185667D01*
X186000Y551442D01*
X186250Y551275D01*
X186458Y551025D01*
X186625Y550734D01*
X186667Y550317D01*
X186625Y549900D01*
X186458Y549609D01*
X186250Y549359D01*
X186000Y549192D01*
X185667Y549067D01*
X184833D01*
G01X187933D02*
Y551567D01*
X188767D01*
X189100Y551442D01*
X189350Y551275D01*
X189558Y551025D01*
X189725Y550734D01*
X189767Y550317D01*
X189725Y549900D01*
X189558Y549609D01*
X189350Y549359D01*
X189100Y549192D01*
X188767Y549067D01*
X187933D01*
G01X194008D02*
X195050Y551567D01*
X196092Y549067D01*
G01X195717Y549942D02*
X194383D01*
G01X199067Y551359D02*
X198817Y551484D01*
X198525Y551567D01*
X198192D01*
X197817Y551442D01*
X197525Y551234D01*
X197317Y550984D01*
X197150Y550567D01*
X197108Y550192D01*
X197192Y549817D01*
X197317Y549567D01*
X197567Y549317D01*
X197858Y549150D01*
X198150Y549067D01*
X198442D01*
X198733Y549150D01*
X198983Y549275D01*
X199192Y549442D01*
G01X201250Y551567D02*
Y549067D01*
G01X200292Y551567D02*
X202208D01*
G01X204350Y549067D02*
X204642Y549109D01*
X204975Y549234D01*
X205183Y549442D01*
X205267Y549734D01*
X205183Y550025D01*
X204933Y550275D01*
X204558Y550400D01*
X204142D01*
X203892Y550484D01*
X203683Y550692D01*
X203600Y550984D01*
X203725Y551275D01*
X204017Y551484D01*
X204350Y551567D01*
X204683Y551484D01*
X204975Y551275D01*
X205100Y550984D01*
X205017Y550692D01*
X204808Y550484D01*
X204558Y550400D01*
X204142D01*
X203767Y550275D01*
X203517Y550025D01*
X203433Y549734D01*
X203517Y549442D01*
X203725Y549234D01*
X204058Y549109D01*
X204350Y549067D01*
G01X175767Y557959D02*
X175517Y558084D01*
X175225Y558167D01*
X174892D01*
X174517Y558042D01*
X174225Y557834D01*
X174017Y557584D01*
X173850Y557167D01*
X173808Y556792D01*
X173892Y556417D01*
X174017Y556167D01*
X174267Y555917D01*
X174558Y555750D01*
X174850Y555667D01*
X175142D01*
X175433Y555750D01*
X175683Y555875D01*
X175892Y556042D01*
G01X177033Y556167D02*
X177283Y555875D01*
X177617Y555709D01*
X177992Y555667D01*
X178325Y555709D01*
X178658Y555917D01*
X178867Y556167D01*
X178908Y556417D01*
X178825Y556709D01*
X178533Y556917D01*
X178242Y557000D01*
X177867D01*
G01X178242D02*
X178492Y557125D01*
X178700Y557334D01*
X178783Y557584D01*
X178700Y557834D01*
X178492Y558042D01*
X178117Y558167D01*
X177742Y558125D01*
X177367Y557959D01*
G01X181550Y555667D02*
Y558167D01*
X180008Y556375D01*
X182092D01*
G01X184650Y555667D02*
Y558167D01*
X183108Y556375D01*
X185192D01*
G01X146500Y553000D02*
Y567000D01*
G01X133500Y553000D02*
X146500D01*
G01X133500Y567000D02*
Y553000D01*
G01X122400Y548500D02*
X122067Y548542D01*
X121775Y548708D01*
X121525Y548958D01*
X121358Y549250D01*
X121275Y549583D01*
Y549917D01*
X121358Y550250D01*
X121525Y550542D01*
X121775Y550792D01*
X122067Y550958D01*
X122400Y551000D01*
X122733Y550958D01*
X123025Y550792D01*
X123275Y550542D01*
X123442Y550250D01*
X123525Y549917D01*
Y549583D01*
X123442Y549250D01*
X123275Y548958D01*
X123025Y548708D01*
X122733Y548542D01*
X122400Y548500D01*
G01X122733Y549167D02*
X123233Y548500D01*
G01X125417D02*
X125500Y549042D01*
X125625Y549500D01*
X125792Y549917D01*
X126000Y550375D01*
X126333Y551000D01*
X124667D01*
G01X128600D02*
X128267Y550917D01*
X128017Y550708D01*
X127850Y550458D01*
X127725Y550125D01*
X127683Y549750D01*
X127725Y549375D01*
X127850Y549042D01*
X128017Y548792D01*
X128267Y548583D01*
X128600Y548500D01*
X128933Y548583D01*
X129183Y548792D01*
X129350Y549042D01*
X129475Y549375D01*
X129517Y549750D01*
X129475Y550125D01*
X129350Y550458D01*
X129183Y550708D01*
X128933Y550917D01*
X128600Y551000D01*
G01X119000Y567000D02*
Y553000D01*
G01X132000D02*
Y567000D01*
G01X119000Y553000D02*
X132000D01*
G01X183447Y520811D02*
Y523311D01*
X184488D01*
X184822Y523186D01*
X185030Y523019D01*
X185113Y522686D01*
X185030Y522353D01*
X184780Y522144D01*
X184488Y522019D01*
X183447D01*
G01X184488D02*
X185113Y520811D01*
G01X186463Y521311D02*
X186713Y521019D01*
X187047Y520853D01*
X187422Y520811D01*
X187755Y520853D01*
X188088Y521061D01*
X188297Y521311D01*
X188338Y521561D01*
X188255Y521853D01*
X187963Y522061D01*
X187672Y522144D01*
X187297D01*
G01X187672D02*
X187922Y522269D01*
X188130Y522478D01*
X188213Y522728D01*
X188130Y522978D01*
X187922Y523186D01*
X187547Y523311D01*
X187172Y523269D01*
X186797Y523103D01*
G01X189688Y522894D02*
X189938Y523144D01*
X190230Y523269D01*
X190563Y523311D01*
X190980Y523228D01*
X191272Y523019D01*
X191355Y522769D01*
X191313Y522519D01*
X191147Y522311D01*
X190313Y521894D01*
X189938Y521603D01*
X189688Y521186D01*
X189605Y520811D01*
X191355D01*
G01X193580Y523311D02*
X193247Y523228D01*
X192997Y523019D01*
X192830Y522769D01*
X192705Y522436D01*
X192663Y522061D01*
X192705Y521686D01*
X192830Y521353D01*
X192997Y521103D01*
X193247Y520894D01*
X193580Y520811D01*
X193913Y520894D01*
X194163Y521103D01*
X194330Y521353D01*
X194455Y521686D01*
X194497Y522061D01*
X194455Y522436D01*
X194330Y522769D01*
X194163Y523019D01*
X193913Y523228D01*
X193580Y523311D01*
G01X187200Y529000D02*
Y533000D01*
X179800D01*
G01X183447Y516811D02*
Y519311D01*
X184488D01*
X184822Y519186D01*
X185030Y519019D01*
X185113Y518686D01*
X185030Y518353D01*
X184780Y518144D01*
X184488Y518019D01*
X183447D01*
G01X184488D02*
X185113Y516811D01*
G01X186463Y517311D02*
X186713Y517019D01*
X187047Y516853D01*
X187422Y516811D01*
X187755Y516853D01*
X188088Y517061D01*
X188297Y517311D01*
X188338Y517561D01*
X188255Y517853D01*
X187963Y518061D01*
X187672Y518144D01*
X187297D01*
G01X187672D02*
X187922Y518269D01*
X188130Y518478D01*
X188213Y518728D01*
X188130Y518978D01*
X187922Y519186D01*
X187547Y519311D01*
X187172Y519269D01*
X186797Y519103D01*
G01X189688Y518894D02*
X189938Y519144D01*
X190230Y519269D01*
X190563Y519311D01*
X190980Y519228D01*
X191272Y519019D01*
X191355Y518769D01*
X191313Y518519D01*
X191147Y518311D01*
X190313Y517894D01*
X189938Y517603D01*
X189688Y517186D01*
X189605Y516811D01*
X191355D01*
G01X193580D02*
Y519311D01*
X193080Y518811D01*
G01Y516811D02*
X194080D01*
G01X187200Y525000D02*
Y529000D01*
X179800D01*
G01X159967Y523667D02*
Y526167D01*
X161008D01*
X161342Y526042D01*
X161550Y525875D01*
X161633Y525542D01*
X161550Y525209D01*
X161300Y525000D01*
X161008Y524875D01*
X159967D01*
G01X161008D02*
X161633Y523667D01*
G01X163192Y523959D02*
X163483Y523750D01*
X163817Y523667D01*
X164150Y523750D01*
X164442Y524000D01*
X164650Y524375D01*
X164733Y524750D01*
Y525209D01*
X164650Y525584D01*
X164442Y525917D01*
X164192Y526084D01*
X163900Y526167D01*
X163567Y526084D01*
X163317Y525917D01*
X163150Y525667D01*
X163067Y525334D01*
X163150Y525042D01*
X163358Y524750D01*
X163608Y524584D01*
X163900Y524542D01*
X164233Y524625D01*
X164483Y524834D01*
X164733Y525209D01*
G01X167000Y523667D02*
X167292Y523709D01*
X167625Y523834D01*
X167833Y524042D01*
X167917Y524334D01*
X167833Y524625D01*
X167583Y524875D01*
X167208Y525000D01*
X166792D01*
X166542Y525084D01*
X166333Y525292D01*
X166250Y525584D01*
X166375Y525875D01*
X166667Y526084D01*
X167000Y526167D01*
X167333Y526084D01*
X167625Y525875D01*
X167750Y525584D01*
X167667Y525292D01*
X167458Y525084D01*
X167208Y525000D01*
X166792D01*
X166417Y524875D01*
X166167Y524625D01*
X166083Y524334D01*
X166167Y524042D01*
X166375Y523834D01*
X166708Y523709D01*
X167000Y523667D01*
G01X169183Y524167D02*
X169433Y523875D01*
X169767Y523709D01*
X170142Y523667D01*
X170475Y523709D01*
X170808Y523917D01*
X171017Y524167D01*
X171058Y524417D01*
X170975Y524709D01*
X170683Y524917D01*
X170392Y525000D01*
X170017D01*
G01X170392D02*
X170642Y525125D01*
X170850Y525334D01*
X170933Y525584D01*
X170850Y525834D01*
X170642Y526042D01*
X170267Y526167D01*
X169892Y526125D01*
X169517Y525959D01*
G01X172283Y524042D02*
X172533Y523834D01*
X172825Y523709D01*
X173200Y523667D01*
X173575Y523750D01*
X173867Y523917D01*
X174075Y524209D01*
X174117Y524542D01*
X174033Y524875D01*
X173825Y525084D01*
X173533Y525250D01*
X173242Y525292D01*
X172950Y525250D01*
X172575Y525084D01*
X172700Y526167D01*
X173825D01*
G01X165300Y558330D02*
Y554330D01*
X172700D01*
G01X138800Y533267D02*
X136300D01*
Y534308D01*
X136425Y534642D01*
X136592Y534850D01*
X136925Y534933D01*
X137258Y534850D01*
X137467Y534600D01*
X137592Y534308D01*
Y533267D01*
G01Y534308D02*
X138800Y534933D01*
G01X138508Y536492D02*
X138717Y536783D01*
X138800Y537117D01*
X138717Y537450D01*
X138467Y537742D01*
X138092Y537950D01*
X137717Y538033D01*
X137258D01*
X136883Y537950D01*
X136550Y537742D01*
X136383Y537492D01*
X136300Y537200D01*
X136383Y536867D01*
X136550Y536617D01*
X136800Y536450D01*
X137133Y536367D01*
X137425Y536450D01*
X137717Y536658D01*
X137883Y536908D01*
X137925Y537200D01*
X137842Y537533D01*
X137633Y537783D01*
X137258Y538033D01*
G01X138800Y540300D02*
X138758Y540592D01*
X138633Y540925D01*
X138425Y541133D01*
X138133Y541217D01*
X137842Y541133D01*
X137592Y540883D01*
X137467Y540508D01*
Y540092D01*
X137383Y539842D01*
X137175Y539633D01*
X136883Y539550D01*
X136592Y539675D01*
X136383Y539967D01*
X136300Y540300D01*
X136383Y540633D01*
X136592Y540925D01*
X136883Y541050D01*
X137175Y540967D01*
X137383Y540758D01*
X137467Y540508D01*
Y540092D01*
X137592Y539717D01*
X137842Y539467D01*
X138133Y539383D01*
X138425Y539467D01*
X138633Y539675D01*
X138758Y540008D01*
X138800Y540300D01*
G01X138300Y542483D02*
X138592Y542733D01*
X138758Y543067D01*
X138800Y543442D01*
X138758Y543775D01*
X138550Y544108D01*
X138300Y544317D01*
X138050Y544358D01*
X137758Y544275D01*
X137550Y543983D01*
X137467Y543692D01*
Y543317D01*
G01Y543692D02*
X137342Y543942D01*
X137133Y544150D01*
X136883Y544233D01*
X136633Y544150D01*
X136425Y543942D01*
X136300Y543567D01*
X136342Y543192D01*
X136508Y542817D01*
G01X137758Y545708D02*
X137467Y546000D01*
X137300Y546250D01*
X137217Y546583D01*
X137300Y546875D01*
X137467Y547083D01*
X137717Y547250D01*
X138008Y547292D01*
X138258Y547250D01*
X138508Y547083D01*
X138717Y546833D01*
X138800Y546542D01*
X138717Y546208D01*
X138467Y545917D01*
X138092Y545750D01*
X137675Y545708D01*
X137133Y545792D01*
X136842Y545917D01*
X136550Y546125D01*
X136342Y546417D01*
X136300Y546708D01*
X136383Y547000D01*
X136592Y547208D01*
G01X148000Y539300D02*
X152000D01*
Y546700D01*
G01X146300Y532867D02*
X143800D01*
Y533908D01*
X143925Y534242D01*
X144092Y534450D01*
X144425Y534533D01*
X144758Y534450D01*
X144967Y534200D01*
X145092Y533908D01*
Y532867D01*
G01Y533908D02*
X146300Y534533D01*
G01X146008Y536092D02*
X146217Y536383D01*
X146300Y536717D01*
X146217Y537050D01*
X145967Y537342D01*
X145592Y537550D01*
X145217Y537633D01*
X144758D01*
X144383Y537550D01*
X144050Y537342D01*
X143883Y537092D01*
X143800Y536800D01*
X143883Y536467D01*
X144050Y536217D01*
X144300Y536050D01*
X144633Y535967D01*
X144925Y536050D01*
X145217Y536258D01*
X145383Y536508D01*
X145425Y536800D01*
X145342Y537133D01*
X145133Y537383D01*
X144758Y537633D01*
G01X146008Y539192D02*
X146217Y539483D01*
X146300Y539817D01*
X146217Y540150D01*
X145967Y540442D01*
X145592Y540650D01*
X145217Y540733D01*
X144758D01*
X144383Y540650D01*
X144050Y540442D01*
X143883Y540192D01*
X143800Y539900D01*
X143883Y539567D01*
X144050Y539317D01*
X144300Y539150D01*
X144633Y539067D01*
X144925Y539150D01*
X145217Y539358D01*
X145383Y539608D01*
X145425Y539900D01*
X145342Y540233D01*
X145133Y540483D01*
X144758Y540733D01*
G01X144217Y542208D02*
X143967Y542458D01*
X143842Y542750D01*
X143800Y543083D01*
X143883Y543500D01*
X144092Y543792D01*
X144342Y543875D01*
X144592Y543833D01*
X144800Y543667D01*
X145217Y542833D01*
X145508Y542458D01*
X145925Y542208D01*
X146300Y542125D01*
Y543875D01*
G01X143800Y546100D02*
X143883Y545767D01*
X144092Y545517D01*
X144342Y545350D01*
X144675Y545225D01*
X145050Y545183D01*
X145425Y545225D01*
X145758Y545350D01*
X146008Y545517D01*
X146217Y545767D01*
X146300Y546100D01*
X146217Y546433D01*
X146008Y546683D01*
X145758Y546850D01*
X145425Y546975D01*
X145050Y547017D01*
X144675Y546975D01*
X144342Y546850D01*
X144092Y546683D01*
X143883Y546433D01*
X143800Y546100D01*
G01X152500Y539300D02*
X156500D01*
Y546700D01*
G01X160467Y527667D02*
Y530167D01*
X161508D01*
X161842Y530042D01*
X162050Y529875D01*
X162133Y529542D01*
X162050Y529209D01*
X161800Y529000D01*
X161508Y528875D01*
X160467D01*
G01X161508D02*
X162133Y527667D01*
G01X163692Y527959D02*
X163983Y527750D01*
X164317Y527667D01*
X164650Y527750D01*
X164942Y528000D01*
X165150Y528375D01*
X165233Y528750D01*
Y529209D01*
X165150Y529584D01*
X164942Y529917D01*
X164692Y530084D01*
X164400Y530167D01*
X164067Y530084D01*
X163817Y529917D01*
X163650Y529667D01*
X163567Y529334D01*
X163650Y529042D01*
X163858Y528750D01*
X164108Y528584D01*
X164400Y528542D01*
X164733Y528625D01*
X164983Y528834D01*
X165233Y529209D01*
G01X166792Y527959D02*
X167083Y527750D01*
X167417Y527667D01*
X167750Y527750D01*
X168042Y528000D01*
X168250Y528375D01*
X168333Y528750D01*
Y529209D01*
X168250Y529584D01*
X168042Y529917D01*
X167792Y530084D01*
X167500Y530167D01*
X167167Y530084D01*
X166917Y529917D01*
X166750Y529667D01*
X166667Y529334D01*
X166750Y529042D01*
X166958Y528750D01*
X167208Y528584D01*
X167500Y528542D01*
X167833Y528625D01*
X168083Y528834D01*
X168333Y529209D01*
G01X171100Y527667D02*
Y530167D01*
X169558Y528375D01*
X171642D01*
G01X174200Y527667D02*
Y530167D01*
X172658Y528375D01*
X174742D01*
G01X148000Y530800D02*
X150500D01*
G01X148000Y529842D02*
Y531758D01*
G01X150500Y533067D02*
X148000D01*
Y534067D01*
X148125Y534400D01*
X148417Y534650D01*
X148750Y534733D01*
X149083Y534650D01*
X149333Y534442D01*
X149458Y534067D01*
Y533067D01*
G01X150125Y536083D02*
X150333Y536333D01*
X150458Y536625D01*
X150500Y537000D01*
X150417Y537375D01*
X150250Y537667D01*
X149958Y537875D01*
X149625Y537917D01*
X149292Y537833D01*
X149083Y537625D01*
X148917Y537333D01*
X148875Y537042D01*
X148917Y536750D01*
X149083Y536375D01*
X148000Y536500D01*
Y537625D01*
G01X162483Y521666D02*
Y519874D01*
X162650Y519499D01*
X162983Y519249D01*
X163400Y519166D01*
X163817Y519249D01*
X164150Y519499D01*
X164317Y519874D01*
Y521666D01*
G01X165583Y519541D02*
X165833Y519333D01*
X166125Y519208D01*
X166500Y519166D01*
X166875Y519249D01*
X167167Y519416D01*
X167375Y519708D01*
X167417Y520041D01*
X167333Y520374D01*
X167125Y520583D01*
X166833Y520749D01*
X166542Y520791D01*
X166250Y520749D01*
X165875Y520583D01*
X166000Y521666D01*
X167125D01*
G01X169600Y519166D02*
Y521666D01*
X169100Y521166D01*
G01Y519166D02*
X170100D01*
G01X169228Y539057D02*
X177228D01*
Y551007D01*
X169228D01*
Y539057D01*
G01X175378Y551007D02*
X173378Y549007D01*
X171378Y551007D01*
G01X158500Y566700D02*
Y553300D01*
G01X148500D02*
Y566700D01*
G01X158500Y553300D02*
X148500D01*
G01X134167Y587467D02*
Y589967D01*
X135167D01*
X135500Y589842D01*
X135750Y589550D01*
X135833Y589217D01*
X135750Y588884D01*
X135542Y588634D01*
X135167Y588509D01*
X134167D01*
G01X138933Y587467D02*
X137267D01*
Y589967D01*
X138933D01*
G01X138267Y588759D02*
X137267D01*
G01X141533Y588800D02*
X141700Y588925D01*
X141825Y589134D01*
X141908Y589425D01*
X141825Y589675D01*
X141658Y589842D01*
X141367Y589967D01*
X140242D01*
Y587467D01*
X141617D01*
X141908Y587634D01*
X142075Y587884D01*
X142158Y588175D01*
X142075Y588467D01*
X141825Y588717D01*
X141533Y588800D01*
X140242D01*
G01X146358Y587467D02*
X147400Y589967D01*
X148442Y587467D01*
G01X148067Y588342D02*
X146733D01*
G01X150500Y589967D02*
Y587467D01*
G01X149542Y589967D02*
X151458D01*
G01X153600D02*
Y587467D01*
G01X152642Y589967D02*
X154558D01*
G01X155742Y587467D02*
Y589967D01*
X157658Y587467D01*
Y589967D01*
G01X159800Y587467D02*
X160092Y587509D01*
X160425Y587634D01*
X160633Y587842D01*
X160717Y588134D01*
X160633Y588425D01*
X160383Y588675D01*
X160008Y588800D01*
X159592D01*
X159342Y588884D01*
X159133Y589092D01*
X159050Y589384D01*
X159175Y589675D01*
X159467Y589884D01*
X159800Y589967D01*
X160133Y589884D01*
X160425Y589675D01*
X160550Y589384D01*
X160467Y589092D01*
X160258Y588884D01*
X160008Y588800D01*
X159592D01*
X159217Y588675D01*
X158967Y588425D01*
X158883Y588134D01*
X158967Y587842D01*
X159175Y587634D01*
X159508Y587509D01*
X159800Y587467D01*
G01X209308Y591329D02*
X180408D01*
Y578429D01*
X162108D01*
Y591329D01*
X148608D01*
Y752529D01*
X162108D01*
Y765429D01*
X180408D01*
Y752529D01*
X209308D01*
Y742179D01*
X202608D01*
Y601679D01*
X209308D01*
Y591329D01*
G01X173517Y562166D02*
Y559666D01*
X175183D01*
G01X178283D02*
X176617D01*
Y562166D01*
X178283D01*
G01X177617Y560958D02*
X176617D01*
G01X179633Y559666D02*
Y562166D01*
X180467D01*
X180800Y562041D01*
X181050Y561874D01*
X181258Y561624D01*
X181425Y561333D01*
X181467Y560916D01*
X181425Y560499D01*
X181258Y560208D01*
X181050Y559958D01*
X180800Y559791D01*
X180467Y559666D01*
X179633D01*
G01X183650D02*
X183942Y559708D01*
X184275Y559833D01*
X184483Y560041D01*
X184567Y560333D01*
X184483Y560624D01*
X184233Y560874D01*
X183858Y560999D01*
X183442D01*
X183192Y561083D01*
X182983Y561291D01*
X182900Y561583D01*
X183025Y561874D01*
X183317Y562083D01*
X183650Y562166D01*
X183983Y562083D01*
X184275Y561874D01*
X184400Y561583D01*
X184317Y561291D01*
X184108Y561083D01*
X183858Y560999D01*
X183442D01*
X183067Y560874D01*
X182817Y560624D01*
X182733Y560333D01*
X182817Y560041D01*
X183025Y559833D01*
X183358Y559708D01*
X183650Y559666D01*
G01X165560Y563523D02*
Y571123D01*
X176960D01*
Y563523D01*
X165560D01*
G01X142717Y582292D02*
X142467Y582417D01*
X142175Y582500D01*
X141842D01*
X141467Y582375D01*
X141175Y582167D01*
X140967Y581917D01*
X140800Y581500D01*
X140758Y581125D01*
X140842Y580750D01*
X140967Y580500D01*
X141217Y580250D01*
X141508Y580083D01*
X141800Y580000D01*
X142092D01*
X142383Y580083D01*
X142633Y580208D01*
X142842Y580375D01*
G01X144192Y580292D02*
X144483Y580083D01*
X144817Y580000D01*
X145150Y580083D01*
X145442Y580333D01*
X145650Y580708D01*
X145733Y581083D01*
Y581542D01*
X145650Y581917D01*
X145442Y582250D01*
X145192Y582417D01*
X144900Y582500D01*
X144567Y582417D01*
X144317Y582250D01*
X144150Y582000D01*
X144067Y581667D01*
X144150Y581375D01*
X144358Y581083D01*
X144608Y580917D01*
X144900Y580875D01*
X145233Y580958D01*
X145483Y581167D01*
X145733Y581542D01*
G01X147083Y580375D02*
X147333Y580167D01*
X147625Y580042D01*
X148000Y580000D01*
X148375Y580083D01*
X148667Y580250D01*
X148875Y580542D01*
X148917Y580875D01*
X148833Y581208D01*
X148625Y581417D01*
X148333Y581583D01*
X148042Y581625D01*
X147750Y581583D01*
X147375Y581417D01*
X147500Y582500D01*
X148625D01*
G01X150308Y582083D02*
X150558Y582333D01*
X150850Y582458D01*
X151183Y582500D01*
X151600Y582417D01*
X151892Y582208D01*
X151975Y581958D01*
X151933Y581708D01*
X151767Y581500D01*
X150933Y581083D01*
X150558Y580792D01*
X150308Y580375D01*
X150225Y580000D01*
X151975D01*
G01X153408Y581042D02*
X153700Y581333D01*
X153950Y581500D01*
X154283Y581583D01*
X154575Y581500D01*
X154783Y581333D01*
X154950Y581083D01*
X154992Y580792D01*
X154950Y580542D01*
X154783Y580292D01*
X154533Y580083D01*
X154242Y580000D01*
X153908Y580083D01*
X153617Y580333D01*
X153450Y580708D01*
X153408Y581125D01*
X153492Y581667D01*
X153617Y581958D01*
X153825Y582250D01*
X154117Y582458D01*
X154408Y582500D01*
X154700Y582417D01*
X154908Y582208D01*
G01X138900Y568500D02*
X138567Y568542D01*
X138275Y568708D01*
X138025Y568958D01*
X137858Y569250D01*
X137775Y569583D01*
Y569917D01*
X137858Y570250D01*
X138025Y570542D01*
X138275Y570792D01*
X138567Y570958D01*
X138900Y571000D01*
X139233Y570958D01*
X139525Y570792D01*
X139775Y570542D01*
X139942Y570250D01*
X140025Y569917D01*
Y569583D01*
X139942Y569250D01*
X139775Y568958D01*
X139525Y568708D01*
X139233Y568542D01*
X138900Y568500D01*
G01X139233Y569167D02*
X139733Y568500D01*
G01X141208Y569542D02*
X141500Y569833D01*
X141750Y570000D01*
X142083Y570083D01*
X142375Y570000D01*
X142583Y569833D01*
X142750Y569583D01*
X142792Y569292D01*
X142750Y569042D01*
X142583Y568792D01*
X142333Y568583D01*
X142042Y568500D01*
X141708Y568583D01*
X141417Y568833D01*
X141250Y569208D01*
X141208Y569625D01*
X141292Y570167D01*
X141417Y570458D01*
X141625Y570750D01*
X141917Y570958D01*
X142208Y571000D01*
X142500Y570917D01*
X142708Y570708D01*
G01X144392Y568792D02*
X144683Y568583D01*
X145017Y568500D01*
X145350Y568583D01*
X145642Y568833D01*
X145850Y569208D01*
X145933Y569583D01*
Y570042D01*
X145850Y570417D01*
X145642Y570750D01*
X145392Y570917D01*
X145100Y571000D01*
X144767Y570917D01*
X144517Y570750D01*
X144350Y570500D01*
X144267Y570167D01*
X144350Y569875D01*
X144558Y569583D01*
X144808Y569417D01*
X145100Y569375D01*
X145433Y569458D01*
X145683Y569667D01*
X145933Y570042D01*
G01X146500Y567000D02*
X133500D01*
G01X132000D02*
X119000D01*
G01X183667Y586400D02*
Y588900D01*
X184708D01*
X185042Y588775D01*
X185250Y588608D01*
X185333Y588275D01*
X185250Y587942D01*
X185000Y587733D01*
X184708Y587608D01*
X183667D01*
G01X184708D02*
X185333Y586400D01*
G01X186892Y586692D02*
X187183Y586483D01*
X187517Y586400D01*
X187850Y586483D01*
X188142Y586733D01*
X188350Y587108D01*
X188433Y587483D01*
Y587942D01*
X188350Y588317D01*
X188142Y588650D01*
X187892Y588817D01*
X187600Y588900D01*
X187267Y588817D01*
X187017Y588650D01*
X186850Y588400D01*
X186767Y588067D01*
X186850Y587775D01*
X187058Y587483D01*
X187308Y587317D01*
X187600Y587275D01*
X187933Y587358D01*
X188183Y587567D01*
X188433Y587942D01*
G01X191200Y586400D02*
Y588900D01*
X189658Y587108D01*
X191742D01*
G01X193008Y588483D02*
X193258Y588733D01*
X193550Y588858D01*
X193883Y588900D01*
X194300Y588817D01*
X194592Y588608D01*
X194675Y588358D01*
X194633Y588108D01*
X194467Y587900D01*
X193633Y587483D01*
X193258Y587192D01*
X193008Y586775D01*
X192925Y586400D01*
X194675D01*
G01X196900D02*
X197192Y586442D01*
X197525Y586567D01*
X197733Y586775D01*
X197817Y587067D01*
X197733Y587358D01*
X197483Y587608D01*
X197108Y587733D01*
X196692D01*
X196442Y587817D01*
X196233Y588025D01*
X196150Y588317D01*
X196275Y588608D01*
X196567Y588817D01*
X196900Y588900D01*
X197233Y588817D01*
X197525Y588608D01*
X197650Y588317D01*
X197567Y588025D01*
X197358Y587817D01*
X197108Y587733D01*
X196692D01*
X196317Y587608D01*
X196067Y587358D01*
X195983Y587067D01*
X196067Y586775D01*
X196275Y586567D01*
X196608Y586442D01*
X196900Y586400D01*
G01X117167Y568875D02*
X117375Y569208D01*
X117500Y569583D01*
Y569917D01*
X117375Y570250D01*
X117167Y570500D01*
X116875Y570625D01*
X116583Y570542D01*
X116333Y570333D01*
X116167Y569958D01*
X116083Y569458D01*
X115917Y569167D01*
X115625Y569042D01*
X115333Y569125D01*
X115125Y569333D01*
X115000Y569625D01*
Y569917D01*
X115083Y570208D01*
X115292Y570458D01*
G01X117500Y572017D02*
X115000D01*
Y573058D01*
X115125Y573392D01*
X115292Y573600D01*
X115625Y573683D01*
X115958Y573600D01*
X116167Y573350D01*
X116292Y573058D01*
Y572017D01*
G01Y573058D02*
X117500Y573683D01*
G01Y575950D02*
X115000D01*
X115500Y575450D01*
G01X117500D02*
Y576450D01*
G01Y579050D02*
X115000D01*
X115500Y578550D01*
G01X117500D02*
Y579550D01*
G01X117000Y581233D02*
X117292Y581483D01*
X117458Y581817D01*
X117500Y582192D01*
X117458Y582525D01*
X117250Y582858D01*
X117000Y583067D01*
X116750Y583108D01*
X116458Y583025D01*
X116250Y582733D01*
X116167Y582442D01*
Y582067D01*
G01Y582442D02*
X116042Y582692D01*
X115833Y582900D01*
X115583Y582983D01*
X115333Y582900D01*
X115125Y582692D01*
X115000Y582317D01*
X115042Y581942D01*
X115208Y581567D01*
G01X117500Y585167D02*
X116958Y585250D01*
X116500Y585375D01*
X116083Y585542D01*
X115625Y585750D01*
X115000Y586083D01*
Y584417D01*
G01X124025Y575075D02*
X120025D01*
Y567675D01*
G01X183667Y578400D02*
Y580900D01*
X184708D01*
X185042Y580775D01*
X185250Y580608D01*
X185333Y580275D01*
X185250Y579942D01*
X185000Y579733D01*
X184708Y579608D01*
X183667D01*
G01X184708D02*
X185333Y578400D01*
G01X186892Y578692D02*
X187183Y578483D01*
X187517Y578400D01*
X187850Y578483D01*
X188142Y578733D01*
X188350Y579108D01*
X188433Y579483D01*
Y579942D01*
X188350Y580317D01*
X188142Y580650D01*
X187892Y580817D01*
X187600Y580900D01*
X187267Y580817D01*
X187017Y580650D01*
X186850Y580400D01*
X186767Y580067D01*
X186850Y579775D01*
X187058Y579483D01*
X187308Y579317D01*
X187600Y579275D01*
X187933Y579358D01*
X188183Y579567D01*
X188433Y579942D01*
G01X189992Y578692D02*
X190283Y578483D01*
X190617Y578400D01*
X190950Y578483D01*
X191242Y578733D01*
X191450Y579108D01*
X191533Y579483D01*
Y579942D01*
X191450Y580317D01*
X191242Y580650D01*
X190992Y580817D01*
X190700Y580900D01*
X190367Y580817D01*
X190117Y580650D01*
X189950Y580400D01*
X189867Y580067D01*
X189950Y579775D01*
X190158Y579483D01*
X190408Y579317D01*
X190700Y579275D01*
X191033Y579358D01*
X191283Y579567D01*
X191533Y579942D01*
G01X193800Y580900D02*
X193467Y580817D01*
X193217Y580608D01*
X193050Y580358D01*
X192925Y580025D01*
X192883Y579650D01*
X192925Y579275D01*
X193050Y578942D01*
X193217Y578692D01*
X193467Y578483D01*
X193800Y578400D01*
X194133Y578483D01*
X194383Y578692D01*
X194550Y578942D01*
X194675Y579275D01*
X194717Y579650D01*
X194675Y580025D01*
X194550Y580358D01*
X194383Y580608D01*
X194133Y580817D01*
X193800Y580900D01*
G01X196900D02*
X196567Y580817D01*
X196317Y580608D01*
X196150Y580358D01*
X196025Y580025D01*
X195983Y579650D01*
X196025Y579275D01*
X196150Y578942D01*
X196317Y578692D01*
X196567Y578483D01*
X196900Y578400D01*
X197233Y578483D01*
X197483Y578692D01*
X197650Y578942D01*
X197775Y579275D01*
X197817Y579650D01*
X197775Y580025D01*
X197650Y580358D01*
X197483Y580608D01*
X197233Y580817D01*
X196900Y580900D01*
G01X165295Y562416D02*
Y558416D01*
X172695D01*
G01X159833Y571967D02*
X157333D01*
Y573008D01*
X157458Y573342D01*
X157625Y573550D01*
X157958Y573633D01*
X158291Y573550D01*
X158500Y573300D01*
X158625Y573008D01*
Y571967D01*
G01Y573008D02*
X159833Y573633D01*
G01X159541Y575192D02*
X159750Y575483D01*
X159833Y575817D01*
X159750Y576150D01*
X159500Y576442D01*
X159125Y576650D01*
X158750Y576733D01*
X158291D01*
X157916Y576650D01*
X157583Y576442D01*
X157416Y576192D01*
X157333Y575900D01*
X157416Y575567D01*
X157583Y575317D01*
X157833Y575150D01*
X158166Y575067D01*
X158458Y575150D01*
X158750Y575358D01*
X158916Y575608D01*
X158958Y575900D01*
X158875Y576233D01*
X158666Y576483D01*
X158291Y576733D01*
G01X159541Y578292D02*
X159750Y578583D01*
X159833Y578917D01*
X159750Y579250D01*
X159500Y579542D01*
X159125Y579750D01*
X158750Y579833D01*
X158291D01*
X157916Y579750D01*
X157583Y579542D01*
X157416Y579292D01*
X157333Y579000D01*
X157416Y578667D01*
X157583Y578417D01*
X157833Y578250D01*
X158166Y578167D01*
X158458Y578250D01*
X158750Y578458D01*
X158916Y578708D01*
X158958Y579000D01*
X158875Y579333D01*
X158666Y579583D01*
X158291Y579833D01*
G01X159833Y582600D02*
X157333D01*
X159125Y581058D01*
Y583142D01*
G01X159333Y584283D02*
X159625Y584533D01*
X159791Y584867D01*
X159833Y585242D01*
X159791Y585575D01*
X159583Y585908D01*
X159333Y586117D01*
X159083Y586158D01*
X158791Y586075D01*
X158583Y585783D01*
X158500Y585492D01*
Y585117D01*
G01Y585492D02*
X158375Y585742D01*
X158166Y585950D01*
X157916Y586033D01*
X157666Y585950D01*
X157458Y585742D01*
X157333Y585367D01*
X157375Y584992D01*
X157541Y584617D01*
G01X160144Y569835D02*
X164144D01*
Y577235D01*
G01X183667Y582400D02*
Y584900D01*
X184708D01*
X185042Y584775D01*
X185250Y584608D01*
X185333Y584275D01*
X185250Y583942D01*
X185000Y583733D01*
X184708Y583608D01*
X183667D01*
G01X184708D02*
X185333Y582400D01*
G01X186892Y582692D02*
X187183Y582483D01*
X187517Y582400D01*
X187850Y582483D01*
X188142Y582733D01*
X188350Y583108D01*
X188433Y583483D01*
Y583942D01*
X188350Y584317D01*
X188142Y584650D01*
X187892Y584817D01*
X187600Y584900D01*
X187267Y584817D01*
X187017Y584650D01*
X186850Y584400D01*
X186767Y584067D01*
X186850Y583775D01*
X187058Y583483D01*
X187308Y583317D01*
X187600Y583275D01*
X187933Y583358D01*
X188183Y583567D01*
X188433Y583942D01*
G01X191200Y582400D02*
Y584900D01*
X189658Y583108D01*
X191742D01*
G01X193008Y584483D02*
X193258Y584733D01*
X193550Y584858D01*
X193883Y584900D01*
X194300Y584817D01*
X194592Y584608D01*
X194675Y584358D01*
X194633Y584108D01*
X194467Y583900D01*
X193633Y583483D01*
X193258Y583192D01*
X193008Y582775D01*
X192925Y582400D01*
X194675D01*
G01X196192Y582692D02*
X196483Y582483D01*
X196817Y582400D01*
X197150Y582483D01*
X197442Y582733D01*
X197650Y583108D01*
X197733Y583483D01*
Y583942D01*
X197650Y584317D01*
X197442Y584650D01*
X197192Y584817D01*
X196900Y584900D01*
X196567Y584817D01*
X196317Y584650D01*
X196150Y584400D01*
X196067Y584067D01*
X196150Y583775D01*
X196358Y583483D01*
X196608Y583317D01*
X196900Y583275D01*
X197233Y583358D01*
X197483Y583567D01*
X197733Y583942D01*
G01X141433Y578500D02*
Y576708D01*
X141600Y576333D01*
X141933Y576083D01*
X142350Y576000D01*
X142767Y576083D01*
X143100Y576333D01*
X143267Y576708D01*
Y578500D01*
G01X144658Y578083D02*
X144908Y578333D01*
X145200Y578458D01*
X145533Y578500D01*
X145950Y578417D01*
X146242Y578208D01*
X146325Y577958D01*
X146283Y577708D01*
X146117Y577500D01*
X145283Y577083D01*
X144908Y576792D01*
X144658Y576375D01*
X144575Y576000D01*
X146325D01*
G01X148550Y578500D02*
X148217Y578417D01*
X147967Y578208D01*
X147800Y577958D01*
X147675Y577625D01*
X147633Y577250D01*
X147675Y576875D01*
X147800Y576542D01*
X147967Y576292D01*
X148217Y576083D01*
X148550Y576000D01*
X148883Y576083D01*
X149133Y576292D01*
X149300Y576542D01*
X149425Y576875D01*
X149467Y577250D01*
X149425Y577625D01*
X149300Y577958D01*
X149133Y578208D01*
X148883Y578417D01*
X148550Y578500D01*
G01X150733Y576375D02*
X150983Y576167D01*
X151275Y576042D01*
X151650Y576000D01*
X152025Y576083D01*
X152317Y576250D01*
X152525Y576542D01*
X152567Y576875D01*
X152483Y577208D01*
X152275Y577417D01*
X151983Y577583D01*
X151692Y577625D01*
X151400Y577583D01*
X151025Y577417D01*
X151150Y578500D01*
X152275D01*
G01X148500Y566700D02*
X158500D01*
G01X124154Y703698D02*
X123321Y702365D01*
X122821Y700865D01*
Y699531D01*
X123321Y698198D01*
X124154Y697198D01*
X125321Y696698D01*
X126487Y697031D01*
X127488Y697865D01*
X128154Y699365D01*
X128488Y701365D01*
X129154Y702531D01*
X130321Y703031D01*
X131488Y702698D01*
X132321Y701865D01*
X132821Y700698D01*
Y699531D01*
X132488Y698365D01*
X131654Y697365D01*
G01X124154Y693098D02*
X123321Y691765D01*
X122821Y690265D01*
Y688931D01*
X123321Y687598D01*
X124154Y686598D01*
X125321Y686098D01*
X126487Y686431D01*
X127488Y687265D01*
X128154Y688765D01*
X128488Y690765D01*
X129154Y691931D01*
X130321Y692431D01*
X131488Y692098D01*
X132321Y691265D01*
X132821Y690098D01*
Y688931D01*
X132488Y687765D01*
X131654Y686765D01*
G01X122821Y682665D02*
X132821D01*
Y679331D01*
X132321Y677998D01*
X131654Y676998D01*
X130654Y676165D01*
X129487Y675498D01*
X127821Y675331D01*
X126154Y675498D01*
X124988Y676165D01*
X123987Y676998D01*
X123321Y677998D01*
X122821Y679331D01*
Y682665D01*
G01Y668398D02*
X122988Y667231D01*
X123488Y665898D01*
X124321Y665065D01*
X125488Y664731D01*
X126654Y665065D01*
X127654Y666065D01*
X128154Y667565D01*
Y669231D01*
X128488Y670231D01*
X129321Y671065D01*
X130488Y671398D01*
X131654Y670898D01*
X132488Y669732D01*
X132821Y668398D01*
X132488Y667065D01*
X131654Y665898D01*
X130488Y665398D01*
X129321Y665731D01*
X128488Y666565D01*
X128154Y667565D01*
Y669231D01*
X127654Y670731D01*
X126654Y671731D01*
X125488Y672065D01*
X124321Y671731D01*
X123488Y670898D01*
X122988Y669565D01*
X122821Y668398D01*
G01X145000Y663117D02*
X145250Y663325D01*
X145417Y663575D01*
X145500Y663867D01*
X145417Y664200D01*
X145250Y664450D01*
X145000Y664700D01*
X144667Y664783D01*
X143000D01*
G01X145500Y667050D02*
X145458Y667342D01*
X145333Y667675D01*
X145125Y667883D01*
X144833Y667967D01*
X144542Y667883D01*
X144292Y667633D01*
X144167Y667258D01*
Y666842D01*
X144083Y666592D01*
X143875Y666383D01*
X143583Y666300D01*
X143292Y666425D01*
X143083Y666717D01*
X143000Y667050D01*
X143083Y667383D01*
X143292Y667675D01*
X143583Y667800D01*
X143875Y667717D01*
X144083Y667508D01*
X144167Y667258D01*
Y666842D01*
X144292Y666467D01*
X144542Y666217D01*
X144833Y666133D01*
X145125Y666217D01*
X145333Y666425D01*
X145458Y666758D01*
X145500Y667050D01*
G01X138000Y641917D02*
X135500D01*
Y642917D01*
X135625Y643250D01*
X135917Y643500D01*
X136250Y643583D01*
X136583Y643500D01*
X136833Y643292D01*
X136958Y642917D01*
Y641917D01*
G01X135708Y646767D02*
X135583Y646517D01*
X135500Y646225D01*
Y645892D01*
X135625Y645517D01*
X135833Y645225D01*
X136083Y645017D01*
X136500Y644850D01*
X136875Y644808D01*
X137250Y644892D01*
X137500Y645017D01*
X137750Y645267D01*
X137917Y645558D01*
X138000Y645850D01*
Y646142D01*
X137917Y646433D01*
X137792Y646683D01*
X137625Y646892D01*
G01X138000Y648950D02*
X135500D01*
X136000Y648450D01*
G01X138000D02*
Y649450D01*
G01X135917Y651258D02*
X135667Y651508D01*
X135542Y651800D01*
X135500Y652133D01*
X135583Y652550D01*
X135792Y652842D01*
X136042Y652925D01*
X136292Y652883D01*
X136500Y652717D01*
X136917Y651883D01*
X137208Y651508D01*
X137625Y651258D01*
X138000Y651175D01*
Y652925D01*
G01Y655150D02*
X135500D01*
X136000Y654650D01*
G01X138000D02*
Y655650D01*
G01X137708Y657542D02*
X137917Y657833D01*
X138000Y658167D01*
X137917Y658500D01*
X137667Y658792D01*
X137292Y659000D01*
X136917Y659083D01*
X136458D01*
X136083Y659000D01*
X135750Y658792D01*
X135583Y658542D01*
X135500Y658250D01*
X135583Y657917D01*
X135750Y657667D01*
X136000Y657500D01*
X136333Y657417D01*
X136625Y657500D01*
X136917Y657708D01*
X137083Y657958D01*
X137125Y658250D01*
X137042Y658583D01*
X136833Y658833D01*
X136458Y659083D01*
G01X114000Y637967D02*
X111500D01*
Y639008D01*
X111625Y639342D01*
X111792Y639550D01*
X112125Y639633D01*
X112458Y639550D01*
X112667Y639300D01*
X112792Y639008D01*
Y637967D01*
G01Y639008D02*
X114000Y639633D01*
G01X113708Y641192D02*
X113917Y641483D01*
X114000Y641817D01*
X113917Y642150D01*
X113667Y642442D01*
X113292Y642650D01*
X112917Y642733D01*
X112458D01*
X112083Y642650D01*
X111750Y642442D01*
X111583Y642192D01*
X111500Y641900D01*
X111583Y641567D01*
X111750Y641317D01*
X112000Y641150D01*
X112333Y641067D01*
X112625Y641150D01*
X112917Y641358D01*
X113083Y641608D01*
X113125Y641900D01*
X113042Y642233D01*
X112833Y642483D01*
X112458Y642733D01*
G01X114000Y645000D02*
X113958Y645292D01*
X113833Y645625D01*
X113625Y645833D01*
X113333Y645917D01*
X113042Y645833D01*
X112792Y645583D01*
X112667Y645208D01*
Y644792D01*
X112583Y644542D01*
X112375Y644333D01*
X112083Y644250D01*
X111792Y644375D01*
X111583Y644667D01*
X111500Y645000D01*
X111583Y645333D01*
X111792Y645625D01*
X112083Y645750D01*
X112375Y645667D01*
X112583Y645458D01*
X112667Y645208D01*
Y644792D01*
X112792Y644417D01*
X113042Y644167D01*
X113333Y644083D01*
X113625Y644167D01*
X113833Y644375D01*
X113958Y644708D01*
X114000Y645000D01*
G01X112958Y647308D02*
X112667Y647600D01*
X112500Y647850D01*
X112417Y648183D01*
X112500Y648475D01*
X112667Y648683D01*
X112917Y648850D01*
X113208Y648892D01*
X113458Y648850D01*
X113708Y648683D01*
X113917Y648433D01*
X114000Y648142D01*
X113917Y647808D01*
X113667Y647517D01*
X113292Y647350D01*
X112875Y647308D01*
X112333Y647392D01*
X112042Y647517D01*
X111750Y647725D01*
X111542Y648017D01*
X111500Y648308D01*
X111583Y648600D01*
X111792Y648808D01*
G01X114000Y651200D02*
X113958Y651492D01*
X113833Y651825D01*
X113625Y652033D01*
X113333Y652117D01*
X113042Y652033D01*
X112792Y651783D01*
X112667Y651408D01*
Y650992D01*
X112583Y650742D01*
X112375Y650533D01*
X112083Y650450D01*
X111792Y650575D01*
X111583Y650867D01*
X111500Y651200D01*
X111583Y651533D01*
X111792Y651825D01*
X112083Y651950D01*
X112375Y651867D01*
X112583Y651658D01*
X112667Y651408D01*
Y650992D01*
X112792Y650617D01*
X113042Y650367D01*
X113333Y650283D01*
X113625Y650367D01*
X113833Y650575D01*
X113958Y650908D01*
X114000Y651200D01*
G01X141500Y717217D02*
X139000D01*
Y718217D01*
X139125Y718550D01*
X139417Y718800D01*
X139750Y718883D01*
X140083Y718800D01*
X140333Y718592D01*
X140458Y718217D01*
Y717217D01*
G01X139208Y722067D02*
X139083Y721817D01*
X139000Y721525D01*
Y721192D01*
X139125Y720817D01*
X139333Y720525D01*
X139583Y720317D01*
X140000Y720150D01*
X140375Y720108D01*
X140750Y720192D01*
X141000Y720317D01*
X141250Y720567D01*
X141417Y720858D01*
X141500Y721150D01*
Y721442D01*
X141417Y721733D01*
X141292Y721983D01*
X141125Y722192D01*
G01X141500Y724250D02*
X139000D01*
X139500Y723750D01*
G01X141500D02*
Y724750D01*
G01X139417Y726558D02*
X139167Y726808D01*
X139042Y727100D01*
X139000Y727433D01*
X139083Y727850D01*
X139292Y728142D01*
X139542Y728225D01*
X139792Y728183D01*
X140000Y728017D01*
X140417Y727183D01*
X140708Y726808D01*
X141125Y726558D01*
X141500Y726475D01*
Y728225D01*
G01Y730450D02*
X139000D01*
X139500Y729950D01*
G01X141500D02*
Y730950D01*
G01Y733550D02*
X141458Y733842D01*
X141333Y734175D01*
X141125Y734383D01*
X140833Y734467D01*
X140542Y734383D01*
X140292Y734133D01*
X140167Y733758D01*
Y733342D01*
X140083Y733092D01*
X139875Y732883D01*
X139583Y732800D01*
X139292Y732925D01*
X139083Y733217D01*
X139000Y733550D01*
X139083Y733883D01*
X139292Y734175D01*
X139583Y734300D01*
X139875Y734217D01*
X140083Y734008D01*
X140167Y733758D01*
Y733342D01*
X140292Y732967D01*
X140542Y732717D01*
X140833Y732633D01*
X141125Y732717D01*
X141333Y732925D01*
X141458Y733258D01*
X141500Y733550D01*
G01X155900Y755017D02*
X153400D01*
Y756017D01*
X153525Y756350D01*
X153817Y756600D01*
X154150Y756683D01*
X154483Y756600D01*
X154733Y756392D01*
X154858Y756017D01*
Y755017D01*
G01X153608Y759867D02*
X153483Y759617D01*
X153400Y759325D01*
Y758992D01*
X153525Y758617D01*
X153733Y758325D01*
X153983Y758117D01*
X154400Y757950D01*
X154775Y757908D01*
X155150Y757992D01*
X155400Y758117D01*
X155650Y758367D01*
X155817Y758658D01*
X155900Y758950D01*
Y759242D01*
X155817Y759533D01*
X155692Y759783D01*
X155525Y759992D01*
G01X155900Y762050D02*
X153400D01*
X153900Y761550D01*
G01X155900D02*
Y762550D01*
G01X153817Y764358D02*
X153567Y764608D01*
X153442Y764900D01*
X153400Y765233D01*
X153483Y765650D01*
X153692Y765942D01*
X153942Y766025D01*
X154192Y765983D01*
X154400Y765817D01*
X154817Y764983D01*
X155108Y764608D01*
X155525Y764358D01*
X155900Y764275D01*
Y766025D01*
G01Y768250D02*
X153400D01*
X153900Y767750D01*
G01X155900D02*
Y768750D01*
G01Y771267D02*
X155358Y771350D01*
X154900Y771475D01*
X154483Y771642D01*
X154025Y771850D01*
X153400Y772183D01*
Y770517D01*
G01X130500Y772900D02*
Y785900D01*
G01X116500Y772900D02*
X130500D01*
G01X116500Y785900D02*
Y772900D01*
G01X117117Y716321D02*
Y718821D01*
X118158D01*
X118492Y718696D01*
X118700Y718529D01*
X118783Y718196D01*
X118700Y717863D01*
X118450Y717654D01*
X118158Y717529D01*
X117117D01*
G01X118158D02*
X118783Y716321D01*
G01X121550D02*
Y718821D01*
X120008Y717029D01*
X122092D01*
G01X124150Y718821D02*
X123817Y718738D01*
X123567Y718529D01*
X123400Y718279D01*
X123275Y717946D01*
X123233Y717571D01*
X123275Y717196D01*
X123400Y716863D01*
X123567Y716613D01*
X123817Y716404D01*
X124150Y716321D01*
X124483Y716404D01*
X124733Y716613D01*
X124900Y716863D01*
X125025Y717196D01*
X125067Y717571D01*
X125025Y717946D01*
X124900Y718279D01*
X124733Y718529D01*
X124483Y718738D01*
X124150Y718821D01*
G01X126333Y716821D02*
X126583Y716529D01*
X126917Y716363D01*
X127292Y716321D01*
X127625Y716363D01*
X127958Y716571D01*
X128167Y716821D01*
X128208Y717071D01*
X128125Y717363D01*
X127833Y717571D01*
X127542Y717654D01*
X127167D01*
G01X127542D02*
X127792Y717779D01*
X128000Y717988D01*
X128083Y718238D01*
X128000Y718488D01*
X127792Y718696D01*
X127417Y718821D01*
X127042Y718779D01*
X126667Y718613D01*
G01X130200Y724500D02*
Y728500D01*
X122800D01*
G01X116917Y720500D02*
Y723000D01*
X117958D01*
X118292Y722875D01*
X118500Y722708D01*
X118583Y722375D01*
X118500Y722042D01*
X118250Y721833D01*
X117958Y721708D01*
X116917D01*
G01X117958D02*
X118583Y720500D01*
G01X121350D02*
Y723000D01*
X119808Y721208D01*
X121892D01*
G01X123950Y723000D02*
X123617Y722917D01*
X123367Y722708D01*
X123200Y722458D01*
X123075Y722125D01*
X123033Y721750D01*
X123075Y721375D01*
X123200Y721042D01*
X123367Y720792D01*
X123617Y720583D01*
X123950Y720500D01*
X124283Y720583D01*
X124533Y720792D01*
X124700Y721042D01*
X124825Y721375D01*
X124867Y721750D01*
X124825Y722125D01*
X124700Y722458D01*
X124533Y722708D01*
X124283Y722917D01*
X123950Y723000D01*
G01X127550Y720500D02*
Y723000D01*
X126008Y721208D01*
X128092D01*
G01X130200Y729500D02*
Y733500D01*
X122800D01*
G01X111650Y773950D02*
X115650D01*
Y781350D01*
G01X119945Y742617D02*
X115945D01*
Y735217D01*
G01X120445D02*
X124445D01*
Y742617D01*
G01X120183Y770300D02*
Y768508D01*
X120350Y768133D01*
X120683Y767883D01*
X121100Y767800D01*
X121517Y767883D01*
X121850Y768133D01*
X122017Y768508D01*
Y770300D01*
G01X124200Y767800D02*
Y770300D01*
X123700Y769800D01*
G01Y767800D02*
X124700D01*
G01X127217D02*
X127300Y768342D01*
X127425Y768800D01*
X127592Y769217D01*
X127800Y769675D01*
X128133Y770300D01*
X126467D01*
G01X119200Y766300D02*
X117200Y764300D01*
X115200Y766300D01*
G01X111600D02*
Y747100D01*
X122800D01*
Y766300D01*
X111600D01*
G01X182800Y768900D02*
Y781900D01*
G01X156800Y768900D02*
X182800D01*
G01X156800Y781900D02*
Y768900D01*
G01X151900Y755017D02*
X149400D01*
Y756017D01*
X149525Y756350D01*
X149817Y756600D01*
X150150Y756683D01*
X150483Y756600D01*
X150733Y756392D01*
X150858Y756017D01*
Y755017D01*
G01X149608Y759867D02*
X149483Y759617D01*
X149400Y759325D01*
Y758992D01*
X149525Y758617D01*
X149733Y758325D01*
X149983Y758117D01*
X150400Y757950D01*
X150775Y757908D01*
X151150Y757992D01*
X151400Y758117D01*
X151650Y758367D01*
X151817Y758658D01*
X151900Y758950D01*
Y759242D01*
X151817Y759533D01*
X151692Y759783D01*
X151525Y759992D01*
G01X151900Y762050D02*
X149400D01*
X149900Y761550D01*
G01X151900D02*
Y762550D01*
G01X149817Y764358D02*
X149567Y764608D01*
X149442Y764900D01*
X149400Y765233D01*
X149483Y765650D01*
X149692Y765942D01*
X149942Y766025D01*
X150192Y765983D01*
X150400Y765817D01*
X150817Y764983D01*
X151108Y764608D01*
X151525Y764358D01*
X151900Y764275D01*
Y766025D01*
G01Y768250D02*
X149400D01*
X149900Y767750D01*
G01X151900D02*
Y768750D01*
G01X151525Y770433D02*
X151733Y770683D01*
X151858Y770975D01*
X151900Y771350D01*
X151817Y771725D01*
X151650Y772017D01*
X151358Y772225D01*
X151025Y772267D01*
X150692Y772183D01*
X150483Y771975D01*
X150317Y771683D01*
X150275Y771392D01*
X150317Y771100D01*
X150483Y770725D01*
X149400Y770850D01*
Y771975D01*
G01X143050Y774550D02*
Y755850D01*
X132750D01*
Y774550D01*
X143050D01*
G01X133800Y717417D02*
X131300D01*
Y718417D01*
X131425Y718750D01*
X131717Y719000D01*
X132050Y719083D01*
X132383Y719000D01*
X132633Y718792D01*
X132758Y718417D01*
Y717417D01*
G01X131508Y722267D02*
X131383Y722017D01*
X131300Y721725D01*
Y721392D01*
X131425Y721017D01*
X131633Y720725D01*
X131883Y720517D01*
X132300Y720350D01*
X132675Y720308D01*
X133050Y720392D01*
X133300Y720517D01*
X133550Y720767D01*
X133717Y721058D01*
X133800Y721350D01*
Y721642D01*
X133717Y721933D01*
X133592Y722183D01*
X133425Y722392D01*
G01X133800Y724450D02*
X131300D01*
X131800Y723950D01*
G01X133800D02*
Y724950D01*
G01X131717Y726758D02*
X131467Y727008D01*
X131342Y727300D01*
X131300Y727633D01*
X131383Y728050D01*
X131592Y728342D01*
X131842Y728425D01*
X132092Y728383D01*
X132300Y728217D01*
X132717Y727383D01*
X133008Y727008D01*
X133425Y726758D01*
X133800Y726675D01*
Y728425D01*
G01Y730650D02*
X131300D01*
X131800Y730150D01*
G01X133800D02*
Y731150D01*
G01X132758Y732958D02*
X132467Y733250D01*
X132300Y733500D01*
X132217Y733833D01*
X132300Y734125D01*
X132467Y734333D01*
X132717Y734500D01*
X133008Y734542D01*
X133258Y734500D01*
X133508Y734333D01*
X133717Y734083D01*
X133800Y733792D01*
X133717Y733458D01*
X133467Y733167D01*
X133092Y733000D01*
X132675Y732958D01*
X132133Y733042D01*
X131842Y733167D01*
X131550Y733375D01*
X131342Y733667D01*
X131300Y733958D01*
X131383Y734250D01*
X131592Y734458D01*
G01X132650Y736250D02*
Y754950D01*
X142950D01*
Y736250D01*
X132650D01*
G01X166700Y830200D02*
X166658Y829867D01*
X166492Y829575D01*
X166242Y829325D01*
X165950Y829158D01*
X165617Y829075D01*
X165283D01*
X164950Y829158D01*
X164658Y829325D01*
X164408Y829575D01*
X164242Y829867D01*
X164200Y830200D01*
X164242Y830533D01*
X164408Y830825D01*
X164658Y831075D01*
X164950Y831242D01*
X165283Y831325D01*
X165617D01*
X165950Y831242D01*
X166242Y831075D01*
X166492Y830825D01*
X166658Y830533D01*
X166700Y830200D01*
G01X166033Y830533D02*
X166700Y831033D01*
G01X164617Y832508D02*
X164367Y832758D01*
X164242Y833050D01*
X164200Y833383D01*
X164283Y833800D01*
X164492Y834092D01*
X164742Y834175D01*
X164992Y834133D01*
X165200Y833967D01*
X165617Y833133D01*
X165908Y832758D01*
X166325Y832508D01*
X166700Y832425D01*
Y834175D01*
G01X164200Y836400D02*
X164283Y836067D01*
X164492Y835817D01*
X164742Y835650D01*
X165075Y835525D01*
X165450Y835483D01*
X165825Y835525D01*
X166158Y835650D01*
X166408Y835817D01*
X166617Y836067D01*
X166700Y836400D01*
X166617Y836733D01*
X166408Y836983D01*
X166158Y837150D01*
X165825Y837275D01*
X165450Y837317D01*
X165075Y837275D01*
X164742Y837150D01*
X164492Y836983D01*
X164283Y836733D01*
X164200Y836400D01*
G01X141900Y829100D02*
Y815100D01*
G01X154900Y829100D02*
X141900D01*
G01X154900Y815100D02*
Y829100D01*
G01X141900Y815100D02*
X154900D01*
G01X124400Y787000D02*
X124067Y787042D01*
X123775Y787208D01*
X123525Y787458D01*
X123358Y787750D01*
X123275Y788083D01*
Y788417D01*
X123358Y788750D01*
X123525Y789042D01*
X123775Y789292D01*
X124067Y789458D01*
X124400Y789500D01*
X124733Y789458D01*
X125025Y789292D01*
X125275Y789042D01*
X125442Y788750D01*
X125525Y788417D01*
Y788083D01*
X125442Y787750D01*
X125275Y787458D01*
X125025Y787208D01*
X124733Y787042D01*
X124400Y787000D01*
G01X124733Y787667D02*
X125233Y787000D01*
G01X126708Y788042D02*
X127000Y788333D01*
X127250Y788500D01*
X127583Y788583D01*
X127875Y788500D01*
X128083Y788333D01*
X128250Y788083D01*
X128292Y787792D01*
X128250Y787542D01*
X128083Y787292D01*
X127833Y787083D01*
X127542Y787000D01*
X127208Y787083D01*
X126917Y787333D01*
X126750Y787708D01*
X126708Y788125D01*
X126792Y788667D01*
X126917Y788958D01*
X127125Y789250D01*
X127417Y789458D01*
X127708Y789500D01*
X128000Y789417D01*
X128208Y789208D01*
G01X130517Y787000D02*
X130600Y787542D01*
X130725Y788000D01*
X130892Y788417D01*
X131100Y788875D01*
X131433Y789500D01*
X129767D01*
G01X130500Y785900D02*
X116500D01*
G01X115900Y793000D02*
X115567Y793042D01*
X115275Y793208D01*
X115025Y793458D01*
X114858Y793750D01*
X114775Y794083D01*
Y794417D01*
X114858Y794750D01*
X115025Y795042D01*
X115275Y795292D01*
X115567Y795458D01*
X115900Y795500D01*
X116233Y795458D01*
X116525Y795292D01*
X116775Y795042D01*
X116942Y794750D01*
X117025Y794417D01*
Y794083D01*
X116942Y793750D01*
X116775Y793458D01*
X116525Y793208D01*
X116233Y793042D01*
X115900Y793000D01*
G01X116233Y793667D02*
X116733Y793000D01*
G01X119000D02*
X119292Y793042D01*
X119625Y793167D01*
X119833Y793375D01*
X119917Y793667D01*
X119833Y793958D01*
X119583Y794208D01*
X119208Y794333D01*
X118792D01*
X118542Y794417D01*
X118333Y794625D01*
X118250Y794917D01*
X118375Y795208D01*
X118667Y795417D01*
X119000Y795500D01*
X119333Y795417D01*
X119625Y795208D01*
X119750Y794917D01*
X119667Y794625D01*
X119458Y794417D01*
X119208Y794333D01*
X118792D01*
X118417Y794208D01*
X118167Y793958D01*
X118083Y793667D01*
X118167Y793375D01*
X118375Y793167D01*
X118708Y793042D01*
X119000Y793000D01*
G01X121308Y794042D02*
X121600Y794333D01*
X121850Y794500D01*
X122183Y794583D01*
X122475Y794500D01*
X122683Y794333D01*
X122850Y794083D01*
X122892Y793792D01*
X122850Y793542D01*
X122683Y793292D01*
X122433Y793083D01*
X122142Y793000D01*
X121808Y793083D01*
X121517Y793333D01*
X121350Y793708D01*
X121308Y794125D01*
X121392Y794667D01*
X121517Y794958D01*
X121725Y795250D01*
X122017Y795458D01*
X122308Y795500D01*
X122600Y795417D01*
X122808Y795208D01*
G01X113500Y800600D02*
X127500D01*
G01X113500Y813600D02*
Y800600D01*
G01X127500Y813600D02*
X113500D01*
G01X127500Y800600D02*
Y813600D01*
G01X145400Y793000D02*
X145067Y793042D01*
X144775Y793208D01*
X144525Y793458D01*
X144358Y793750D01*
X144275Y794083D01*
Y794417D01*
X144358Y794750D01*
X144525Y795042D01*
X144775Y795292D01*
X145067Y795458D01*
X145400Y795500D01*
X145733Y795458D01*
X146025Y795292D01*
X146275Y795042D01*
X146442Y794750D01*
X146525Y794417D01*
Y794083D01*
X146442Y793750D01*
X146275Y793458D01*
X146025Y793208D01*
X145733Y793042D01*
X145400Y793000D01*
G01X145733Y793667D02*
X146233Y793000D01*
G01X148500D02*
X148792Y793042D01*
X149125Y793167D01*
X149333Y793375D01*
X149417Y793667D01*
X149333Y793958D01*
X149083Y794208D01*
X148708Y794333D01*
X148292D01*
X148042Y794417D01*
X147833Y794625D01*
X147750Y794917D01*
X147875Y795208D01*
X148167Y795417D01*
X148500Y795500D01*
X148833Y795417D01*
X149125Y795208D01*
X149250Y794917D01*
X149167Y794625D01*
X148958Y794417D01*
X148708Y794333D01*
X148292D01*
X147917Y794208D01*
X147667Y793958D01*
X147583Y793667D01*
X147667Y793375D01*
X147875Y793167D01*
X148208Y793042D01*
X148500Y793000D01*
G01X151517D02*
X151600Y793542D01*
X151725Y794000D01*
X151892Y794417D01*
X152100Y794875D01*
X152433Y795500D01*
X150767D01*
G01X133000Y800600D02*
X147000D01*
G01X133000Y813600D02*
Y800600D01*
G01X147000Y813600D02*
X133000D01*
G01X147000Y800600D02*
Y813600D01*
G01X142417Y844100D02*
Y846600D01*
X143458D01*
X143792Y846475D01*
X144000Y846308D01*
X144083Y845975D01*
X144000Y845642D01*
X143750Y845433D01*
X143458Y845308D01*
X142417D01*
G01X143458D02*
X144083Y844100D01*
G01X146350D02*
Y846600D01*
X145850Y846100D01*
G01Y844100D02*
X146850D01*
G01X148533Y844475D02*
X148783Y844267D01*
X149075Y844142D01*
X149450Y844100D01*
X149825Y844183D01*
X150117Y844350D01*
X150325Y844642D01*
X150367Y844975D01*
X150283Y845308D01*
X150075Y845517D01*
X149783Y845683D01*
X149492Y845725D01*
X149200Y845683D01*
X148825Y845517D01*
X148950Y846600D01*
X150075D01*
G01X152550D02*
X152217Y846517D01*
X151967Y846308D01*
X151800Y846058D01*
X151675Y845725D01*
X151633Y845350D01*
X151675Y844975D01*
X151800Y844642D01*
X151967Y844392D01*
X152217Y844183D01*
X152550Y844100D01*
X152883Y844183D01*
X153133Y844392D01*
X153300Y844642D01*
X153425Y844975D01*
X153467Y845350D01*
X153425Y845725D01*
X153300Y846058D01*
X153133Y846308D01*
X152883Y846517D01*
X152550Y846600D01*
G01X142700Y834100D02*
Y830100D01*
X150100D01*
G01X150900Y834400D02*
X154900D01*
Y841800D01*
G01X150400D02*
X146400D01*
Y834400D01*
G01X171100Y811267D02*
X168600D01*
Y812308D01*
X168725Y812642D01*
X168892Y812850D01*
X169225Y812933D01*
X169558Y812850D01*
X169767Y812600D01*
X169892Y812308D01*
Y811267D01*
G01Y812308D02*
X171100Y812933D01*
G01X170808Y814492D02*
X171017Y814783D01*
X171100Y815117D01*
X171017Y815450D01*
X170767Y815742D01*
X170392Y815950D01*
X170017Y816033D01*
X169558D01*
X169183Y815950D01*
X168850Y815742D01*
X168683Y815492D01*
X168600Y815200D01*
X168683Y814867D01*
X168850Y814617D01*
X169100Y814450D01*
X169433Y814367D01*
X169725Y814450D01*
X170017Y814658D01*
X170183Y814908D01*
X170225Y815200D01*
X170142Y815533D01*
X169933Y815783D01*
X169558Y816033D01*
G01X171100Y818217D02*
X170558Y818300D01*
X170100Y818425D01*
X169683Y818592D01*
X169225Y818800D01*
X168600Y819133D01*
Y817467D01*
G01X170725Y820483D02*
X170933Y820733D01*
X171058Y821025D01*
X171100Y821400D01*
X171017Y821775D01*
X170850Y822067D01*
X170558Y822275D01*
X170225Y822317D01*
X169892Y822233D01*
X169683Y822025D01*
X169517Y821733D01*
X169475Y821442D01*
X169517Y821150D01*
X169683Y820775D01*
X168600Y820900D01*
Y822025D01*
G01X170600Y823583D02*
X170892Y823833D01*
X171058Y824167D01*
X171100Y824542D01*
X171058Y824875D01*
X170850Y825208D01*
X170600Y825417D01*
X170350Y825458D01*
X170058Y825375D01*
X169850Y825083D01*
X169767Y824792D01*
Y824417D01*
G01Y824792D02*
X169642Y825042D01*
X169433Y825250D01*
X169183Y825333D01*
X168933Y825250D01*
X168725Y825042D01*
X168600Y824667D01*
X168642Y824292D01*
X168808Y823917D01*
G01X156000Y813700D02*
X152000D01*
Y806300D01*
G01X167100Y811267D02*
X164600D01*
Y812308D01*
X164725Y812642D01*
X164892Y812850D01*
X165225Y812933D01*
X165558Y812850D01*
X165767Y812600D01*
X165892Y812308D01*
Y811267D01*
G01Y812308D02*
X167100Y812933D01*
G01X166808Y814492D02*
X167017Y814783D01*
X167100Y815117D01*
X167017Y815450D01*
X166767Y815742D01*
X166392Y815950D01*
X166017Y816033D01*
X165558D01*
X165183Y815950D01*
X164850Y815742D01*
X164683Y815492D01*
X164600Y815200D01*
X164683Y814867D01*
X164850Y814617D01*
X165100Y814450D01*
X165433Y814367D01*
X165725Y814450D01*
X166017Y814658D01*
X166183Y814908D01*
X166225Y815200D01*
X166142Y815533D01*
X165933Y815783D01*
X165558Y816033D01*
G01X167100Y818217D02*
X166558Y818300D01*
X166100Y818425D01*
X165683Y818592D01*
X165225Y818800D01*
X164600Y819133D01*
Y817467D01*
G01X167100Y821317D02*
X166558Y821400D01*
X166100Y821525D01*
X165683Y821692D01*
X165225Y821900D01*
X164600Y822233D01*
Y820567D01*
G01X165017Y823708D02*
X164767Y823958D01*
X164642Y824250D01*
X164600Y824583D01*
X164683Y825000D01*
X164892Y825292D01*
X165142Y825375D01*
X165392Y825333D01*
X165600Y825167D01*
X166017Y824333D01*
X166308Y823958D01*
X166725Y823708D01*
X167100Y823625D01*
Y825375D01*
G01X147500Y806300D02*
X151500D01*
Y813700D01*
G01X174800Y815067D02*
X172300D01*
Y816108D01*
X172425Y816442D01*
X172592Y816650D01*
X172925Y816733D01*
X173258Y816650D01*
X173467Y816400D01*
X173592Y816108D01*
Y815067D01*
G01Y816108D02*
X174800Y816733D01*
G01X174508Y818292D02*
X174717Y818583D01*
X174800Y818917D01*
X174717Y819250D01*
X174467Y819542D01*
X174092Y819750D01*
X173717Y819833D01*
X173258D01*
X172883Y819750D01*
X172550Y819542D01*
X172383Y819292D01*
X172300Y819000D01*
X172383Y818667D01*
X172550Y818417D01*
X172800Y818250D01*
X173133Y818167D01*
X173425Y818250D01*
X173717Y818458D01*
X173883Y818708D01*
X173925Y819000D01*
X173842Y819333D01*
X173633Y819583D01*
X173258Y819833D01*
G01X174800Y822100D02*
X174758Y822392D01*
X174633Y822725D01*
X174425Y822933D01*
X174133Y823017D01*
X173842Y822933D01*
X173592Y822683D01*
X173467Y822308D01*
Y821892D01*
X173383Y821642D01*
X173175Y821433D01*
X172883Y821350D01*
X172592Y821475D01*
X172383Y821767D01*
X172300Y822100D01*
X172383Y822433D01*
X172592Y822725D01*
X172883Y822850D01*
X173175Y822767D01*
X173383Y822558D01*
X173467Y822308D01*
Y821892D01*
X173592Y821517D01*
X173842Y821267D01*
X174133Y821183D01*
X174425Y821267D01*
X174633Y821475D01*
X174758Y821808D01*
X174800Y822100D01*
G01X174425Y824283D02*
X174633Y824533D01*
X174758Y824825D01*
X174800Y825200D01*
X174717Y825575D01*
X174550Y825867D01*
X174258Y826075D01*
X173925Y826117D01*
X173592Y826033D01*
X173383Y825825D01*
X173217Y825533D01*
X173175Y825242D01*
X173217Y824950D01*
X173383Y824575D01*
X172300Y824700D01*
Y825825D01*
G01X174508Y827592D02*
X174717Y827883D01*
X174800Y828217D01*
X174717Y828550D01*
X174467Y828842D01*
X174092Y829050D01*
X173717Y829133D01*
X173258D01*
X172883Y829050D01*
X172550Y828842D01*
X172383Y828592D01*
X172300Y828300D01*
X172383Y827967D01*
X172550Y827717D01*
X172800Y827550D01*
X173133Y827467D01*
X173425Y827550D01*
X173717Y827758D01*
X173883Y828008D01*
X173925Y828300D01*
X173842Y828633D01*
X173633Y828883D01*
X173258Y829133D01*
G01X160500Y809700D02*
X156500D01*
Y802300D01*
G01X126467Y792700D02*
Y795200D01*
X127508D01*
X127842Y795075D01*
X128050Y794908D01*
X128133Y794575D01*
X128050Y794242D01*
X127800Y794033D01*
X127508Y793908D01*
X126467D01*
G01X127508D02*
X128133Y792700D01*
G01X129692Y792992D02*
X129983Y792783D01*
X130317Y792700D01*
X130650Y792783D01*
X130942Y793033D01*
X131150Y793408D01*
X131233Y793783D01*
Y794242D01*
X131150Y794617D01*
X130942Y794950D01*
X130692Y795117D01*
X130400Y795200D01*
X130067Y795117D01*
X129817Y794950D01*
X129650Y794700D01*
X129567Y794367D01*
X129650Y794075D01*
X129858Y793783D01*
X130108Y793617D01*
X130400Y793575D01*
X130733Y793658D01*
X130983Y793867D01*
X131233Y794242D01*
G01X133500Y792700D02*
X133792Y792742D01*
X134125Y792867D01*
X134333Y793075D01*
X134417Y793367D01*
X134333Y793658D01*
X134083Y793908D01*
X133708Y794033D01*
X133292D01*
X133042Y794117D01*
X132833Y794325D01*
X132750Y794617D01*
X132875Y794908D01*
X133167Y795117D01*
X133500Y795200D01*
X133833Y795117D01*
X134125Y794908D01*
X134250Y794617D01*
X134167Y794325D01*
X133958Y794117D01*
X133708Y794033D01*
X133292D01*
X132917Y793908D01*
X132667Y793658D01*
X132583Y793367D01*
X132667Y793075D01*
X132875Y792867D01*
X133208Y792742D01*
X133500Y792700D01*
G01X135808Y793742D02*
X136100Y794033D01*
X136350Y794200D01*
X136683Y794283D01*
X136975Y794200D01*
X137183Y794033D01*
X137350Y793783D01*
X137392Y793492D01*
X137350Y793242D01*
X137183Y792992D01*
X136933Y792783D01*
X136642Y792700D01*
X136308Y792783D01*
X136017Y793033D01*
X135850Y793408D01*
X135808Y793825D01*
X135892Y794367D01*
X136017Y794658D01*
X136225Y794950D01*
X136517Y795158D01*
X136808Y795200D01*
X137100Y795117D01*
X137308Y794908D01*
G01X139700Y795200D02*
X139367Y795117D01*
X139117Y794908D01*
X138950Y794658D01*
X138825Y794325D01*
X138783Y793950D01*
X138825Y793575D01*
X138950Y793242D01*
X139117Y792992D01*
X139367Y792783D01*
X139700Y792700D01*
X140033Y792783D01*
X140283Y792992D01*
X140450Y793242D01*
X140575Y793575D01*
X140617Y793950D01*
X140575Y794325D01*
X140450Y794658D01*
X140283Y794908D01*
X140033Y795117D01*
X139700Y795200D01*
G01X132350Y812550D02*
X128350D01*
Y805150D01*
G01X124800Y843600D02*
X128800D01*
Y851000D01*
G01X124251Y850946D02*
X120251D01*
Y843546D01*
G01X136417Y785600D02*
Y788100D01*
X137458D01*
X137792Y787975D01*
X138000Y787808D01*
X138083Y787475D01*
X138000Y787142D01*
X137750Y786933D01*
X137458Y786808D01*
X136417D01*
G01X137458D02*
X138083Y785600D01*
G01X139642Y785892D02*
X139933Y785683D01*
X140267Y785600D01*
X140600Y785683D01*
X140892Y785933D01*
X141100Y786308D01*
X141183Y786683D01*
Y787142D01*
X141100Y787517D01*
X140892Y787850D01*
X140642Y788017D01*
X140350Y788100D01*
X140017Y788017D01*
X139767Y787850D01*
X139600Y787600D01*
X139517Y787267D01*
X139600Y786975D01*
X139808Y786683D01*
X140058Y786517D01*
X140350Y786475D01*
X140683Y786558D01*
X140933Y786767D01*
X141183Y787142D01*
G01X143450Y785600D02*
X143742Y785642D01*
X144075Y785767D01*
X144283Y785975D01*
X144367Y786267D01*
X144283Y786558D01*
X144033Y786808D01*
X143658Y786933D01*
X143242D01*
X142992Y787017D01*
X142783Y787225D01*
X142700Y787517D01*
X142825Y787808D01*
X143117Y788017D01*
X143450Y788100D01*
X143783Y788017D01*
X144075Y787808D01*
X144200Y787517D01*
X144117Y787225D01*
X143908Y787017D01*
X143658Y786933D01*
X143242D01*
X142867Y786808D01*
X142617Y786558D01*
X142533Y786267D01*
X142617Y785975D01*
X142825Y785767D01*
X143158Y785642D01*
X143450Y785600D01*
G01X145633Y786100D02*
X145883Y785808D01*
X146217Y785642D01*
X146592Y785600D01*
X146925Y785642D01*
X147258Y785850D01*
X147467Y786100D01*
X147508Y786350D01*
X147425Y786642D01*
X147133Y786850D01*
X146842Y786933D01*
X146467D01*
G01X146842D02*
X147092Y787058D01*
X147300Y787267D01*
X147383Y787517D01*
X147300Y787767D01*
X147092Y787975D01*
X146717Y788100D01*
X146342Y788058D01*
X145967Y787892D01*
G01X148858Y787683D02*
X149108Y787933D01*
X149400Y788058D01*
X149733Y788100D01*
X150150Y788017D01*
X150442Y787808D01*
X150525Y787558D01*
X150483Y787308D01*
X150317Y787100D01*
X149483Y786683D01*
X149108Y786392D01*
X148858Y785975D01*
X148775Y785600D01*
X150525D01*
G01X149600Y777100D02*
X144400D01*
G01X149600Y784100D02*
X141800D01*
G01X149600Y777100D02*
Y784100D01*
G01X136200Y777100D02*
X144900D01*
G01X136200Y784100D02*
Y777100D01*
G01X142600Y784100D02*
X136200D01*
G01X132383Y845600D02*
Y843808D01*
X132550Y843433D01*
X132883Y843183D01*
X133300Y843100D01*
X133717Y843183D01*
X134050Y843433D01*
X134217Y843808D01*
Y845600D01*
G01X135608Y845183D02*
X135858Y845433D01*
X136150Y845558D01*
X136483Y845600D01*
X136900Y845517D01*
X137192Y845308D01*
X137275Y845058D01*
X137233Y844808D01*
X137067Y844600D01*
X136233Y844183D01*
X135858Y843892D01*
X135608Y843475D01*
X135525Y843100D01*
X137275D01*
G01X139500D02*
Y845600D01*
X139000Y845100D01*
G01Y843100D02*
X140000D01*
G01X124900Y820300D02*
X126900Y822300D01*
X128900Y820300D01*
G01X132500D02*
Y839500D01*
X121300D01*
Y820300D01*
X132500D01*
G01X165367Y784500D02*
Y787000D01*
X166408D01*
X166742Y786875D01*
X166950Y786708D01*
X167033Y786375D01*
X166950Y786042D01*
X166700Y785833D01*
X166408Y785708D01*
X165367D01*
G01X166408D02*
X167033Y784500D01*
G01X168592Y784792D02*
X168883Y784583D01*
X169217Y784500D01*
X169550Y784583D01*
X169842Y784833D01*
X170050Y785208D01*
X170133Y785583D01*
Y786042D01*
X170050Y786417D01*
X169842Y786750D01*
X169592Y786917D01*
X169300Y787000D01*
X168967Y786917D01*
X168717Y786750D01*
X168550Y786500D01*
X168467Y786167D01*
X168550Y785875D01*
X168758Y785583D01*
X169008Y785417D01*
X169300Y785375D01*
X169633Y785458D01*
X169883Y785667D01*
X170133Y786042D01*
G01X171608Y786583D02*
X171858Y786833D01*
X172150Y786958D01*
X172483Y787000D01*
X172900Y786917D01*
X173192Y786708D01*
X173275Y786458D01*
X173233Y786208D01*
X173067Y786000D01*
X172233Y785583D01*
X171858Y785292D01*
X171608Y784875D01*
X171525Y784500D01*
X173275D01*
G01X176000D02*
Y787000D01*
X174458Y785208D01*
X176542D01*
G01X178517Y784500D02*
X178600Y785042D01*
X178725Y785500D01*
X178892Y785917D01*
X179100Y786375D01*
X179433Y787000D01*
X177767D01*
G01X182800Y781900D02*
X156800D01*
G01X170834Y829483D02*
X168334D01*
Y830317D01*
X168459Y830650D01*
X168626Y830900D01*
X168876Y831108D01*
X169167Y831275D01*
X169584Y831317D01*
X170001Y831275D01*
X170292Y831108D01*
X170542Y830900D01*
X170709Y830650D01*
X170834Y830317D01*
Y829483D01*
G01X170334Y832583D02*
X170626Y832833D01*
X170792Y833167D01*
X170834Y833542D01*
X170792Y833875D01*
X170584Y834208D01*
X170334Y834417D01*
X170084Y834458D01*
X169792Y834375D01*
X169584Y834083D01*
X169501Y833792D01*
Y833417D01*
G01Y833792D02*
X169376Y834042D01*
X169167Y834250D01*
X168917Y834333D01*
X168667Y834250D01*
X168459Y834042D01*
X168334Y833667D01*
X168376Y833292D01*
X168542Y832917D01*
G01X168334Y836600D02*
X168417Y836267D01*
X168626Y836017D01*
X168876Y835850D01*
X169209Y835725D01*
X169584Y835683D01*
X169959Y835725D01*
X170292Y835850D01*
X170542Y836017D01*
X170751Y836267D01*
X170834Y836600D01*
X170751Y836933D01*
X170542Y837183D01*
X170292Y837350D01*
X169959Y837475D01*
X169584Y837517D01*
X169209Y837475D01*
X168876Y837350D01*
X168626Y837183D01*
X168417Y836933D01*
X168334Y836600D01*
G01X162900Y837100D02*
Y821000D01*
G01X155900Y837100D02*
X162900D01*
G01X155900Y821000D02*
Y837100D01*
G01X162900Y821000D02*
X155900D01*
G01X117665Y921900D02*
X116832Y920567D01*
X116332Y919067D01*
Y917733D01*
X116832Y916400D01*
X117665Y915400D01*
X118832Y914900D01*
X119998Y915233D01*
X120999Y916067D01*
X121665Y917567D01*
X121999Y919567D01*
X122665Y920733D01*
X123832Y921233D01*
X124999Y920900D01*
X125832Y920067D01*
X126332Y918900D01*
Y917733D01*
X125999Y916567D01*
X125165Y915567D01*
G01X117665Y911300D02*
X116832Y909967D01*
X116332Y908467D01*
Y907133D01*
X116832Y905800D01*
X117665Y904800D01*
X118832Y904300D01*
X119998Y904633D01*
X120999Y905467D01*
X121665Y906967D01*
X121999Y908967D01*
X122665Y910133D01*
X123832Y910633D01*
X124999Y910300D01*
X125832Y909467D01*
X126332Y908300D01*
Y907133D01*
X125999Y905967D01*
X125165Y904967D01*
G01X116332Y900867D02*
X126332D01*
Y897533D01*
X125832Y896200D01*
X125165Y895200D01*
X124165Y894367D01*
X122998Y893700D01*
X121332Y893533D01*
X119665Y893700D01*
X118499Y894367D01*
X117498Y895200D01*
X116832Y896200D01*
X116332Y897533D01*
Y900867D01*
G01Y886600D02*
X126332D01*
X124332Y888600D01*
G01X116332D02*
Y884600D01*
G01X124665Y879167D02*
X125665Y878167D01*
X126165Y877000D01*
X126332Y875667D01*
X125999Y874000D01*
X125165Y872833D01*
X124165Y872500D01*
X123165Y872667D01*
X122332Y873333D01*
X120665Y876667D01*
X119499Y878167D01*
X117832Y879167D01*
X116332Y879500D01*
Y872500D01*
G01X144508Y851047D02*
X144383Y850797D01*
X144300Y850505D01*
Y850172D01*
X144425Y849797D01*
X144633Y849505D01*
X144883Y849297D01*
X145300Y849130D01*
X145675Y849088D01*
X146050Y849172D01*
X146300Y849297D01*
X146550Y849547D01*
X146717Y849838D01*
X146800Y850130D01*
Y850422D01*
X146717Y850713D01*
X146592Y850963D01*
X146425Y851172D01*
G01X146300Y852313D02*
X146592Y852563D01*
X146758Y852897D01*
X146800Y853272D01*
X146758Y853605D01*
X146550Y853938D01*
X146300Y854147D01*
X146050Y854188D01*
X145758Y854105D01*
X145550Y853813D01*
X145467Y853522D01*
Y853147D01*
G01Y853522D02*
X145342Y853772D01*
X145133Y853980D01*
X144883Y854063D01*
X144633Y853980D01*
X144425Y853772D01*
X144300Y853397D01*
X144342Y853022D01*
X144508Y852647D01*
G01X146508Y855622D02*
X146717Y855913D01*
X146800Y856247D01*
X146717Y856580D01*
X146467Y856872D01*
X146092Y857080D01*
X145717Y857163D01*
X145258D01*
X144883Y857080D01*
X144550Y856872D01*
X144383Y856622D01*
X144300Y856330D01*
X144383Y855997D01*
X144550Y855747D01*
X144800Y855580D01*
X145133Y855497D01*
X145425Y855580D01*
X145717Y855788D01*
X145883Y856038D01*
X145925Y856330D01*
X145842Y856663D01*
X145633Y856913D01*
X145258Y857163D01*
G01X146800Y859930D02*
X144300D01*
X146092Y858388D01*
Y860472D01*
G01X154800Y849297D02*
X152300D01*
Y850338D01*
X152425Y850672D01*
X152592Y850880D01*
X152925Y850963D01*
X153258Y850880D01*
X153467Y850630D01*
X153592Y850338D01*
Y849297D01*
G01Y850338D02*
X154800Y850963D01*
G01X154425Y852313D02*
X154633Y852563D01*
X154758Y852855D01*
X154800Y853230D01*
X154717Y853605D01*
X154550Y853897D01*
X154258Y854105D01*
X153925Y854147D01*
X153592Y854063D01*
X153383Y853855D01*
X153217Y853563D01*
X153175Y853272D01*
X153217Y852980D01*
X153383Y852605D01*
X152300Y852730D01*
Y853855D01*
G01X153758Y855538D02*
X153467Y855830D01*
X153300Y856080D01*
X153217Y856413D01*
X153300Y856705D01*
X153467Y856913D01*
X153717Y857080D01*
X154008Y857122D01*
X154258Y857080D01*
X154508Y856913D01*
X154717Y856663D01*
X154800Y856372D01*
X154717Y856038D01*
X154467Y855747D01*
X154092Y855580D01*
X153675Y855538D01*
X153133Y855622D01*
X152842Y855747D01*
X152550Y855955D01*
X152342Y856247D01*
X152300Y856538D01*
X152383Y856830D01*
X152592Y857038D01*
G01X154300Y858513D02*
X154592Y858763D01*
X154758Y859097D01*
X154800Y859472D01*
X154758Y859805D01*
X154550Y860138D01*
X154300Y860347D01*
X154050Y860388D01*
X153758Y860305D01*
X153550Y860013D01*
X153467Y859722D01*
Y859347D01*
G01Y859722D02*
X153342Y859972D01*
X153133Y860180D01*
X152883Y860263D01*
X152633Y860180D01*
X152425Y859972D01*
X152300Y859597D01*
X152342Y859222D01*
X152508Y858847D01*
G01X150800Y849297D02*
X148300D01*
Y850338D01*
X148425Y850672D01*
X148592Y850880D01*
X148925Y850963D01*
X149258Y850880D01*
X149467Y850630D01*
X149592Y850338D01*
Y849297D01*
G01Y850338D02*
X150800Y850963D01*
G01X150425Y852313D02*
X150633Y852563D01*
X150758Y852855D01*
X150800Y853230D01*
X150717Y853605D01*
X150550Y853897D01*
X150258Y854105D01*
X149925Y854147D01*
X149592Y854063D01*
X149383Y853855D01*
X149217Y853563D01*
X149175Y853272D01*
X149217Y852980D01*
X149383Y852605D01*
X148300Y852730D01*
Y853855D01*
G01X150800Y856330D02*
X150758Y856622D01*
X150633Y856955D01*
X150425Y857163D01*
X150133Y857247D01*
X149842Y857163D01*
X149592Y856913D01*
X149467Y856538D01*
Y856122D01*
X149383Y855872D01*
X149175Y855663D01*
X148883Y855580D01*
X148592Y855705D01*
X148383Y855997D01*
X148300Y856330D01*
X148383Y856663D01*
X148592Y856955D01*
X148883Y857080D01*
X149175Y856997D01*
X149383Y856788D01*
X149467Y856538D01*
Y856122D01*
X149592Y855747D01*
X149842Y855497D01*
X150133Y855413D01*
X150425Y855497D01*
X150633Y855705D01*
X150758Y856038D01*
X150800Y856330D01*
G01X148300Y859430D02*
X148383Y859097D01*
X148592Y858847D01*
X148842Y858680D01*
X149175Y858555D01*
X149550Y858513D01*
X149925Y858555D01*
X150258Y858680D01*
X150508Y858847D01*
X150717Y859097D01*
X150800Y859430D01*
X150717Y859763D01*
X150508Y860013D01*
X150258Y860180D01*
X149925Y860305D01*
X149550Y860347D01*
X149175Y860305D01*
X148842Y860180D01*
X148592Y860013D01*
X148383Y859763D01*
X148300Y859430D01*
G01X114917Y867900D02*
Y870400D01*
X115958D01*
X116292Y870275D01*
X116500Y870108D01*
X116583Y869775D01*
X116500Y869442D01*
X116250Y869233D01*
X115958Y869108D01*
X114917D01*
G01X115958D02*
X116583Y867900D01*
G01X119350D02*
Y870400D01*
X117808Y868608D01*
X119892D01*
G01X121950Y867900D02*
Y870400D01*
X121450Y869900D01*
G01Y867900D02*
X122450D01*
G01X124133Y868400D02*
X124383Y868108D01*
X124717Y867942D01*
X125092Y867900D01*
X125425Y867942D01*
X125758Y868150D01*
X125967Y868400D01*
X126008Y868650D01*
X125925Y868942D01*
X125633Y869150D01*
X125342Y869233D01*
X124967D01*
G01X125342D02*
X125592Y869358D01*
X125800Y869567D01*
X125883Y869817D01*
X125800Y870067D01*
X125592Y870275D01*
X125217Y870400D01*
X124842Y870358D01*
X124467Y870192D01*
G01X113800Y862000D02*
Y858000D01*
X121200D01*
G01X114917Y863900D02*
Y866400D01*
X115958D01*
X116292Y866275D01*
X116500Y866108D01*
X116583Y865775D01*
X116500Y865442D01*
X116250Y865233D01*
X115958Y865108D01*
X114917D01*
G01X115958D02*
X116583Y863900D01*
G01X119350D02*
Y866400D01*
X117808Y864608D01*
X119892D01*
G01X121950Y863900D02*
Y866400D01*
X121450Y865900D01*
G01Y863900D02*
X122450D01*
G01X125550D02*
Y866400D01*
X124008Y864608D01*
X126092D01*
G01X113800Y857000D02*
Y853000D01*
X121200D01*
G01X135167Y853375D02*
X135375Y853708D01*
X135500Y854083D01*
Y854417D01*
X135375Y854750D01*
X135167Y855000D01*
X134875Y855125D01*
X134583Y855042D01*
X134333Y854833D01*
X134167Y854458D01*
X134083Y853958D01*
X133917Y853667D01*
X133625Y853542D01*
X133333Y853625D01*
X133125Y853833D01*
X133000Y854125D01*
Y854417D01*
X133083Y854708D01*
X133292Y854958D01*
G01X135500Y856517D02*
X133000D01*
Y857558D01*
X133125Y857892D01*
X133292Y858100D01*
X133625Y858183D01*
X133958Y858100D01*
X134167Y857850D01*
X134292Y857558D01*
Y856517D01*
G01Y857558D02*
X135500Y858183D01*
G01Y860450D02*
X133000D01*
X133500Y859950D01*
G01X135500D02*
Y860950D01*
G01Y863550D02*
X133000D01*
X133500Y863050D01*
G01X135500D02*
Y864050D01*
G01Y866650D02*
X133000D01*
X133500Y866150D01*
G01X135500D02*
Y867150D01*
G01X135125Y868833D02*
X135333Y869083D01*
X135458Y869375D01*
X135500Y869750D01*
X135417Y870125D01*
X135250Y870417D01*
X134958Y870625D01*
X134625Y870667D01*
X134292Y870583D01*
X134083Y870375D01*
X133917Y870083D01*
X133875Y869792D01*
X133917Y869500D01*
X134083Y869125D01*
X133000Y869250D01*
Y870375D01*
G01X131167Y853375D02*
X131375Y853708D01*
X131500Y854083D01*
Y854417D01*
X131375Y854750D01*
X131167Y855000D01*
X130875Y855125D01*
X130583Y855042D01*
X130333Y854833D01*
X130167Y854458D01*
X130083Y853958D01*
X129917Y853667D01*
X129625Y853542D01*
X129333Y853625D01*
X129125Y853833D01*
X129000Y854125D01*
Y854417D01*
X129083Y854708D01*
X129292Y854958D01*
G01X131500Y856517D02*
X129000D01*
Y857558D01*
X129125Y857892D01*
X129292Y858100D01*
X129625Y858183D01*
X129958Y858100D01*
X130167Y857850D01*
X130292Y857558D01*
Y856517D01*
G01Y857558D02*
X131500Y858183D01*
G01Y860450D02*
X129000D01*
X129500Y859950D01*
G01X131500D02*
Y860950D01*
G01Y863550D02*
X129000D01*
X129500Y863050D01*
G01X131500D02*
Y864050D01*
G01Y866650D02*
X129000D01*
X129500Y866150D01*
G01X131500D02*
Y867150D01*
G01X130458Y868958D02*
X130167Y869250D01*
X130000Y869500D01*
X129917Y869833D01*
X130000Y870125D01*
X130167Y870333D01*
X130417Y870500D01*
X130708Y870542D01*
X130958Y870500D01*
X131208Y870333D01*
X131417Y870083D01*
X131500Y869792D01*
X131417Y869458D01*
X131167Y869167D01*
X130792Y869000D01*
X130375Y868958D01*
X129833Y869042D01*
X129542Y869167D01*
X129250Y869375D01*
X129042Y869667D01*
X129000Y869958D01*
X129083Y870250D01*
X129292Y870458D01*
G01X133767Y982667D02*
Y985167D01*
X134767D01*
X135100Y985042D01*
X135350Y984750D01*
X135433Y984417D01*
X135350Y984084D01*
X135142Y983834D01*
X134767Y983709D01*
X133767D01*
G01X138533Y982667D02*
X136867D01*
Y985167D01*
X138533D01*
G01X137867Y983959D02*
X136867D01*
G01X141133Y984000D02*
X141300Y984125D01*
X141425Y984334D01*
X141508Y984625D01*
X141425Y984875D01*
X141258Y985042D01*
X140967Y985167D01*
X139842D01*
Y982667D01*
X141217D01*
X141508Y982834D01*
X141675Y983084D01*
X141758Y983375D01*
X141675Y983667D01*
X141425Y983917D01*
X141133Y984000D01*
X139842D01*
G01X145958Y982667D02*
X147000Y985167D01*
X148042Y982667D01*
G01X147667Y983542D02*
X146333D01*
G01X150100Y985167D02*
Y982667D01*
G01X149142Y985167D02*
X151058D01*
G01X153200D02*
Y982667D01*
G01X152242Y985167D02*
X154158D01*
G01X155342Y982667D02*
Y985167D01*
X157258Y982667D01*
Y985167D01*
G01X159317Y982667D02*
X159400Y983209D01*
X159525Y983667D01*
X159692Y984084D01*
X159900Y984542D01*
X160233Y985167D01*
X158567D01*
G01X132175Y957300D02*
X132508Y957092D01*
X132883Y956967D01*
X133217D01*
X133550Y957092D01*
X133800Y957300D01*
X133925Y957592D01*
X133842Y957884D01*
X133633Y958134D01*
X133258Y958300D01*
X132758Y958384D01*
X132467Y958550D01*
X132342Y958842D01*
X132425Y959134D01*
X132633Y959342D01*
X132925Y959467D01*
X133217D01*
X133508Y959384D01*
X133758Y959175D01*
G01X135233Y956967D02*
Y959467D01*
X136067D01*
X136400Y959342D01*
X136650Y959175D01*
X136858Y958925D01*
X137025Y958634D01*
X137067Y958217D01*
X137025Y957800D01*
X136858Y957509D01*
X136650Y957259D01*
X136400Y957092D01*
X136067Y956967D01*
X135233D01*
G01X138333D02*
Y959467D01*
X139167D01*
X139500Y959342D01*
X139750Y959175D01*
X139958Y958925D01*
X140125Y958634D01*
X140167Y958217D01*
X140125Y957800D01*
X139958Y957509D01*
X139750Y957259D01*
X139500Y957092D01*
X139167Y956967D01*
X138333D01*
G01X144408D02*
X145450Y959467D01*
X146492Y956967D01*
G01X146117Y957842D02*
X144783D01*
G01X149467Y959259D02*
X149217Y959384D01*
X148925Y959467D01*
X148592D01*
X148217Y959342D01*
X147925Y959134D01*
X147717Y958884D01*
X147550Y958467D01*
X147508Y958092D01*
X147592Y957717D01*
X147717Y957467D01*
X147967Y957217D01*
X148258Y957050D01*
X148550Y956967D01*
X148842D01*
X149133Y957050D01*
X149383Y957175D01*
X149592Y957342D01*
G01X151650Y959467D02*
Y956967D01*
G01X150692Y959467D02*
X152608D01*
G01X154667Y956967D02*
X154750Y957509D01*
X154875Y957967D01*
X155042Y958384D01*
X155250Y958842D01*
X155583Y959467D01*
X153917D01*
G01X209308Y996841D02*
X180408D01*
Y983941D01*
X162108D01*
Y996841D01*
X148608D01*
Y1158041D01*
X162108D01*
Y1170941D01*
X180408D01*
Y1158041D01*
X209308D01*
Y1147691D01*
X202608D01*
Y1007191D01*
X209308D01*
Y996841D01*
G01X178834Y966517D02*
X181334D01*
Y968183D01*
G01Y971283D02*
Y969617D01*
X178834D01*
Y971283D01*
G01X180042Y970617D02*
Y969617D01*
G01X181334Y972633D02*
X178834D01*
Y973467D01*
X178959Y973800D01*
X179126Y974050D01*
X179376Y974258D01*
X179667Y974425D01*
X180084Y974467D01*
X180501Y974425D01*
X180792Y974258D01*
X181042Y974050D01*
X181209Y973800D01*
X181334Y973467D01*
Y972633D01*
G01Y976567D02*
X180792Y976650D01*
X180334Y976775D01*
X179917Y976942D01*
X179459Y977150D01*
X178834Y977483D01*
Y975817D01*
G01X165560Y969035D02*
Y976635D01*
X176960D01*
Y969035D01*
X165560D01*
G01X162408Y928917D02*
X162283Y928667D01*
X162200Y928375D01*
Y928042D01*
X162325Y927667D01*
X162533Y927375D01*
X162783Y927167D01*
X163200Y927000D01*
X163575Y926958D01*
X163950Y927042D01*
X164200Y927167D01*
X164450Y927417D01*
X164617Y927708D01*
X164700Y928000D01*
Y928292D01*
X164617Y928583D01*
X164492Y928833D01*
X164325Y929042D01*
G01X164408Y930392D02*
X164617Y930683D01*
X164700Y931017D01*
X164617Y931350D01*
X164367Y931642D01*
X163992Y931850D01*
X163617Y931933D01*
X163158D01*
X162783Y931850D01*
X162450Y931642D01*
X162283Y931392D01*
X162200Y931100D01*
X162283Y930767D01*
X162450Y930517D01*
X162700Y930350D01*
X163033Y930267D01*
X163325Y930350D01*
X163617Y930558D01*
X163783Y930808D01*
X163825Y931100D01*
X163742Y931433D01*
X163533Y931683D01*
X163158Y931933D01*
G01X164325Y933283D02*
X164533Y933533D01*
X164658Y933825D01*
X164700Y934200D01*
X164617Y934575D01*
X164450Y934867D01*
X164158Y935075D01*
X163825Y935117D01*
X163492Y935033D01*
X163283Y934825D01*
X163117Y934533D01*
X163075Y934242D01*
X163117Y933950D01*
X163283Y933575D01*
X162200Y933700D01*
Y934825D01*
G01X162617Y936508D02*
X162367Y936758D01*
X162242Y937050D01*
X162200Y937383D01*
X162283Y937800D01*
X162492Y938092D01*
X162742Y938175D01*
X162992Y938133D01*
X163200Y937967D01*
X163617Y937133D01*
X163908Y936758D01*
X164325Y936508D01*
X164700Y936425D01*
Y938175D01*
G01X164325Y939483D02*
X164533Y939733D01*
X164658Y940025D01*
X164700Y940400D01*
X164617Y940775D01*
X164450Y941067D01*
X164158Y941275D01*
X163825Y941317D01*
X163492Y941233D01*
X163283Y941025D01*
X163117Y940733D01*
X163075Y940442D01*
X163117Y940150D01*
X163283Y939775D01*
X162200Y939900D01*
Y941025D01*
G01X143000Y964400D02*
X142958Y964067D01*
X142792Y963775D01*
X142542Y963525D01*
X142250Y963358D01*
X141917Y963275D01*
X141583D01*
X141250Y963358D01*
X140958Y963525D01*
X140708Y963775D01*
X140542Y964067D01*
X140500Y964400D01*
X140542Y964733D01*
X140708Y965025D01*
X140958Y965275D01*
X141250Y965442D01*
X141583Y965525D01*
X141917D01*
X142250Y965442D01*
X142542Y965275D01*
X142792Y965025D01*
X142958Y964733D01*
X143000Y964400D01*
G01X142333Y964733D02*
X143000Y965233D01*
G01X141958Y966708D02*
X141667Y967000D01*
X141500Y967250D01*
X141417Y967583D01*
X141500Y967875D01*
X141667Y968083D01*
X141917Y968250D01*
X142208Y968292D01*
X142458Y968250D01*
X142708Y968083D01*
X142917Y967833D01*
X143000Y967542D01*
X142917Y967208D01*
X142667Y966917D01*
X142292Y966750D01*
X141875Y966708D01*
X141333Y966792D01*
X141042Y966917D01*
X140750Y967125D01*
X140542Y967417D01*
X140500Y967708D01*
X140583Y968000D01*
X140792Y968208D01*
G01X142500Y969683D02*
X142792Y969933D01*
X142958Y970267D01*
X143000Y970642D01*
X142958Y970975D01*
X142750Y971308D01*
X142500Y971517D01*
X142250Y971558D01*
X141958Y971475D01*
X141750Y971183D01*
X141667Y970892D01*
Y970517D01*
G01Y970892D02*
X141542Y971142D01*
X141333Y971350D01*
X141083Y971433D01*
X140833Y971350D01*
X140625Y971142D01*
X140500Y970767D01*
X140542Y970392D01*
X140708Y970017D01*
G01X145000Y974500D02*
Y960500D01*
G01X158000Y974500D02*
X145000D01*
G01X158000Y960500D02*
Y974500D01*
G01X145000Y960500D02*
X158000D01*
G01X155967Y945500D02*
Y948000D01*
X157008D01*
X157342Y947875D01*
X157550Y947708D01*
X157633Y947375D01*
X157550Y947042D01*
X157300Y946833D01*
X157008Y946708D01*
X155967D01*
G01X157008D02*
X157633Y945500D01*
G01X159192Y945792D02*
X159483Y945583D01*
X159817Y945500D01*
X160150Y945583D01*
X160442Y945833D01*
X160650Y946208D01*
X160733Y946583D01*
Y947042D01*
X160650Y947417D01*
X160442Y947750D01*
X160192Y947917D01*
X159900Y948000D01*
X159567Y947917D01*
X159317Y947750D01*
X159150Y947500D01*
X159067Y947167D01*
X159150Y946875D01*
X159358Y946583D01*
X159608Y946417D01*
X159900Y946375D01*
X160233Y946458D01*
X160483Y946667D01*
X160733Y947042D01*
G01X163000Y945500D02*
X163292Y945542D01*
X163625Y945667D01*
X163833Y945875D01*
X163917Y946167D01*
X163833Y946458D01*
X163583Y946708D01*
X163208Y946833D01*
X162792D01*
X162542Y946917D01*
X162333Y947125D01*
X162250Y947417D01*
X162375Y947708D01*
X162667Y947917D01*
X163000Y948000D01*
X163333Y947917D01*
X163625Y947708D01*
X163750Y947417D01*
X163667Y947125D01*
X163458Y946917D01*
X163208Y946833D01*
X162792D01*
X162417Y946708D01*
X162167Y946458D01*
X162083Y946167D01*
X162167Y945875D01*
X162375Y945667D01*
X162708Y945542D01*
X163000Y945500D01*
G01X165308Y947583D02*
X165558Y947833D01*
X165850Y947958D01*
X166183Y948000D01*
X166600Y947917D01*
X166892Y947708D01*
X166975Y947458D01*
X166933Y947208D01*
X166767Y947000D01*
X165933Y946583D01*
X165558Y946292D01*
X165308Y945875D01*
X165225Y945500D01*
X166975D01*
G01X168492Y945792D02*
X168783Y945583D01*
X169117Y945500D01*
X169450Y945583D01*
X169742Y945833D01*
X169950Y946208D01*
X170033Y946583D01*
Y947042D01*
X169950Y947417D01*
X169742Y947750D01*
X169492Y947917D01*
X169200Y948000D01*
X168867Y947917D01*
X168617Y947750D01*
X168450Y947500D01*
X168367Y947167D01*
X168450Y946875D01*
X168658Y946583D01*
X168908Y946417D01*
X169200Y946375D01*
X169533Y946458D01*
X169783Y946667D01*
X170033Y947042D01*
G01X182200Y961500D02*
Y965500D01*
X174800D01*
G01X156967Y953500D02*
Y956000D01*
X158008D01*
X158342Y955875D01*
X158550Y955708D01*
X158633Y955375D01*
X158550Y955042D01*
X158300Y954833D01*
X158008Y954708D01*
X156967D01*
G01X158008D02*
X158633Y953500D01*
G01X160192Y953792D02*
X160483Y953583D01*
X160817Y953500D01*
X161150Y953583D01*
X161442Y953833D01*
X161650Y954208D01*
X161733Y954583D01*
Y955042D01*
X161650Y955417D01*
X161442Y955750D01*
X161192Y955917D01*
X160900Y956000D01*
X160567Y955917D01*
X160317Y955750D01*
X160150Y955500D01*
X160067Y955167D01*
X160150Y954875D01*
X160358Y954583D01*
X160608Y954417D01*
X160900Y954375D01*
X161233Y954458D01*
X161483Y954667D01*
X161733Y955042D01*
G01X164000Y953500D02*
X164292Y953542D01*
X164625Y953667D01*
X164833Y953875D01*
X164917Y954167D01*
X164833Y954458D01*
X164583Y954708D01*
X164208Y954833D01*
X163792D01*
X163542Y954917D01*
X163333Y955125D01*
X163250Y955417D01*
X163375Y955708D01*
X163667Y955917D01*
X164000Y956000D01*
X164333Y955917D01*
X164625Y955708D01*
X164750Y955417D01*
X164667Y955125D01*
X164458Y954917D01*
X164208Y954833D01*
X163792D01*
X163417Y954708D01*
X163167Y954458D01*
X163083Y954167D01*
X163167Y953875D01*
X163375Y953667D01*
X163708Y953542D01*
X164000Y953500D01*
G01X166183Y954000D02*
X166433Y953708D01*
X166767Y953542D01*
X167142Y953500D01*
X167475Y953542D01*
X167808Y953750D01*
X168017Y954000D01*
X168058Y954250D01*
X167975Y954542D01*
X167683Y954750D01*
X167392Y954833D01*
X167017D01*
G01X167392D02*
X167642Y954958D01*
X167850Y955167D01*
X167933Y955417D01*
X167850Y955667D01*
X167642Y955875D01*
X167267Y956000D01*
X166892Y955958D01*
X166517Y955792D01*
G01X170200Y953500D02*
Y956000D01*
X169700Y955500D01*
G01Y953500D02*
X170700D01*
G01X164217Y962000D02*
Y958000D01*
X171617D01*
G01X159867Y927075D02*
X160075Y927408D01*
X160200Y927783D01*
Y928117D01*
X160075Y928450D01*
X159867Y928700D01*
X159575Y928825D01*
X159283Y928742D01*
X159033Y928533D01*
X158867Y928158D01*
X158783Y927658D01*
X158617Y927367D01*
X158325Y927242D01*
X158033Y927325D01*
X157825Y927533D01*
X157700Y927825D01*
Y928117D01*
X157783Y928408D01*
X157992Y928658D01*
G01X160200Y930217D02*
X157700D01*
Y931258D01*
X157825Y931592D01*
X157992Y931800D01*
X158325Y931883D01*
X158658Y931800D01*
X158867Y931550D01*
X158992Y931258D01*
Y930217D01*
G01Y931258D02*
X160200Y931883D01*
G01Y934150D02*
X157700D01*
X158200Y933650D01*
G01X160200D02*
Y934650D01*
G01Y937250D02*
X157700D01*
X158200Y936750D01*
G01X160200D02*
Y937750D01*
G01X159700Y939433D02*
X159992Y939683D01*
X160158Y940017D01*
X160200Y940392D01*
X160158Y940725D01*
X159950Y941058D01*
X159700Y941267D01*
X159450Y941308D01*
X159158Y941225D01*
X158950Y940933D01*
X158867Y940642D01*
Y940267D01*
G01Y940642D02*
X158742Y940892D01*
X158533Y941100D01*
X158283Y941183D01*
X158033Y941100D01*
X157825Y940892D01*
X157700Y940517D01*
X157742Y940142D01*
X157908Y939767D01*
G01X159158Y942658D02*
X158867Y942950D01*
X158700Y943200D01*
X158617Y943533D01*
X158700Y943825D01*
X158867Y944033D01*
X159117Y944200D01*
X159408Y944242D01*
X159658Y944200D01*
X159908Y944033D01*
X160117Y943783D01*
X160200Y943492D01*
X160117Y943158D01*
X159867Y942867D01*
X159492Y942700D01*
X159075Y942658D01*
X158533Y942742D01*
X158242Y942867D01*
X157950Y943075D01*
X157742Y943367D01*
X157700Y943658D01*
X157783Y943950D01*
X157992Y944158D01*
G01X180000Y958200D02*
X176000D01*
Y950800D01*
G01X138967Y976167D02*
Y978667D01*
X140008D01*
X140342Y978542D01*
X140550Y978375D01*
X140633Y978042D01*
X140550Y977709D01*
X140300Y977500D01*
X140008Y977375D01*
X138967D01*
G01X140008D02*
X140633Y976167D01*
G01X142192Y976459D02*
X142483Y976250D01*
X142817Y976167D01*
X143150Y976250D01*
X143442Y976500D01*
X143650Y976875D01*
X143733Y977250D01*
Y977709D01*
X143650Y978084D01*
X143442Y978417D01*
X143192Y978584D01*
X142900Y978667D01*
X142567Y978584D01*
X142317Y978417D01*
X142150Y978167D01*
X142067Y977834D01*
X142150Y977542D01*
X142358Y977250D01*
X142608Y977084D01*
X142900Y977042D01*
X143233Y977125D01*
X143483Y977334D01*
X143733Y977709D01*
G01X145292Y976459D02*
X145583Y976250D01*
X145917Y976167D01*
X146250Y976250D01*
X146542Y976500D01*
X146750Y976875D01*
X146833Y977250D01*
Y977709D01*
X146750Y978084D01*
X146542Y978417D01*
X146292Y978584D01*
X146000Y978667D01*
X145667Y978584D01*
X145417Y978417D01*
X145250Y978167D01*
X145167Y977834D01*
X145250Y977542D01*
X145458Y977250D01*
X145708Y977084D01*
X146000Y977042D01*
X146333Y977125D01*
X146583Y977334D01*
X146833Y977709D01*
G01X149600Y976167D02*
Y978667D01*
X148058Y976875D01*
X150142D01*
G01X151408Y978250D02*
X151658Y978500D01*
X151950Y978625D01*
X152283Y978667D01*
X152700Y978584D01*
X152992Y978375D01*
X153075Y978125D01*
X153033Y977875D01*
X152867Y977667D01*
X152033Y977250D01*
X151658Y976959D01*
X151408Y976542D01*
X151325Y976167D01*
X153075D01*
G01X162446Y974999D02*
Y978999D01*
X155046D01*
G01X171467Y979667D02*
Y982167D01*
X172508D01*
X172842Y982042D01*
X173050Y981875D01*
X173133Y981542D01*
X173050Y981209D01*
X172800Y981000D01*
X172508Y980875D01*
X171467D01*
G01X172508D02*
X173133Y979667D01*
G01X174692Y979959D02*
X174983Y979750D01*
X175317Y979667D01*
X175650Y979750D01*
X175942Y980000D01*
X176150Y980375D01*
X176233Y980750D01*
Y981209D01*
X176150Y981584D01*
X175942Y981917D01*
X175692Y982084D01*
X175400Y982167D01*
X175067Y982084D01*
X174817Y981917D01*
X174650Y981667D01*
X174567Y981334D01*
X174650Y981042D01*
X174858Y980750D01*
X175108Y980584D01*
X175400Y980542D01*
X175733Y980625D01*
X175983Y980834D01*
X176233Y981209D01*
G01X177792Y979959D02*
X178083Y979750D01*
X178417Y979667D01*
X178750Y979750D01*
X179042Y980000D01*
X179250Y980375D01*
X179333Y980750D01*
Y981209D01*
X179250Y981584D01*
X179042Y981917D01*
X178792Y982084D01*
X178500Y982167D01*
X178167Y982084D01*
X177917Y981917D01*
X177750Y981667D01*
X177667Y981334D01*
X177750Y981042D01*
X177958Y980750D01*
X178208Y980584D01*
X178500Y980542D01*
X178833Y980625D01*
X179083Y980834D01*
X179333Y981209D01*
G01X182100Y979667D02*
Y982167D01*
X180558Y980375D01*
X182642D01*
G01X184700Y979667D02*
Y982167D01*
X184200Y981667D01*
G01Y979667D02*
X185200D01*
G01X162830Y981729D02*
Y977729D01*
X170230D01*
G01X140000Y1036917D02*
X137500D01*
Y1037917D01*
X137625Y1038250D01*
X137917Y1038500D01*
X138250Y1038583D01*
X138583Y1038500D01*
X138833Y1038292D01*
X138958Y1037917D01*
Y1036917D01*
G01X137708Y1041767D02*
X137583Y1041517D01*
X137500Y1041225D01*
Y1040892D01*
X137625Y1040517D01*
X137833Y1040225D01*
X138083Y1040017D01*
X138500Y1039850D01*
X138875Y1039808D01*
X139250Y1039892D01*
X139500Y1040017D01*
X139750Y1040267D01*
X139917Y1040558D01*
X140000Y1040850D01*
Y1041142D01*
X139917Y1041433D01*
X139792Y1041683D01*
X139625Y1041892D01*
G01X140000Y1043950D02*
X137500D01*
X138000Y1043450D01*
G01X140000D02*
Y1044450D01*
G01X137917Y1046258D02*
X137667Y1046508D01*
X137542Y1046800D01*
X137500Y1047133D01*
X137583Y1047550D01*
X137792Y1047842D01*
X138042Y1047925D01*
X138292Y1047883D01*
X138500Y1047717D01*
X138917Y1046883D01*
X139208Y1046508D01*
X139625Y1046258D01*
X140000Y1046175D01*
Y1047925D01*
G01Y1050650D02*
X137500D01*
X139292Y1049108D01*
Y1051192D01*
G01X139708Y1052542D02*
X139917Y1052833D01*
X140000Y1053167D01*
X139917Y1053500D01*
X139667Y1053792D01*
X139292Y1054000D01*
X138917Y1054083D01*
X138458D01*
X138083Y1054000D01*
X137750Y1053792D01*
X137583Y1053542D01*
X137500Y1053250D01*
X137583Y1052917D01*
X137750Y1052667D01*
X138000Y1052500D01*
X138333Y1052417D01*
X138625Y1052500D01*
X138917Y1052708D01*
X139083Y1052958D01*
X139125Y1053250D01*
X139042Y1053583D01*
X138833Y1053833D01*
X138458Y1054083D01*
G01X111500Y1049433D02*
X113292D01*
X113667Y1049600D01*
X113917Y1049933D01*
X114000Y1050350D01*
X113917Y1050767D01*
X113667Y1051100D01*
X113292Y1051267D01*
X111500D01*
G01X111917Y1052658D02*
X111667Y1052908D01*
X111542Y1053200D01*
X111500Y1053533D01*
X111583Y1053950D01*
X111792Y1054242D01*
X112042Y1054325D01*
X112292Y1054283D01*
X112500Y1054117D01*
X112917Y1053283D01*
X113208Y1052908D01*
X113625Y1052658D01*
X114000Y1052575D01*
Y1054325D01*
G01X111500Y1056550D02*
X111583Y1056217D01*
X111792Y1055967D01*
X112042Y1055800D01*
X112375Y1055675D01*
X112750Y1055633D01*
X113125Y1055675D01*
X113458Y1055800D01*
X113708Y1055967D01*
X113917Y1056217D01*
X114000Y1056550D01*
X113917Y1056883D01*
X113708Y1057133D01*
X113458Y1057300D01*
X113125Y1057425D01*
X112750Y1057467D01*
X112375Y1057425D01*
X112042Y1057300D01*
X111792Y1057133D01*
X111583Y1056883D01*
X111500Y1056550D01*
G01X113708Y1058942D02*
X113917Y1059233D01*
X114000Y1059567D01*
X113917Y1059900D01*
X113667Y1060192D01*
X113292Y1060400D01*
X112917Y1060483D01*
X112458D01*
X112083Y1060400D01*
X111750Y1060192D01*
X111583Y1059942D01*
X111500Y1059650D01*
X111583Y1059317D01*
X111750Y1059067D01*
X112000Y1058900D01*
X112333Y1058817D01*
X112625Y1058900D01*
X112917Y1059108D01*
X113083Y1059358D01*
X113125Y1059650D01*
X113042Y1059983D01*
X112833Y1060233D01*
X112458Y1060483D01*
G01X123653Y1115010D02*
X122820Y1113677D01*
X122320Y1112177D01*
Y1110843D01*
X122820Y1109510D01*
X123653Y1108510D01*
X124820Y1108010D01*
X125986Y1108343D01*
X126987Y1109177D01*
X127653Y1110677D01*
X127987Y1112677D01*
X128653Y1113843D01*
X129820Y1114343D01*
X130987Y1114010D01*
X131820Y1113177D01*
X132320Y1112010D01*
Y1110843D01*
X131987Y1109677D01*
X131153Y1108677D01*
G01X123653Y1104410D02*
X122820Y1103077D01*
X122320Y1101577D01*
Y1100243D01*
X122820Y1098910D01*
X123653Y1097910D01*
X124820Y1097410D01*
X125986Y1097743D01*
X126987Y1098577D01*
X127653Y1100077D01*
X127987Y1102077D01*
X128653Y1103243D01*
X129820Y1103743D01*
X130987Y1103410D01*
X131820Y1102577D01*
X132320Y1101410D01*
Y1100243D01*
X131987Y1099077D01*
X131153Y1098077D01*
G01X122320Y1093977D02*
X132320D01*
Y1090643D01*
X131820Y1089310D01*
X131153Y1088310D01*
X130153Y1087477D01*
X128986Y1086810D01*
X127320Y1086643D01*
X125653Y1086810D01*
X124487Y1087477D01*
X123486Y1088310D01*
X122820Y1089310D01*
X122320Y1090643D01*
Y1093977D01*
G01Y1080043D02*
X124487Y1079710D01*
X126320Y1079210D01*
X127987Y1078543D01*
X129820Y1077710D01*
X132320Y1076377D01*
Y1083043D01*
G01X144500Y1068617D02*
X144750Y1068825D01*
X144917Y1069075D01*
X145000Y1069367D01*
X144917Y1069700D01*
X144750Y1069950D01*
X144500Y1070200D01*
X144167Y1070283D01*
X142500D01*
G01X145000Y1072467D02*
X144458Y1072550D01*
X144000Y1072675D01*
X143583Y1072842D01*
X143125Y1073050D01*
X142500Y1073383D01*
Y1071717D01*
G01X140700Y1122417D02*
X138200D01*
Y1123417D01*
X138325Y1123750D01*
X138617Y1124000D01*
X138950Y1124083D01*
X139283Y1124000D01*
X139533Y1123792D01*
X139658Y1123417D01*
Y1122417D01*
G01X138408Y1127267D02*
X138283Y1127017D01*
X138200Y1126725D01*
Y1126392D01*
X138325Y1126017D01*
X138533Y1125725D01*
X138783Y1125517D01*
X139200Y1125350D01*
X139575Y1125308D01*
X139950Y1125392D01*
X140200Y1125517D01*
X140450Y1125767D01*
X140617Y1126058D01*
X140700Y1126350D01*
Y1126642D01*
X140617Y1126933D01*
X140492Y1127183D01*
X140325Y1127392D01*
G01X140700Y1129450D02*
X138200D01*
X138700Y1128950D01*
G01X140700D02*
Y1129950D01*
G01X138617Y1131758D02*
X138367Y1132008D01*
X138242Y1132300D01*
X138200Y1132633D01*
X138283Y1133050D01*
X138492Y1133342D01*
X138742Y1133425D01*
X138992Y1133383D01*
X139200Y1133217D01*
X139617Y1132383D01*
X139908Y1132008D01*
X140325Y1131758D01*
X140700Y1131675D01*
Y1133425D01*
G01Y1136150D02*
X138200D01*
X139992Y1134608D01*
Y1136692D01*
G01X140700Y1138750D02*
X140658Y1139042D01*
X140533Y1139375D01*
X140325Y1139583D01*
X140033Y1139667D01*
X139742Y1139583D01*
X139492Y1139333D01*
X139367Y1138958D01*
Y1138542D01*
X139283Y1138292D01*
X139075Y1138083D01*
X138783Y1138000D01*
X138492Y1138125D01*
X138283Y1138417D01*
X138200Y1138750D01*
X138283Y1139083D01*
X138492Y1139375D01*
X138783Y1139500D01*
X139075Y1139417D01*
X139283Y1139208D01*
X139367Y1138958D01*
Y1138542D01*
X139492Y1138167D01*
X139742Y1137917D01*
X140033Y1137833D01*
X140325Y1137917D01*
X140533Y1138125D01*
X140658Y1138458D01*
X140700Y1138750D01*
G01X118017Y1120900D02*
Y1123400D01*
X119058D01*
X119392Y1123275D01*
X119600Y1123108D01*
X119683Y1122775D01*
X119600Y1122442D01*
X119350Y1122233D01*
X119058Y1122108D01*
X118017D01*
G01X119058D02*
X119683Y1120900D01*
G01X122450D02*
Y1123400D01*
X120908Y1121608D01*
X122992D01*
G01X125050Y1123400D02*
X124717Y1123317D01*
X124467Y1123108D01*
X124300Y1122858D01*
X124175Y1122525D01*
X124133Y1122150D01*
X124175Y1121775D01*
X124300Y1121442D01*
X124467Y1121192D01*
X124717Y1120983D01*
X125050Y1120900D01*
X125383Y1120983D01*
X125633Y1121192D01*
X125800Y1121442D01*
X125925Y1121775D01*
X125967Y1122150D01*
X125925Y1122525D01*
X125800Y1122858D01*
X125633Y1123108D01*
X125383Y1123317D01*
X125050Y1123400D01*
G01X128150Y1120900D02*
Y1123400D01*
X127650Y1122900D01*
G01Y1120900D02*
X128650D01*
G01X130200Y1130000D02*
Y1134000D01*
X122800D01*
G01X118327Y1125221D02*
Y1127721D01*
X119368D01*
X119702Y1127596D01*
X119910Y1127429D01*
X119993Y1127096D01*
X119910Y1126763D01*
X119660Y1126554D01*
X119368Y1126429D01*
X118327D01*
G01X119368D02*
X119993Y1125221D01*
G01X122760D02*
Y1127721D01*
X121218Y1125929D01*
X123302D01*
G01X125360Y1127721D02*
X125027Y1127638D01*
X124777Y1127429D01*
X124610Y1127179D01*
X124485Y1126846D01*
X124443Y1126471D01*
X124485Y1126096D01*
X124610Y1125763D01*
X124777Y1125513D01*
X125027Y1125304D01*
X125360Y1125221D01*
X125693Y1125304D01*
X125943Y1125513D01*
X126110Y1125763D01*
X126235Y1126096D01*
X126277Y1126471D01*
X126235Y1126846D01*
X126110Y1127179D01*
X125943Y1127429D01*
X125693Y1127638D01*
X125360Y1127721D01*
G01X127668Y1127304D02*
X127918Y1127554D01*
X128210Y1127679D01*
X128543Y1127721D01*
X128960Y1127638D01*
X129252Y1127429D01*
X129335Y1127179D01*
X129293Y1126929D01*
X129127Y1126721D01*
X128293Y1126304D01*
X127918Y1126013D01*
X127668Y1125596D01*
X127585Y1125221D01*
X129335D01*
G01X130200Y1135000D02*
Y1139000D01*
X122800D01*
G01X133700Y1122217D02*
X131200D01*
Y1123217D01*
X131325Y1123550D01*
X131617Y1123800D01*
X131950Y1123883D01*
X132283Y1123800D01*
X132533Y1123592D01*
X132658Y1123217D01*
Y1122217D01*
G01X131408Y1127067D02*
X131283Y1126817D01*
X131200Y1126525D01*
Y1126192D01*
X131325Y1125817D01*
X131533Y1125525D01*
X131783Y1125317D01*
X132200Y1125150D01*
X132575Y1125108D01*
X132950Y1125192D01*
X133200Y1125317D01*
X133450Y1125567D01*
X133617Y1125858D01*
X133700Y1126150D01*
Y1126442D01*
X133617Y1126733D01*
X133492Y1126983D01*
X133325Y1127192D01*
G01X133700Y1129250D02*
X131200D01*
X131700Y1128750D01*
G01X133700D02*
Y1129750D01*
G01X131617Y1131558D02*
X131367Y1131808D01*
X131242Y1132100D01*
X131200Y1132433D01*
X131283Y1132850D01*
X131492Y1133142D01*
X131742Y1133225D01*
X131992Y1133183D01*
X132200Y1133017D01*
X132617Y1132183D01*
X132908Y1131808D01*
X133325Y1131558D01*
X133700Y1131475D01*
Y1133225D01*
G01Y1135950D02*
X131200D01*
X132992Y1134408D01*
Y1136492D01*
G01X132658Y1137758D02*
X132367Y1138050D01*
X132200Y1138300D01*
X132117Y1138633D01*
X132200Y1138925D01*
X132367Y1139133D01*
X132617Y1139300D01*
X132908Y1139342D01*
X133158Y1139300D01*
X133408Y1139133D01*
X133617Y1138883D01*
X133700Y1138592D01*
X133617Y1138258D01*
X133367Y1137967D01*
X132992Y1137800D01*
X132575Y1137758D01*
X132033Y1137842D01*
X131742Y1137967D01*
X131450Y1138175D01*
X131242Y1138467D01*
X131200Y1138758D01*
X131283Y1139050D01*
X131492Y1139258D01*
G01X154500Y1162417D02*
X152000D01*
Y1163417D01*
X152125Y1163750D01*
X152417Y1164000D01*
X152750Y1164083D01*
X153083Y1164000D01*
X153333Y1163792D01*
X153458Y1163417D01*
Y1162417D01*
G01X152208Y1167267D02*
X152083Y1167017D01*
X152000Y1166725D01*
Y1166392D01*
X152125Y1166017D01*
X152333Y1165725D01*
X152583Y1165517D01*
X153000Y1165350D01*
X153375Y1165308D01*
X153750Y1165392D01*
X154000Y1165517D01*
X154250Y1165767D01*
X154417Y1166058D01*
X154500Y1166350D01*
Y1166642D01*
X154417Y1166933D01*
X154292Y1167183D01*
X154125Y1167392D01*
G01X154500Y1169450D02*
X152000D01*
X152500Y1168950D01*
G01X154500D02*
Y1169950D01*
G01X152417Y1171758D02*
X152167Y1172008D01*
X152042Y1172300D01*
X152000Y1172633D01*
X152083Y1173050D01*
X152292Y1173342D01*
X152542Y1173425D01*
X152792Y1173383D01*
X153000Y1173217D01*
X153417Y1172383D01*
X153708Y1172008D01*
X154125Y1171758D01*
X154500Y1171675D01*
Y1173425D01*
G01Y1176150D02*
X152000D01*
X153792Y1174608D01*
Y1176692D01*
G01X154500Y1178667D02*
X153958Y1178750D01*
X153500Y1178875D01*
X153083Y1179042D01*
X152625Y1179250D01*
X152000Y1179583D01*
Y1177917D01*
G01X124400Y1193000D02*
X124067Y1193042D01*
X123775Y1193208D01*
X123525Y1193458D01*
X123358Y1193750D01*
X123275Y1194083D01*
Y1194417D01*
X123358Y1194750D01*
X123525Y1195042D01*
X123775Y1195292D01*
X124067Y1195458D01*
X124400Y1195500D01*
X124733Y1195458D01*
X125025Y1195292D01*
X125275Y1195042D01*
X125442Y1194750D01*
X125525Y1194417D01*
Y1194083D01*
X125442Y1193750D01*
X125275Y1193458D01*
X125025Y1193208D01*
X124733Y1193042D01*
X124400Y1193000D01*
G01X124733Y1193667D02*
X125233Y1193000D01*
G01X126708Y1194042D02*
X127000Y1194333D01*
X127250Y1194500D01*
X127583Y1194583D01*
X127875Y1194500D01*
X128083Y1194333D01*
X128250Y1194083D01*
X128292Y1193792D01*
X128250Y1193542D01*
X128083Y1193292D01*
X127833Y1193083D01*
X127542Y1193000D01*
X127208Y1193083D01*
X126917Y1193333D01*
X126750Y1193708D01*
X126708Y1194125D01*
X126792Y1194667D01*
X126917Y1194958D01*
X127125Y1195250D01*
X127417Y1195458D01*
X127708Y1195500D01*
X128000Y1195417D01*
X128208Y1195208D01*
G01X130600Y1193000D02*
Y1195500D01*
X130100Y1195000D01*
G01Y1193000D02*
X131100D01*
G01X130500Y1191400D02*
X116500D01*
G01X130500Y1178400D02*
Y1191400D01*
G01X116500Y1178400D02*
X130500D01*
G01X116500Y1191400D02*
Y1178400D01*
G01X114800Y1198400D02*
X114467Y1198442D01*
X114175Y1198608D01*
X113925Y1198858D01*
X113758Y1199150D01*
X113675Y1199483D01*
Y1199817D01*
X113758Y1200150D01*
X113925Y1200442D01*
X114175Y1200692D01*
X114467Y1200858D01*
X114800Y1200900D01*
X115133Y1200858D01*
X115425Y1200692D01*
X115675Y1200442D01*
X115842Y1200150D01*
X115925Y1199817D01*
Y1199483D01*
X115842Y1199150D01*
X115675Y1198858D01*
X115425Y1198608D01*
X115133Y1198442D01*
X114800Y1198400D01*
G01X115133Y1199067D02*
X115633Y1198400D01*
G01X117900D02*
X118192Y1198442D01*
X118525Y1198567D01*
X118733Y1198775D01*
X118817Y1199067D01*
X118733Y1199358D01*
X118483Y1199608D01*
X118108Y1199733D01*
X117692D01*
X117442Y1199817D01*
X117233Y1200025D01*
X117150Y1200317D01*
X117275Y1200608D01*
X117567Y1200817D01*
X117900Y1200900D01*
X118233Y1200817D01*
X118525Y1200608D01*
X118650Y1200317D01*
X118567Y1200025D01*
X118358Y1199817D01*
X118108Y1199733D01*
X117692D01*
X117317Y1199608D01*
X117067Y1199358D01*
X116983Y1199067D01*
X117067Y1198775D01*
X117275Y1198567D01*
X117608Y1198442D01*
X117900Y1198400D01*
G01X121000D02*
Y1200900D01*
X120500Y1200400D01*
G01Y1198400D02*
X121500D01*
G01X113500Y1206100D02*
X127500D01*
G01X113500Y1219100D02*
Y1206100D01*
G01X127500D02*
Y1219100D01*
G01X144200Y1198300D02*
X143867Y1198342D01*
X143575Y1198508D01*
X143325Y1198758D01*
X143158Y1199050D01*
X143075Y1199383D01*
Y1199717D01*
X143158Y1200050D01*
X143325Y1200342D01*
X143575Y1200592D01*
X143867Y1200758D01*
X144200Y1200800D01*
X144533Y1200758D01*
X144825Y1200592D01*
X145075Y1200342D01*
X145242Y1200050D01*
X145325Y1199717D01*
Y1199383D01*
X145242Y1199050D01*
X145075Y1198758D01*
X144825Y1198508D01*
X144533Y1198342D01*
X144200Y1198300D01*
G01X144533Y1198967D02*
X145033Y1198300D01*
G01X147300D02*
X147592Y1198342D01*
X147925Y1198467D01*
X148133Y1198675D01*
X148217Y1198967D01*
X148133Y1199258D01*
X147883Y1199508D01*
X147508Y1199633D01*
X147092D01*
X146842Y1199717D01*
X146633Y1199925D01*
X146550Y1200217D01*
X146675Y1200508D01*
X146967Y1200717D01*
X147300Y1200800D01*
X147633Y1200717D01*
X147925Y1200508D01*
X148050Y1200217D01*
X147967Y1199925D01*
X147758Y1199717D01*
X147508Y1199633D01*
X147092D01*
X146717Y1199508D01*
X146467Y1199258D01*
X146383Y1198967D01*
X146467Y1198675D01*
X146675Y1198467D01*
X147008Y1198342D01*
X147300Y1198300D01*
G01X149608Y1200383D02*
X149858Y1200633D01*
X150150Y1200758D01*
X150483Y1200800D01*
X150900Y1200717D01*
X151192Y1200508D01*
X151275Y1200258D01*
X151233Y1200008D01*
X151067Y1199800D01*
X150233Y1199383D01*
X149858Y1199092D01*
X149608Y1198675D01*
X149525Y1198300D01*
X151275D01*
G01X133000Y1206100D02*
X147000D01*
G01X133000Y1219100D02*
Y1206100D01*
G01X147000D02*
Y1219100D01*
G01X172400Y1210867D02*
X169900D01*
Y1211908D01*
X170025Y1212242D01*
X170192Y1212450D01*
X170525Y1212533D01*
X170858Y1212450D01*
X171067Y1212200D01*
X171192Y1211908D01*
Y1210867D01*
G01Y1211908D02*
X172400Y1212533D01*
G01X172108Y1214092D02*
X172317Y1214383D01*
X172400Y1214717D01*
X172317Y1215050D01*
X172067Y1215342D01*
X171692Y1215550D01*
X171317Y1215633D01*
X170858D01*
X170483Y1215550D01*
X170150Y1215342D01*
X169983Y1215092D01*
X169900Y1214800D01*
X169983Y1214467D01*
X170150Y1214217D01*
X170400Y1214050D01*
X170733Y1213967D01*
X171025Y1214050D01*
X171317Y1214258D01*
X171483Y1214508D01*
X171525Y1214800D01*
X171442Y1215133D01*
X171233Y1215383D01*
X170858Y1215633D01*
G01X172400Y1217817D02*
X171858Y1217900D01*
X171400Y1218025D01*
X170983Y1218192D01*
X170525Y1218400D01*
X169900Y1218733D01*
Y1217067D01*
G01X172025Y1220083D02*
X172233Y1220333D01*
X172358Y1220625D01*
X172400Y1221000D01*
X172317Y1221375D01*
X172150Y1221667D01*
X171858Y1221875D01*
X171525Y1221917D01*
X171192Y1221833D01*
X170983Y1221625D01*
X170817Y1221333D01*
X170775Y1221042D01*
X170817Y1220750D01*
X170983Y1220375D01*
X169900Y1220500D01*
Y1221625D01*
G01X170317Y1223308D02*
X170067Y1223558D01*
X169942Y1223850D01*
X169900Y1224183D01*
X169983Y1224600D01*
X170192Y1224892D01*
X170442Y1224975D01*
X170692Y1224933D01*
X170900Y1224767D01*
X171317Y1223933D01*
X171608Y1223558D01*
X172025Y1223308D01*
X172400Y1223225D01*
Y1224975D01*
G01X111650Y1179450D02*
X115650D01*
Y1186850D01*
G01X119900Y1148000D02*
X115900D01*
Y1140600D01*
G01X120400D02*
X124400D01*
Y1148000D01*
G01X167900Y1210867D02*
X165400D01*
Y1211908D01*
X165525Y1212242D01*
X165692Y1212450D01*
X166025Y1212533D01*
X166358Y1212450D01*
X166567Y1212200D01*
X166692Y1211908D01*
Y1210867D01*
G01Y1211908D02*
X167900Y1212533D01*
G01X167608Y1214092D02*
X167817Y1214383D01*
X167900Y1214717D01*
X167817Y1215050D01*
X167567Y1215342D01*
X167192Y1215550D01*
X166817Y1215633D01*
X166358D01*
X165983Y1215550D01*
X165650Y1215342D01*
X165483Y1215092D01*
X165400Y1214800D01*
X165483Y1214467D01*
X165650Y1214217D01*
X165900Y1214050D01*
X166233Y1213967D01*
X166525Y1214050D01*
X166817Y1214258D01*
X166983Y1214508D01*
X167025Y1214800D01*
X166942Y1215133D01*
X166733Y1215383D01*
X166358Y1215633D01*
G01X167900Y1217817D02*
X167358Y1217900D01*
X166900Y1218025D01*
X166483Y1218192D01*
X166025Y1218400D01*
X165400Y1218733D01*
Y1217067D01*
G01X167900Y1220917D02*
X167358Y1221000D01*
X166900Y1221125D01*
X166483Y1221292D01*
X166025Y1221500D01*
X165400Y1221833D01*
Y1220167D01*
G01X167900Y1224100D02*
X165400D01*
X165900Y1223600D01*
G01X167900D02*
Y1224600D01*
G01X162267Y1206200D02*
Y1208700D01*
X163308D01*
X163642Y1208575D01*
X163850Y1208408D01*
X163933Y1208075D01*
X163850Y1207742D01*
X163600Y1207533D01*
X163308Y1207408D01*
X162267D01*
G01X163308D02*
X163933Y1206200D01*
G01X165492Y1206492D02*
X165783Y1206283D01*
X166117Y1206200D01*
X166450Y1206283D01*
X166742Y1206533D01*
X166950Y1206908D01*
X167033Y1207283D01*
Y1207742D01*
X166950Y1208117D01*
X166742Y1208450D01*
X166492Y1208617D01*
X166200Y1208700D01*
X165867Y1208617D01*
X165617Y1208450D01*
X165450Y1208200D01*
X165367Y1207867D01*
X165450Y1207575D01*
X165658Y1207283D01*
X165908Y1207117D01*
X166200Y1207075D01*
X166533Y1207158D01*
X166783Y1207367D01*
X167033Y1207742D01*
G01X169300Y1206200D02*
X169592Y1206242D01*
X169925Y1206367D01*
X170133Y1206575D01*
X170217Y1206867D01*
X170133Y1207158D01*
X169883Y1207408D01*
X169508Y1207533D01*
X169092D01*
X168842Y1207617D01*
X168633Y1207825D01*
X168550Y1208117D01*
X168675Y1208408D01*
X168967Y1208617D01*
X169300Y1208700D01*
X169633Y1208617D01*
X169925Y1208408D01*
X170050Y1208117D01*
X169967Y1207825D01*
X169758Y1207617D01*
X169508Y1207533D01*
X169092D01*
X168717Y1207408D01*
X168467Y1207158D01*
X168383Y1206867D01*
X168467Y1206575D01*
X168675Y1206367D01*
X169008Y1206242D01*
X169300Y1206200D01*
G01X171483Y1206575D02*
X171733Y1206367D01*
X172025Y1206242D01*
X172400Y1206200D01*
X172775Y1206283D01*
X173067Y1206450D01*
X173275Y1206742D01*
X173317Y1207075D01*
X173233Y1207408D01*
X173025Y1207617D01*
X172733Y1207783D01*
X172442Y1207825D01*
X172150Y1207783D01*
X171775Y1207617D01*
X171900Y1208700D01*
X173025D01*
G01X175500Y1206200D02*
Y1208700D01*
X175000Y1208200D01*
G01Y1206200D02*
X176000D01*
G01X160525Y1206725D02*
Y1210725D01*
X153125D01*
G01X124867Y1198300D02*
Y1200800D01*
X125908D01*
X126242Y1200675D01*
X126450Y1200508D01*
X126533Y1200175D01*
X126450Y1199842D01*
X126200Y1199633D01*
X125908Y1199508D01*
X124867D01*
G01X125908D02*
X126533Y1198300D01*
G01X128092Y1198592D02*
X128383Y1198383D01*
X128717Y1198300D01*
X129050Y1198383D01*
X129342Y1198633D01*
X129550Y1199008D01*
X129633Y1199383D01*
Y1199842D01*
X129550Y1200217D01*
X129342Y1200550D01*
X129092Y1200717D01*
X128800Y1200800D01*
X128467Y1200717D01*
X128217Y1200550D01*
X128050Y1200300D01*
X127967Y1199967D01*
X128050Y1199675D01*
X128258Y1199383D01*
X128508Y1199217D01*
X128800Y1199175D01*
X129133Y1199258D01*
X129383Y1199467D01*
X129633Y1199842D01*
G01X131900Y1198300D02*
X132192Y1198342D01*
X132525Y1198467D01*
X132733Y1198675D01*
X132817Y1198967D01*
X132733Y1199258D01*
X132483Y1199508D01*
X132108Y1199633D01*
X131692D01*
X131442Y1199717D01*
X131233Y1199925D01*
X131150Y1200217D01*
X131275Y1200508D01*
X131567Y1200717D01*
X131900Y1200800D01*
X132233Y1200717D01*
X132525Y1200508D01*
X132650Y1200217D01*
X132567Y1199925D01*
X132358Y1199717D01*
X132108Y1199633D01*
X131692D01*
X131317Y1199508D01*
X131067Y1199258D01*
X130983Y1198967D01*
X131067Y1198675D01*
X131275Y1198467D01*
X131608Y1198342D01*
X131900Y1198300D01*
G01X134083Y1198675D02*
X134333Y1198467D01*
X134625Y1198342D01*
X135000Y1198300D01*
X135375Y1198383D01*
X135667Y1198550D01*
X135875Y1198842D01*
X135917Y1199175D01*
X135833Y1199508D01*
X135625Y1199717D01*
X135333Y1199883D01*
X135042Y1199925D01*
X134750Y1199883D01*
X134375Y1199717D01*
X134500Y1200800D01*
X135625D01*
G01X137308Y1200383D02*
X137558Y1200633D01*
X137850Y1200758D01*
X138183Y1200800D01*
X138600Y1200717D01*
X138892Y1200508D01*
X138975Y1200258D01*
X138933Y1200008D01*
X138767Y1199800D01*
X137933Y1199383D01*
X137558Y1199092D01*
X137308Y1198675D01*
X137225Y1198300D01*
X138975D01*
G01X132350Y1218050D02*
X128350D01*
Y1210650D01*
G01X136017Y1191200D02*
Y1193700D01*
X137058D01*
X137392Y1193575D01*
X137600Y1193408D01*
X137683Y1193075D01*
X137600Y1192742D01*
X137350Y1192533D01*
X137058Y1192408D01*
X136017D01*
G01X137058D02*
X137683Y1191200D01*
G01X139242Y1191492D02*
X139533Y1191283D01*
X139867Y1191200D01*
X140200Y1191283D01*
X140492Y1191533D01*
X140700Y1191908D01*
X140783Y1192283D01*
Y1192742D01*
X140700Y1193117D01*
X140492Y1193450D01*
X140242Y1193617D01*
X139950Y1193700D01*
X139617Y1193617D01*
X139367Y1193450D01*
X139200Y1193200D01*
X139117Y1192867D01*
X139200Y1192575D01*
X139408Y1192283D01*
X139658Y1192117D01*
X139950Y1192075D01*
X140283Y1192158D01*
X140533Y1192367D01*
X140783Y1192742D01*
G01X143050Y1191200D02*
X143342Y1191242D01*
X143675Y1191367D01*
X143883Y1191575D01*
X143967Y1191867D01*
X143883Y1192158D01*
X143633Y1192408D01*
X143258Y1192533D01*
X142842D01*
X142592Y1192617D01*
X142383Y1192825D01*
X142300Y1193117D01*
X142425Y1193408D01*
X142717Y1193617D01*
X143050Y1193700D01*
X143383Y1193617D01*
X143675Y1193408D01*
X143800Y1193117D01*
X143717Y1192825D01*
X143508Y1192617D01*
X143258Y1192533D01*
X142842D01*
X142467Y1192408D01*
X142217Y1192158D01*
X142133Y1191867D01*
X142217Y1191575D01*
X142425Y1191367D01*
X142758Y1191242D01*
X143050Y1191200D01*
G01X145358Y1193283D02*
X145608Y1193533D01*
X145900Y1193658D01*
X146233Y1193700D01*
X146650Y1193617D01*
X146942Y1193408D01*
X147025Y1193158D01*
X146983Y1192908D01*
X146817Y1192700D01*
X145983Y1192283D01*
X145608Y1191992D01*
X145358Y1191575D01*
X145275Y1191200D01*
X147025D01*
G01X148458Y1192242D02*
X148750Y1192533D01*
X149000Y1192700D01*
X149333Y1192783D01*
X149625Y1192700D01*
X149833Y1192533D01*
X150000Y1192283D01*
X150042Y1191992D01*
X150000Y1191742D01*
X149833Y1191492D01*
X149583Y1191283D01*
X149292Y1191200D01*
X148958Y1191283D01*
X148667Y1191533D01*
X148500Y1191908D01*
X148458Y1192325D01*
X148542Y1192867D01*
X148667Y1193158D01*
X148875Y1193450D01*
X149167Y1193658D01*
X149458Y1193700D01*
X149750Y1193617D01*
X149958Y1193408D01*
G01X148200Y1182400D02*
X143000D01*
G01X148200Y1189400D02*
X140400D01*
G01X148200Y1182400D02*
Y1189400D01*
G01X134800Y1182400D02*
X143500D01*
G01X134800Y1189400D02*
Y1182400D01*
G01X141200Y1189400D02*
X134800D01*
G01X119200Y1172200D02*
X117200Y1170200D01*
X115200Y1172200D01*
G01X111600D02*
Y1153000D01*
X122800D01*
Y1172200D01*
X111600D01*
G01X168967Y1187300D02*
Y1189800D01*
X170008D01*
X170342Y1189675D01*
X170550Y1189508D01*
X170633Y1189175D01*
X170550Y1188842D01*
X170300Y1188633D01*
X170008Y1188508D01*
X168967D01*
G01X170008D02*
X170633Y1187300D01*
G01X172192Y1187592D02*
X172483Y1187383D01*
X172817Y1187300D01*
X173150Y1187383D01*
X173442Y1187633D01*
X173650Y1188008D01*
X173733Y1188383D01*
Y1188842D01*
X173650Y1189217D01*
X173442Y1189550D01*
X173192Y1189717D01*
X172900Y1189800D01*
X172567Y1189717D01*
X172317Y1189550D01*
X172150Y1189300D01*
X172067Y1188967D01*
X172150Y1188675D01*
X172358Y1188383D01*
X172608Y1188217D01*
X172900Y1188175D01*
X173233Y1188258D01*
X173483Y1188467D01*
X173733Y1188842D01*
G01X175208Y1189383D02*
X175458Y1189633D01*
X175750Y1189758D01*
X176083Y1189800D01*
X176500Y1189717D01*
X176792Y1189508D01*
X176875Y1189258D01*
X176833Y1189008D01*
X176667Y1188800D01*
X175833Y1188383D01*
X175458Y1188092D01*
X175208Y1187675D01*
X175125Y1187300D01*
X176875D01*
G01X178183Y1187675D02*
X178433Y1187467D01*
X178725Y1187342D01*
X179100Y1187300D01*
X179475Y1187383D01*
X179767Y1187550D01*
X179975Y1187842D01*
X180017Y1188175D01*
X179933Y1188508D01*
X179725Y1188717D01*
X179433Y1188883D01*
X179142Y1188925D01*
X178850Y1188883D01*
X178475Y1188717D01*
X178600Y1189800D01*
X179725D01*
G01X182200D02*
X181867Y1189717D01*
X181617Y1189508D01*
X181450Y1189258D01*
X181325Y1188925D01*
X181283Y1188550D01*
X181325Y1188175D01*
X181450Y1187842D01*
X181617Y1187592D01*
X181867Y1187383D01*
X182200Y1187300D01*
X182533Y1187383D01*
X182783Y1187592D01*
X182950Y1187842D01*
X183075Y1188175D01*
X183117Y1188550D01*
X183075Y1188925D01*
X182950Y1189258D01*
X182783Y1189508D01*
X182533Y1189717D01*
X182200Y1189800D01*
G01X182300Y1173000D02*
Y1186000D01*
G01X156300Y1173000D02*
X182300D01*
G01X156300Y1186000D02*
Y1173000D01*
G01X182300Y1186000D02*
X156300D01*
G01X115917Y1174000D02*
Y1176500D01*
X116917D01*
X117250Y1176375D01*
X117500Y1176083D01*
X117583Y1175750D01*
X117500Y1175417D01*
X117292Y1175167D01*
X116917Y1175042D01*
X115917D01*
G01X120767Y1176292D02*
X120517Y1176417D01*
X120225Y1176500D01*
X119892D01*
X119517Y1176375D01*
X119225Y1176167D01*
X119017Y1175917D01*
X118850Y1175500D01*
X118808Y1175125D01*
X118892Y1174750D01*
X119017Y1174500D01*
X119267Y1174250D01*
X119558Y1174083D01*
X119850Y1174000D01*
X120142D01*
X120433Y1174083D01*
X120683Y1174208D01*
X120892Y1174375D01*
G01X122950Y1174000D02*
Y1176500D01*
X122450Y1176000D01*
G01Y1174000D02*
X123450D01*
G01X125258Y1176083D02*
X125508Y1176333D01*
X125800Y1176458D01*
X126133Y1176500D01*
X126550Y1176417D01*
X126842Y1176208D01*
X126925Y1175958D01*
X126883Y1175708D01*
X126717Y1175500D01*
X125883Y1175083D01*
X125508Y1174792D01*
X125258Y1174375D01*
X125175Y1174000D01*
X126925D01*
G01X129650D02*
Y1176500D01*
X128108Y1174708D01*
X130192D01*
G01X131333Y1174375D02*
X131583Y1174167D01*
X131875Y1174042D01*
X132250Y1174000D01*
X132625Y1174083D01*
X132917Y1174250D01*
X133125Y1174542D01*
X133167Y1174875D01*
X133083Y1175208D01*
X132875Y1175417D01*
X132583Y1175583D01*
X132292Y1175625D01*
X132000Y1175583D01*
X131625Y1175417D01*
X131750Y1176500D01*
X132875D01*
G01X145150Y1179350D02*
Y1160650D01*
X134850D01*
Y1179350D01*
X145150D01*
G01X132650Y1141250D02*
Y1159950D01*
X142950D01*
Y1141250D01*
X132650D01*
G01X144597Y1256407D02*
X144472Y1256157D01*
X144389Y1255865D01*
Y1255532D01*
X144514Y1255157D01*
X144722Y1254865D01*
X144972Y1254657D01*
X145389Y1254490D01*
X145764Y1254448D01*
X146139Y1254532D01*
X146389Y1254657D01*
X146639Y1254907D01*
X146806Y1255198D01*
X146889Y1255490D01*
Y1255782D01*
X146806Y1256073D01*
X146681Y1256323D01*
X146514Y1256532D01*
G01X146389Y1257673D02*
X146681Y1257923D01*
X146847Y1258257D01*
X146889Y1258632D01*
X146847Y1258965D01*
X146639Y1259298D01*
X146389Y1259507D01*
X146139Y1259548D01*
X145847Y1259465D01*
X145639Y1259173D01*
X145556Y1258882D01*
Y1258507D01*
G01Y1258882D02*
X145431Y1259132D01*
X145222Y1259340D01*
X144972Y1259423D01*
X144722Y1259340D01*
X144514Y1259132D01*
X144389Y1258757D01*
X144431Y1258382D01*
X144597Y1258007D01*
G01X146597Y1260982D02*
X146806Y1261273D01*
X146889Y1261607D01*
X146806Y1261940D01*
X146556Y1262232D01*
X146181Y1262440D01*
X145806Y1262523D01*
X145347D01*
X144972Y1262440D01*
X144639Y1262232D01*
X144472Y1261982D01*
X144389Y1261690D01*
X144472Y1261357D01*
X144639Y1261107D01*
X144889Y1260940D01*
X145222Y1260857D01*
X145514Y1260940D01*
X145806Y1261148D01*
X145972Y1261398D01*
X146014Y1261690D01*
X145931Y1262023D01*
X145722Y1262273D01*
X145347Y1262523D01*
G01X146389Y1263873D02*
X146681Y1264123D01*
X146847Y1264457D01*
X146889Y1264832D01*
X146847Y1265165D01*
X146639Y1265498D01*
X146389Y1265707D01*
X146139Y1265748D01*
X145847Y1265665D01*
X145639Y1265373D01*
X145556Y1265082D01*
Y1264707D01*
G01Y1265082D02*
X145431Y1265332D01*
X145222Y1265540D01*
X144972Y1265623D01*
X144722Y1265540D01*
X144514Y1265332D01*
X144389Y1264957D01*
X144431Y1264582D01*
X144597Y1264207D01*
G01X167200Y1229000D02*
X167158Y1228667D01*
X166992Y1228375D01*
X166742Y1228125D01*
X166450Y1227958D01*
X166117Y1227875D01*
X165783D01*
X165450Y1227958D01*
X165158Y1228125D01*
X164908Y1228375D01*
X164742Y1228667D01*
X164700Y1229000D01*
X164742Y1229333D01*
X164908Y1229625D01*
X165158Y1229875D01*
X165450Y1230042D01*
X165783Y1230125D01*
X166117D01*
X166450Y1230042D01*
X166742Y1229875D01*
X166992Y1229625D01*
X167158Y1229333D01*
X167200Y1229000D01*
G01X166533Y1229333D02*
X167200Y1229833D01*
G01Y1232100D02*
X164700D01*
X165200Y1231600D01*
G01X167200D02*
Y1232600D01*
G01X166908Y1234492D02*
X167117Y1234783D01*
X167200Y1235117D01*
X167117Y1235450D01*
X166867Y1235742D01*
X166492Y1235950D01*
X166117Y1236033D01*
X165658D01*
X165283Y1235950D01*
X164950Y1235742D01*
X164783Y1235492D01*
X164700Y1235200D01*
X164783Y1234867D01*
X164950Y1234617D01*
X165200Y1234450D01*
X165533Y1234367D01*
X165825Y1234450D01*
X166117Y1234658D01*
X166283Y1234908D01*
X166325Y1235200D01*
X166242Y1235533D01*
X166033Y1235783D01*
X165658Y1236033D01*
G01X142200Y1234600D02*
Y1220600D01*
G01X155200Y1234600D02*
X142200D01*
G01X155200Y1220600D02*
Y1234600D01*
G01X142200Y1220600D02*
X155200D01*
G01X127500Y1219100D02*
X113500D01*
G01X147000D02*
X133000D01*
G01X143607Y1250110D02*
Y1252610D01*
X144648D01*
X144982Y1252485D01*
X145190Y1252318D01*
X145273Y1251985D01*
X145190Y1251652D01*
X144940Y1251443D01*
X144648Y1251318D01*
X143607D01*
G01X144648D02*
X145273Y1250110D01*
G01X147540D02*
Y1252610D01*
X147040Y1252110D01*
G01Y1250110D02*
X148040D01*
G01X151140D02*
Y1252610D01*
X149598Y1250818D01*
X151682D01*
G01X153032Y1250402D02*
X153323Y1250193D01*
X153657Y1250110D01*
X153990Y1250193D01*
X154282Y1250443D01*
X154490Y1250818D01*
X154573Y1251193D01*
Y1251652D01*
X154490Y1252027D01*
X154282Y1252360D01*
X154032Y1252527D01*
X153740Y1252610D01*
X153407Y1252527D01*
X153157Y1252360D01*
X152990Y1252110D01*
X152907Y1251777D01*
X152990Y1251485D01*
X153198Y1251193D01*
X153448Y1251027D01*
X153740Y1250985D01*
X154073Y1251068D01*
X154323Y1251277D01*
X154573Y1251652D01*
G01X143000Y1239600D02*
Y1235600D01*
X150400D01*
G01X156319Y1254887D02*
X153819D01*
Y1255928D01*
X153944Y1256262D01*
X154111Y1256470D01*
X154444Y1256553D01*
X154777Y1256470D01*
X154986Y1256220D01*
X155111Y1255928D01*
Y1254887D01*
G01Y1255928D02*
X156319Y1256553D01*
G01X155944Y1257903D02*
X156152Y1258153D01*
X156277Y1258445D01*
X156319Y1258820D01*
X156236Y1259195D01*
X156069Y1259487D01*
X155777Y1259695D01*
X155444Y1259737D01*
X155111Y1259653D01*
X154902Y1259445D01*
X154736Y1259153D01*
X154694Y1258862D01*
X154736Y1258570D01*
X154902Y1258195D01*
X153819Y1258320D01*
Y1259445D01*
G01X155277Y1261128D02*
X154986Y1261420D01*
X154819Y1261670D01*
X154736Y1262003D01*
X154819Y1262295D01*
X154986Y1262503D01*
X155236Y1262670D01*
X155527Y1262712D01*
X155777Y1262670D01*
X156027Y1262503D01*
X156236Y1262253D01*
X156319Y1261962D01*
X156236Y1261628D01*
X155986Y1261337D01*
X155611Y1261170D01*
X155194Y1261128D01*
X154652Y1261212D01*
X154361Y1261337D01*
X154069Y1261545D01*
X153861Y1261837D01*
X153819Y1262128D01*
X153902Y1262420D01*
X154111Y1262628D01*
G01X154236Y1264228D02*
X153986Y1264478D01*
X153861Y1264770D01*
X153819Y1265103D01*
X153902Y1265520D01*
X154111Y1265812D01*
X154361Y1265895D01*
X154611Y1265853D01*
X154819Y1265687D01*
X155236Y1264853D01*
X155527Y1264478D01*
X155944Y1264228D01*
X156319Y1264145D01*
Y1265895D01*
G01X151200Y1239900D02*
X155200D01*
Y1247300D01*
G01X151819Y1254887D02*
X149319D01*
Y1255928D01*
X149444Y1256262D01*
X149611Y1256470D01*
X149944Y1256553D01*
X150277Y1256470D01*
X150486Y1256220D01*
X150611Y1255928D01*
Y1254887D01*
G01Y1255928D02*
X151819Y1256553D01*
G01X151444Y1257903D02*
X151652Y1258153D01*
X151777Y1258445D01*
X151819Y1258820D01*
X151736Y1259195D01*
X151569Y1259487D01*
X151277Y1259695D01*
X150944Y1259737D01*
X150611Y1259653D01*
X150402Y1259445D01*
X150236Y1259153D01*
X150194Y1258862D01*
X150236Y1258570D01*
X150402Y1258195D01*
X149319Y1258320D01*
Y1259445D01*
G01X151819Y1261837D02*
X151277Y1261920D01*
X150819Y1262045D01*
X150402Y1262212D01*
X149944Y1262420D01*
X149319Y1262753D01*
Y1261087D01*
G01X151819Y1264937D02*
X151277Y1265020D01*
X150819Y1265145D01*
X150402Y1265312D01*
X149944Y1265520D01*
X149319Y1265853D01*
Y1264187D01*
G01X150700Y1247300D02*
X146700D01*
Y1239900D01*
G01X156000Y1219200D02*
X152000D01*
Y1211800D01*
G01X115517Y1272000D02*
Y1274500D01*
X116558D01*
X116892Y1274375D01*
X117100Y1274208D01*
X117183Y1273875D01*
X117100Y1273542D01*
X116850Y1273333D01*
X116558Y1273208D01*
X115517D01*
G01X116558D02*
X117183Y1272000D01*
G01X119950D02*
Y1274500D01*
X118408Y1272708D01*
X120492D01*
G01X122550Y1272000D02*
Y1274500D01*
X122050Y1274000D01*
G01Y1272000D02*
X123050D01*
G01X125650Y1274500D02*
X125317Y1274417D01*
X125067Y1274208D01*
X124900Y1273958D01*
X124775Y1273625D01*
X124733Y1273250D01*
X124775Y1272875D01*
X124900Y1272542D01*
X125067Y1272292D01*
X125317Y1272083D01*
X125650Y1272000D01*
X125983Y1272083D01*
X126233Y1272292D01*
X126400Y1272542D01*
X126525Y1272875D01*
X126567Y1273250D01*
X126525Y1273625D01*
X126400Y1273958D01*
X126233Y1274208D01*
X125983Y1274417D01*
X125650Y1274500D01*
G01X113800Y1267500D02*
Y1263500D01*
X121200D01*
G01X115517Y1268000D02*
Y1270500D01*
X116558D01*
X116892Y1270375D01*
X117100Y1270208D01*
X117183Y1269875D01*
X117100Y1269542D01*
X116850Y1269333D01*
X116558Y1269208D01*
X115517D01*
G01X116558D02*
X117183Y1268000D01*
G01X119950D02*
Y1270500D01*
X118408Y1268708D01*
X120492D01*
G01X122550Y1268000D02*
Y1270500D01*
X122050Y1270000D01*
G01Y1268000D02*
X123050D01*
G01X124858Y1270083D02*
X125108Y1270333D01*
X125400Y1270458D01*
X125733Y1270500D01*
X126150Y1270417D01*
X126442Y1270208D01*
X126525Y1269958D01*
X126483Y1269708D01*
X126317Y1269500D01*
X125483Y1269083D01*
X125108Y1268792D01*
X124858Y1268375D01*
X124775Y1268000D01*
X126525D01*
G01X113800Y1262500D02*
Y1258500D01*
X121200D01*
G01X147500Y1211800D02*
X151500D01*
Y1219200D01*
G01X136167Y1253875D02*
X136375Y1254208D01*
X136500Y1254583D01*
Y1254917D01*
X136375Y1255250D01*
X136167Y1255500D01*
X135875Y1255625D01*
X135583Y1255542D01*
X135333Y1255333D01*
X135167Y1254958D01*
X135083Y1254458D01*
X134917Y1254167D01*
X134625Y1254042D01*
X134333Y1254125D01*
X134125Y1254333D01*
X134000Y1254625D01*
Y1254917D01*
X134083Y1255208D01*
X134292Y1255458D01*
G01X136500Y1257017D02*
X134000D01*
Y1258058D01*
X134125Y1258392D01*
X134292Y1258600D01*
X134625Y1258683D01*
X134958Y1258600D01*
X135167Y1258350D01*
X135292Y1258058D01*
Y1257017D01*
G01Y1258058D02*
X136500Y1258683D01*
G01Y1260950D02*
X134000D01*
X134500Y1260450D01*
G01X136500D02*
Y1261450D01*
G01Y1264050D02*
X134000D01*
X134500Y1263550D01*
G01X136500D02*
Y1264550D01*
G01Y1267150D02*
X134000D01*
X134500Y1266650D01*
G01X136500D02*
Y1267650D01*
G01X136000Y1269333D02*
X136292Y1269583D01*
X136458Y1269917D01*
X136500Y1270292D01*
X136458Y1270625D01*
X136250Y1270958D01*
X136000Y1271167D01*
X135750Y1271208D01*
X135458Y1271125D01*
X135250Y1270833D01*
X135167Y1270542D01*
Y1270167D01*
G01Y1270542D02*
X135042Y1270792D01*
X134833Y1271000D01*
X134583Y1271083D01*
X134333Y1271000D01*
X134125Y1270792D01*
X134000Y1270417D01*
X134042Y1270042D01*
X134208Y1269667D01*
G01X124000Y1250100D02*
X128000D01*
Y1257500D01*
G01X132167Y1254375D02*
X132375Y1254708D01*
X132500Y1255083D01*
Y1255417D01*
X132375Y1255750D01*
X132167Y1256000D01*
X131875Y1256125D01*
X131583Y1256042D01*
X131333Y1255833D01*
X131167Y1255458D01*
X131083Y1254958D01*
X130917Y1254667D01*
X130625Y1254542D01*
X130333Y1254625D01*
X130125Y1254833D01*
X130000Y1255125D01*
Y1255417D01*
X130083Y1255708D01*
X130292Y1255958D01*
G01X132500Y1257517D02*
X130000D01*
Y1258558D01*
X130125Y1258892D01*
X130292Y1259100D01*
X130625Y1259183D01*
X130958Y1259100D01*
X131167Y1258850D01*
X131292Y1258558D01*
Y1257517D01*
G01Y1258558D02*
X132500Y1259183D01*
G01Y1261450D02*
X130000D01*
X130500Y1260950D01*
G01X132500D02*
Y1261950D01*
G01Y1264550D02*
X130000D01*
X130500Y1264050D01*
G01X132500D02*
Y1265050D01*
G01Y1267650D02*
X130000D01*
X130500Y1267150D01*
G01X132500D02*
Y1268150D01*
G01Y1271250D02*
X130000D01*
X131792Y1269708D01*
Y1271792D01*
G01X123500Y1257500D02*
X119500D01*
Y1250100D01*
G01X133483Y1251000D02*
Y1249208D01*
X133650Y1248833D01*
X133983Y1248583D01*
X134400Y1248500D01*
X134817Y1248583D01*
X135150Y1248833D01*
X135317Y1249208D01*
Y1251000D01*
G01X136708Y1250583D02*
X136958Y1250833D01*
X137250Y1250958D01*
X137583Y1251000D01*
X138000Y1250917D01*
X138292Y1250708D01*
X138375Y1250458D01*
X138333Y1250208D01*
X138167Y1250000D01*
X137333Y1249583D01*
X136958Y1249292D01*
X136708Y1248875D01*
X136625Y1248500D01*
X138375D01*
G01X140600Y1251000D02*
X140267Y1250917D01*
X140017Y1250708D01*
X139850Y1250458D01*
X139725Y1250125D01*
X139683Y1249750D01*
X139725Y1249375D01*
X139850Y1249042D01*
X140017Y1248792D01*
X140267Y1248583D01*
X140600Y1248500D01*
X140933Y1248583D01*
X141183Y1248792D01*
X141350Y1249042D01*
X141475Y1249375D01*
X141517Y1249750D01*
X141475Y1250125D01*
X141350Y1250458D01*
X141183Y1250708D01*
X140933Y1250917D01*
X140600Y1251000D01*
G01X125200Y1225800D02*
X127200Y1227800D01*
X129200Y1225800D01*
G01X132800D02*
Y1245000D01*
X121600D01*
Y1225800D01*
X132800D01*
G01X113417Y1221500D02*
Y1224000D01*
X114417D01*
X114750Y1223875D01*
X115000Y1223583D01*
X115083Y1223250D01*
X115000Y1222917D01*
X114792Y1222667D01*
X114417Y1222542D01*
X113417D01*
G01X118267Y1223792D02*
X118017Y1223917D01*
X117725Y1224000D01*
X117392D01*
X117017Y1223875D01*
X116725Y1223667D01*
X116517Y1223417D01*
X116350Y1223000D01*
X116308Y1222625D01*
X116392Y1222250D01*
X116517Y1222000D01*
X116767Y1221750D01*
X117058Y1221583D01*
X117350Y1221500D01*
X117642D01*
X117933Y1221583D01*
X118183Y1221708D01*
X118392Y1221875D01*
G01X120450Y1221500D02*
Y1224000D01*
X119950Y1223500D01*
G01Y1221500D02*
X120950D01*
G01X122758Y1223583D02*
X123008Y1223833D01*
X123300Y1223958D01*
X123633Y1224000D01*
X124050Y1223917D01*
X124342Y1223708D01*
X124425Y1223458D01*
X124383Y1223208D01*
X124217Y1223000D01*
X123383Y1222583D01*
X123008Y1222292D01*
X122758Y1221875D01*
X122675Y1221500D01*
X124425D01*
G01X125858Y1223583D02*
X126108Y1223833D01*
X126400Y1223958D01*
X126733Y1224000D01*
X127150Y1223917D01*
X127442Y1223708D01*
X127525Y1223458D01*
X127483Y1223208D01*
X127317Y1223000D01*
X126483Y1222583D01*
X126108Y1222292D01*
X125858Y1221875D01*
X125775Y1221500D01*
X127525D01*
G01X129750Y1224000D02*
X129417Y1223917D01*
X129167Y1223708D01*
X129000Y1223458D01*
X128875Y1223125D01*
X128833Y1222750D01*
X128875Y1222375D01*
X129000Y1222042D01*
X129167Y1221792D01*
X129417Y1221583D01*
X129750Y1221500D01*
X130083Y1221583D01*
X130333Y1221792D01*
X130500Y1222042D01*
X130625Y1222375D01*
X130667Y1222750D01*
X130625Y1223125D01*
X130500Y1223458D01*
X130333Y1223708D01*
X130083Y1223917D01*
X129750Y1224000D01*
G01X171334Y1228483D02*
X168834D01*
Y1229317D01*
X168959Y1229650D01*
X169126Y1229900D01*
X169376Y1230108D01*
X169667Y1230275D01*
X170084Y1230317D01*
X170501Y1230275D01*
X170792Y1230108D01*
X171042Y1229900D01*
X171209Y1229650D01*
X171334Y1229317D01*
Y1228483D01*
G01X169251Y1231708D02*
X169001Y1231958D01*
X168876Y1232250D01*
X168834Y1232583D01*
X168917Y1233000D01*
X169126Y1233292D01*
X169376Y1233375D01*
X169626Y1233333D01*
X169834Y1233167D01*
X170251Y1232333D01*
X170542Y1231958D01*
X170959Y1231708D01*
X171334Y1231625D01*
Y1233375D01*
G01X171042Y1234892D02*
X171251Y1235183D01*
X171334Y1235517D01*
X171251Y1235850D01*
X171001Y1236142D01*
X170626Y1236350D01*
X170251Y1236433D01*
X169792D01*
X169417Y1236350D01*
X169084Y1236142D01*
X168917Y1235892D01*
X168834Y1235600D01*
X168917Y1235267D01*
X169084Y1235017D01*
X169334Y1234850D01*
X169667Y1234767D01*
X169959Y1234850D01*
X170251Y1235058D01*
X170417Y1235308D01*
X170459Y1235600D01*
X170376Y1235933D01*
X170167Y1236183D01*
X169792Y1236433D01*
G01X163200Y1242600D02*
Y1226500D01*
G01X156200Y1242600D02*
X163200D01*
G01X156200Y1226500D02*
Y1242600D01*
G01X163200Y1226500D02*
X156200D01*
G01X176208Y1337717D02*
X176083Y1337467D01*
X176000Y1337175D01*
Y1336842D01*
X176125Y1336467D01*
X176333Y1336175D01*
X176583Y1335967D01*
X177000Y1335800D01*
X177375Y1335758D01*
X177750Y1335842D01*
X178000Y1335967D01*
X178250Y1336217D01*
X178417Y1336508D01*
X178500Y1336800D01*
Y1337092D01*
X178417Y1337383D01*
X178292Y1337633D01*
X178125Y1337842D01*
G01X178208Y1339192D02*
X178417Y1339483D01*
X178500Y1339817D01*
X178417Y1340150D01*
X178167Y1340442D01*
X177792Y1340650D01*
X177417Y1340733D01*
X176958D01*
X176583Y1340650D01*
X176250Y1340442D01*
X176083Y1340192D01*
X176000Y1339900D01*
X176083Y1339567D01*
X176250Y1339317D01*
X176500Y1339150D01*
X176833Y1339067D01*
X177125Y1339150D01*
X177417Y1339358D01*
X177583Y1339608D01*
X177625Y1339900D01*
X177542Y1340233D01*
X177333Y1340483D01*
X176958Y1340733D01*
G01X178125Y1342083D02*
X178333Y1342333D01*
X178458Y1342625D01*
X178500Y1343000D01*
X178417Y1343375D01*
X178250Y1343667D01*
X177958Y1343875D01*
X177625Y1343917D01*
X177292Y1343833D01*
X177083Y1343625D01*
X176917Y1343333D01*
X176875Y1343042D01*
X176917Y1342750D01*
X177083Y1342375D01*
X176000Y1342500D01*
Y1343625D01*
G01X176417Y1345308D02*
X176167Y1345558D01*
X176042Y1345850D01*
X176000Y1346183D01*
X176083Y1346600D01*
X176292Y1346892D01*
X176542Y1346975D01*
X176792Y1346933D01*
X177000Y1346767D01*
X177417Y1345933D01*
X177708Y1345558D01*
X178125Y1345308D01*
X178500Y1345225D01*
Y1346975D01*
G01Y1349700D02*
X176000D01*
X177792Y1348158D01*
Y1350242D01*
G01X132767Y1352500D02*
Y1355000D01*
X133808D01*
X134142Y1354875D01*
X134350Y1354708D01*
X134433Y1354375D01*
X134350Y1354042D01*
X134100Y1353833D01*
X133808Y1353708D01*
X132767D01*
G01X133808D02*
X134433Y1352500D01*
G01X135992Y1352792D02*
X136283Y1352583D01*
X136617Y1352500D01*
X136950Y1352583D01*
X137242Y1352833D01*
X137450Y1353208D01*
X137533Y1353583D01*
Y1354042D01*
X137450Y1354417D01*
X137242Y1354750D01*
X136992Y1354917D01*
X136700Y1355000D01*
X136367Y1354917D01*
X136117Y1354750D01*
X135950Y1354500D01*
X135867Y1354167D01*
X135950Y1353875D01*
X136158Y1353583D01*
X136408Y1353417D01*
X136700Y1353375D01*
X137033Y1353458D01*
X137283Y1353667D01*
X137533Y1354042D01*
G01X139800Y1352500D02*
X140092Y1352542D01*
X140425Y1352667D01*
X140633Y1352875D01*
X140717Y1353167D01*
X140633Y1353458D01*
X140383Y1353708D01*
X140008Y1353833D01*
X139592D01*
X139342Y1353917D01*
X139133Y1354125D01*
X139050Y1354417D01*
X139175Y1354708D01*
X139467Y1354917D01*
X139800Y1355000D01*
X140133Y1354917D01*
X140425Y1354708D01*
X140550Y1354417D01*
X140467Y1354125D01*
X140258Y1353917D01*
X140008Y1353833D01*
X139592D01*
X139217Y1353708D01*
X138967Y1353458D01*
X138883Y1353167D01*
X138967Y1352875D01*
X139175Y1352667D01*
X139508Y1352542D01*
X139800Y1352500D01*
G01X142108Y1354583D02*
X142358Y1354833D01*
X142650Y1354958D01*
X142983Y1355000D01*
X143400Y1354917D01*
X143692Y1354708D01*
X143775Y1354458D01*
X143733Y1354208D01*
X143567Y1354000D01*
X142733Y1353583D01*
X142358Y1353292D01*
X142108Y1352875D01*
X142025Y1352500D01*
X143775D01*
G01X145208Y1354583D02*
X145458Y1354833D01*
X145750Y1354958D01*
X146083Y1355000D01*
X146500Y1354917D01*
X146792Y1354708D01*
X146875Y1354458D01*
X146833Y1354208D01*
X146667Y1354000D01*
X145833Y1353583D01*
X145458Y1353292D01*
X145208Y1352875D01*
X145125Y1352500D01*
X146875D01*
G01X149259Y1354302D02*
Y1350302D01*
X156659D01*
G01X184000Y1340967D02*
X181500D01*
Y1342008D01*
X181625Y1342342D01*
X181792Y1342550D01*
X182125Y1342633D01*
X182458Y1342550D01*
X182667Y1342300D01*
X182792Y1342008D01*
Y1340967D01*
G01Y1342008D02*
X184000Y1342633D01*
G01X183708Y1344192D02*
X183917Y1344483D01*
X184000Y1344817D01*
X183917Y1345150D01*
X183667Y1345442D01*
X183292Y1345650D01*
X182917Y1345733D01*
X182458D01*
X182083Y1345650D01*
X181750Y1345442D01*
X181583Y1345192D01*
X181500Y1344900D01*
X181583Y1344567D01*
X181750Y1344317D01*
X182000Y1344150D01*
X182333Y1344067D01*
X182625Y1344150D01*
X182917Y1344358D01*
X183083Y1344608D01*
X183125Y1344900D01*
X183042Y1345233D01*
X182833Y1345483D01*
X182458Y1345733D01*
G01X184000Y1348000D02*
X183958Y1348292D01*
X183833Y1348625D01*
X183625Y1348833D01*
X183333Y1348917D01*
X183042Y1348833D01*
X182792Y1348583D01*
X182667Y1348208D01*
Y1347792D01*
X182583Y1347542D01*
X182375Y1347333D01*
X182083Y1347250D01*
X181792Y1347375D01*
X181583Y1347667D01*
X181500Y1348000D01*
X181583Y1348333D01*
X181792Y1348625D01*
X182083Y1348750D01*
X182375Y1348667D01*
X182583Y1348458D01*
X182667Y1348208D01*
Y1347792D01*
X182792Y1347417D01*
X183042Y1347167D01*
X183333Y1347083D01*
X183625Y1347167D01*
X183833Y1347375D01*
X183958Y1347708D01*
X184000Y1348000D01*
G01X181917Y1350308D02*
X181667Y1350558D01*
X181542Y1350850D01*
X181500Y1351183D01*
X181583Y1351600D01*
X181792Y1351892D01*
X182042Y1351975D01*
X182292Y1351933D01*
X182500Y1351767D01*
X182917Y1350933D01*
X183208Y1350558D01*
X183625Y1350308D01*
X184000Y1350225D01*
Y1351975D01*
G01X183500Y1353283D02*
X183792Y1353533D01*
X183958Y1353867D01*
X184000Y1354242D01*
X183958Y1354575D01*
X183750Y1354908D01*
X183500Y1355117D01*
X183250Y1355158D01*
X182958Y1355075D01*
X182750Y1354783D01*
X182667Y1354492D01*
Y1354117D01*
G01Y1354492D02*
X182542Y1354742D01*
X182333Y1354950D01*
X182083Y1355033D01*
X181833Y1354950D01*
X181625Y1354742D01*
X181500Y1354367D01*
X181542Y1353992D01*
X181708Y1353617D01*
G01X157875Y1345233D02*
X158208Y1345025D01*
X158583Y1344900D01*
X158917D01*
X159250Y1345025D01*
X159500Y1345233D01*
X159625Y1345525D01*
X159542Y1345817D01*
X159333Y1346067D01*
X158958Y1346233D01*
X158458Y1346317D01*
X158167Y1346483D01*
X158042Y1346775D01*
X158125Y1347067D01*
X158333Y1347275D01*
X158625Y1347400D01*
X158917D01*
X159208Y1347317D01*
X159458Y1347108D01*
G01X161017Y1344900D02*
Y1347400D01*
X162058D01*
X162392Y1347275D01*
X162600Y1347108D01*
X162683Y1346775D01*
X162600Y1346442D01*
X162350Y1346233D01*
X162058Y1346108D01*
X161017D01*
G01X162058D02*
X162683Y1344900D01*
G01X164950D02*
Y1347400D01*
X164450Y1346900D01*
G01Y1344900D02*
X165450D01*
G01X168050D02*
Y1347400D01*
X167550Y1346900D01*
G01Y1344900D02*
X168550D01*
G01X170233Y1345400D02*
X170483Y1345108D01*
X170817Y1344942D01*
X171192Y1344900D01*
X171525Y1344942D01*
X171858Y1345150D01*
X172067Y1345400D01*
X172108Y1345650D01*
X172025Y1345942D01*
X171733Y1346150D01*
X171442Y1346233D01*
X171067D01*
G01X171442D02*
X171692Y1346358D01*
X171900Y1346567D01*
X171983Y1346817D01*
X171900Y1347067D01*
X171692Y1347275D01*
X171317Y1347400D01*
X170942Y1347358D01*
X170567Y1347192D01*
G01X174750Y1344900D02*
Y1347400D01*
X173208Y1345608D01*
X175292D01*
G01X132749Y1348496D02*
Y1350996D01*
X133790D01*
X134124Y1350871D01*
X134332Y1350704D01*
X134415Y1350371D01*
X134332Y1350038D01*
X134082Y1349829D01*
X133790Y1349704D01*
X132749D01*
G01X133790D02*
X134415Y1348496D01*
G01X135974Y1348788D02*
X136265Y1348579D01*
X136599Y1348496D01*
X136932Y1348579D01*
X137224Y1348829D01*
X137432Y1349204D01*
X137515Y1349579D01*
Y1350038D01*
X137432Y1350413D01*
X137224Y1350746D01*
X136974Y1350913D01*
X136682Y1350996D01*
X136349Y1350913D01*
X136099Y1350746D01*
X135932Y1350496D01*
X135849Y1350163D01*
X135932Y1349871D01*
X136140Y1349579D01*
X136390Y1349413D01*
X136682Y1349371D01*
X137015Y1349454D01*
X137265Y1349663D01*
X137515Y1350038D01*
G01X139074Y1348788D02*
X139365Y1348579D01*
X139699Y1348496D01*
X140032Y1348579D01*
X140324Y1348829D01*
X140532Y1349204D01*
X140615Y1349579D01*
Y1350038D01*
X140532Y1350413D01*
X140324Y1350746D01*
X140074Y1350913D01*
X139782Y1350996D01*
X139449Y1350913D01*
X139199Y1350746D01*
X139032Y1350496D01*
X138949Y1350163D01*
X139032Y1349871D01*
X139240Y1349579D01*
X139490Y1349413D01*
X139782Y1349371D01*
X140115Y1349454D01*
X140365Y1349663D01*
X140615Y1350038D01*
G01X142882Y1348496D02*
Y1350996D01*
X142382Y1350496D01*
G01Y1348496D02*
X143382D01*
G01X145982D02*
X146274Y1348538D01*
X146607Y1348663D01*
X146815Y1348871D01*
X146899Y1349163D01*
X146815Y1349454D01*
X146565Y1349704D01*
X146190Y1349829D01*
X145774D01*
X145524Y1349913D01*
X145315Y1350121D01*
X145232Y1350413D01*
X145357Y1350704D01*
X145649Y1350913D01*
X145982Y1350996D01*
X146315Y1350913D01*
X146607Y1350704D01*
X146732Y1350413D01*
X146649Y1350121D01*
X146440Y1349913D01*
X146190Y1349829D01*
X145774D01*
X145399Y1349704D01*
X145149Y1349454D01*
X145065Y1349163D01*
X145149Y1348871D01*
X145357Y1348663D01*
X145690Y1348538D01*
X145982Y1348496D01*
G01X149259Y1349802D02*
Y1345802D01*
X156659D01*
G01X163233Y1343300D02*
Y1341508D01*
X163400Y1341133D01*
X163733Y1340883D01*
X164150Y1340800D01*
X164567Y1340883D01*
X164900Y1341133D01*
X165067Y1341508D01*
Y1343300D01*
G01X166458Y1342883D02*
X166708Y1343133D01*
X167000Y1343258D01*
X167333Y1343300D01*
X167750Y1343217D01*
X168042Y1343008D01*
X168125Y1342758D01*
X168083Y1342508D01*
X167917Y1342300D01*
X167083Y1341883D01*
X166708Y1341592D01*
X166458Y1341175D01*
X166375Y1340800D01*
X168125D01*
G01X170350Y1343300D02*
X170017Y1343217D01*
X169767Y1343008D01*
X169600Y1342758D01*
X169475Y1342425D01*
X169433Y1342050D01*
X169475Y1341675D01*
X169600Y1341342D01*
X169767Y1341092D01*
X170017Y1340883D01*
X170350Y1340800D01*
X170683Y1340883D01*
X170933Y1341092D01*
X171100Y1341342D01*
X171225Y1341675D01*
X171267Y1342050D01*
X171225Y1342425D01*
X171100Y1342758D01*
X170933Y1343008D01*
X170683Y1343217D01*
X170350Y1343300D01*
G01X172533Y1341300D02*
X172783Y1341008D01*
X173117Y1340842D01*
X173492Y1340800D01*
X173825Y1340842D01*
X174158Y1341050D01*
X174367Y1341300D01*
X174408Y1341550D01*
X174325Y1341842D01*
X174033Y1342050D01*
X173742Y1342133D01*
X173367D01*
G01X173742D02*
X173992Y1342258D01*
X174200Y1342467D01*
X174283Y1342717D01*
X174200Y1342967D01*
X173992Y1343175D01*
X173617Y1343300D01*
X173242Y1343258D01*
X172867Y1343092D01*
G01X172854Y1348988D02*
X159454D01*
G01X172854Y1358988D02*
Y1348988D01*
G01X159454D02*
Y1358988D01*
G01X125000Y1451478D02*
X124167Y1450145D01*
X123667Y1448645D01*
Y1447311D01*
X124167Y1445978D01*
X125000Y1444978D01*
X126167Y1444478D01*
X127333Y1444811D01*
X128334Y1445645D01*
X129000Y1447145D01*
X129334Y1449145D01*
X130000Y1450311D01*
X131167Y1450811D01*
X132334Y1450478D01*
X133167Y1449645D01*
X133667Y1448478D01*
Y1447311D01*
X133334Y1446145D01*
X132500Y1445145D01*
G01X125000Y1440878D02*
X124167Y1439545D01*
X123667Y1438045D01*
Y1436711D01*
X124167Y1435378D01*
X125000Y1434378D01*
X126167Y1433878D01*
X127333Y1434211D01*
X128334Y1435045D01*
X129000Y1436545D01*
X129334Y1438545D01*
X130000Y1439711D01*
X131167Y1440211D01*
X132334Y1439878D01*
X133167Y1439045D01*
X133667Y1437878D01*
Y1436711D01*
X133334Y1435545D01*
X132500Y1434545D01*
G01X123667Y1430445D02*
X133667D01*
Y1427111D01*
X133167Y1425778D01*
X132500Y1424778D01*
X131500Y1423945D01*
X130333Y1423278D01*
X128667Y1423111D01*
X127000Y1423278D01*
X125834Y1423945D01*
X124833Y1424778D01*
X124167Y1425778D01*
X123667Y1427111D01*
Y1430445D01*
G01X127833Y1419345D02*
X129000Y1418178D01*
X129667Y1417178D01*
X130000Y1415845D01*
X129667Y1414678D01*
X129000Y1413845D01*
X128000Y1413178D01*
X126834Y1413011D01*
X125834Y1413178D01*
X124833Y1413845D01*
X124000Y1414845D01*
X123667Y1416011D01*
X124000Y1417345D01*
X125000Y1418511D01*
X126500Y1419178D01*
X128167Y1419345D01*
X130333Y1419011D01*
X131500Y1418511D01*
X132667Y1417678D01*
X133500Y1416511D01*
X133667Y1415345D01*
X133334Y1414178D01*
X132500Y1413345D01*
G01X182267Y1386167D02*
Y1388667D01*
X183267D01*
X183600Y1388542D01*
X183850Y1388250D01*
X183933Y1387917D01*
X183850Y1387584D01*
X183642Y1387334D01*
X183267Y1387209D01*
X182267D01*
G01X187033Y1386167D02*
X185367D01*
Y1388667D01*
X187033D01*
G01X186367Y1387459D02*
X185367D01*
G01X189633Y1387500D02*
X189800Y1387625D01*
X189925Y1387834D01*
X190008Y1388125D01*
X189925Y1388375D01*
X189758Y1388542D01*
X189467Y1388667D01*
X188342D01*
Y1386167D01*
X189717D01*
X190008Y1386334D01*
X190175Y1386584D01*
X190258Y1386875D01*
X190175Y1387167D01*
X189925Y1387417D01*
X189633Y1387500D01*
X188342D01*
G01X194458Y1386167D02*
X195500Y1388667D01*
X196542Y1386167D01*
G01X196167Y1387042D02*
X194833D01*
G01X198600Y1388667D02*
Y1386167D01*
G01X197642Y1388667D02*
X199558D01*
G01X201700D02*
Y1386167D01*
G01X200742Y1388667D02*
X202658D01*
G01X203842Y1386167D02*
Y1388667D01*
X205758Y1386167D01*
Y1388667D01*
G01X207108Y1387209D02*
X207400Y1387500D01*
X207650Y1387667D01*
X207983Y1387750D01*
X208275Y1387667D01*
X208483Y1387500D01*
X208650Y1387250D01*
X208692Y1386959D01*
X208650Y1386709D01*
X208483Y1386459D01*
X208233Y1386250D01*
X207942Y1386167D01*
X207608Y1386250D01*
X207317Y1386500D01*
X207150Y1386875D01*
X207108Y1387292D01*
X207192Y1387834D01*
X207317Y1388125D01*
X207525Y1388417D01*
X207817Y1388625D01*
X208108Y1388667D01*
X208400Y1388584D01*
X208608Y1388375D01*
G01X178875Y1366533D02*
X179208Y1366325D01*
X179583Y1366200D01*
X179917D01*
X180250Y1366325D01*
X180500Y1366533D01*
X180625Y1366825D01*
X180542Y1367117D01*
X180333Y1367367D01*
X179958Y1367533D01*
X179458Y1367617D01*
X179167Y1367783D01*
X179042Y1368075D01*
X179125Y1368367D01*
X179333Y1368575D01*
X179625Y1368700D01*
X179917D01*
X180208Y1368617D01*
X180458Y1368408D01*
G01X181933Y1366200D02*
Y1368700D01*
X182767D01*
X183100Y1368575D01*
X183350Y1368408D01*
X183558Y1368158D01*
X183725Y1367867D01*
X183767Y1367450D01*
X183725Y1367033D01*
X183558Y1366742D01*
X183350Y1366492D01*
X183100Y1366325D01*
X182767Y1366200D01*
X181933D01*
G01X185033D02*
Y1368700D01*
X185867D01*
X186200Y1368575D01*
X186450Y1368408D01*
X186658Y1368158D01*
X186825Y1367867D01*
X186867Y1367450D01*
X186825Y1367033D01*
X186658Y1366742D01*
X186450Y1366492D01*
X186200Y1366325D01*
X185867Y1366200D01*
X185033D01*
G01X191108D02*
X192150Y1368700D01*
X193192Y1366200D01*
G01X192817Y1367075D02*
X191483D01*
G01X196167Y1368492D02*
X195917Y1368617D01*
X195625Y1368700D01*
X195292D01*
X194917Y1368575D01*
X194625Y1368367D01*
X194417Y1368117D01*
X194250Y1367700D01*
X194208Y1367325D01*
X194292Y1366950D01*
X194417Y1366700D01*
X194667Y1366450D01*
X194958Y1366283D01*
X195250Y1366200D01*
X195542D01*
X195833Y1366283D01*
X196083Y1366408D01*
X196292Y1366575D01*
G01X198350Y1368700D02*
Y1366200D01*
G01X197392Y1368700D02*
X199308D01*
G01X200658Y1367242D02*
X200950Y1367533D01*
X201200Y1367700D01*
X201533Y1367783D01*
X201825Y1367700D01*
X202033Y1367533D01*
X202200Y1367283D01*
X202242Y1366992D01*
X202200Y1366742D01*
X202033Y1366492D01*
X201783Y1366283D01*
X201492Y1366200D01*
X201158Y1366283D01*
X200867Y1366533D01*
X200700Y1366908D01*
X200658Y1367325D01*
X200742Y1367867D01*
X200867Y1368158D01*
X201075Y1368450D01*
X201367Y1368658D01*
X201658Y1368700D01*
X201950Y1368617D01*
X202158Y1368408D01*
G01X209308Y1402353D02*
X180408D01*
Y1389453D01*
X162108D01*
Y1402353D01*
X148608D01*
Y1563553D01*
X162108D01*
Y1576453D01*
X180408D01*
Y1563553D01*
X209308D01*
Y1553203D01*
X202608D01*
Y1412703D01*
X209308D01*
Y1402353D01*
G01X172217Y1372567D02*
Y1370067D01*
X173883D01*
G01X176983D02*
X175317D01*
Y1372567D01*
X176983D01*
G01X176317Y1371359D02*
X175317D01*
G01X178333Y1370067D02*
Y1372567D01*
X179167D01*
X179500Y1372442D01*
X179750Y1372275D01*
X179958Y1372025D01*
X180125Y1371734D01*
X180167Y1371317D01*
X180125Y1370900D01*
X179958Y1370609D01*
X179750Y1370359D01*
X179500Y1370192D01*
X179167Y1370067D01*
X178333D01*
G01X181558Y1371109D02*
X181850Y1371400D01*
X182100Y1371567D01*
X182433Y1371650D01*
X182725Y1371567D01*
X182933Y1371400D01*
X183100Y1371150D01*
X183142Y1370859D01*
X183100Y1370609D01*
X182933Y1370359D01*
X182683Y1370150D01*
X182392Y1370067D01*
X182058Y1370150D01*
X181767Y1370400D01*
X181600Y1370775D01*
X181558Y1371192D01*
X181642Y1371734D01*
X181767Y1372025D01*
X181975Y1372317D01*
X182267Y1372525D01*
X182558Y1372567D01*
X182850Y1372484D01*
X183058Y1372275D01*
G01X165560Y1374546D02*
Y1382146D01*
X176960D01*
Y1374546D01*
X165560D01*
G01X146900Y1378667D02*
X146567Y1378709D01*
X146275Y1378875D01*
X146025Y1379125D01*
X145858Y1379417D01*
X145775Y1379750D01*
Y1380084D01*
X145858Y1380417D01*
X146025Y1380709D01*
X146275Y1380959D01*
X146567Y1381125D01*
X146900Y1381167D01*
X147233Y1381125D01*
X147525Y1380959D01*
X147775Y1380709D01*
X147942Y1380417D01*
X148025Y1380084D01*
Y1379750D01*
X147942Y1379417D01*
X147775Y1379125D01*
X147525Y1378875D01*
X147233Y1378709D01*
X146900Y1378667D01*
G01X147233Y1379334D02*
X147733Y1378667D01*
G01X149083Y1379042D02*
X149333Y1378834D01*
X149625Y1378709D01*
X150000Y1378667D01*
X150375Y1378750D01*
X150667Y1378917D01*
X150875Y1379209D01*
X150917Y1379542D01*
X150833Y1379875D01*
X150625Y1380084D01*
X150333Y1380250D01*
X150042Y1380292D01*
X149750Y1380250D01*
X149375Y1380084D01*
X149500Y1381167D01*
X150625D01*
G01X152392Y1378959D02*
X152683Y1378750D01*
X153017Y1378667D01*
X153350Y1378750D01*
X153642Y1379000D01*
X153850Y1379375D01*
X153933Y1379750D01*
Y1380209D01*
X153850Y1380584D01*
X153642Y1380917D01*
X153392Y1381084D01*
X153100Y1381167D01*
X152767Y1381084D01*
X152517Y1380917D01*
X152350Y1380667D01*
X152267Y1380334D01*
X152350Y1380042D01*
X152558Y1379750D01*
X152808Y1379584D01*
X153100Y1379542D01*
X153433Y1379625D01*
X153683Y1379834D01*
X153933Y1380209D01*
G01X161500Y1361035D02*
Y1375035D01*
G01X148500Y1361035D02*
X161500D01*
G01X148500Y1375035D02*
Y1361035D01*
G01X161500Y1375035D02*
X148500D01*
G01X132000Y1364400D02*
X131958Y1364067D01*
X131792Y1363775D01*
X131542Y1363525D01*
X131250Y1363358D01*
X130917Y1363275D01*
X130583D01*
X130250Y1363358D01*
X129958Y1363525D01*
X129708Y1363775D01*
X129542Y1364067D01*
X129500Y1364400D01*
X129542Y1364733D01*
X129708Y1365025D01*
X129958Y1365275D01*
X130250Y1365442D01*
X130583Y1365525D01*
X130917D01*
X131250Y1365442D01*
X131542Y1365275D01*
X131792Y1365025D01*
X131958Y1364733D01*
X132000Y1364400D01*
G01X131333Y1364733D02*
X132000Y1365233D01*
G01X130958Y1366708D02*
X130667Y1367000D01*
X130500Y1367250D01*
X130417Y1367583D01*
X130500Y1367875D01*
X130667Y1368083D01*
X130917Y1368250D01*
X131208Y1368292D01*
X131458Y1368250D01*
X131708Y1368083D01*
X131917Y1367833D01*
X132000Y1367542D01*
X131917Y1367208D01*
X131667Y1366917D01*
X131292Y1366750D01*
X130875Y1366708D01*
X130333Y1366792D01*
X130042Y1366917D01*
X129750Y1367125D01*
X129542Y1367417D01*
X129500Y1367708D01*
X129583Y1368000D01*
X129792Y1368208D01*
G01X129500Y1370600D02*
X129583Y1370267D01*
X129792Y1370017D01*
X130042Y1369850D01*
X130375Y1369725D01*
X130750Y1369683D01*
X131125Y1369725D01*
X131458Y1369850D01*
X131708Y1370017D01*
X131917Y1370267D01*
X132000Y1370600D01*
X131917Y1370933D01*
X131708Y1371183D01*
X131458Y1371350D01*
X131125Y1371475D01*
X130750Y1371517D01*
X130375Y1371475D01*
X130042Y1371350D01*
X129792Y1371183D01*
X129583Y1370933D01*
X129500Y1370600D01*
G01X134000Y1375035D02*
Y1361035D01*
G01X147000Y1375035D02*
X134000D01*
G01X147000Y1361035D02*
Y1375035D01*
G01X134000Y1361035D02*
X147000D01*
G01X183354Y1360488D02*
Y1364488D01*
X175954D01*
G01X119375Y1383000D02*
X119708Y1382792D01*
X120083Y1382667D01*
X120417D01*
X120750Y1382792D01*
X121000Y1383000D01*
X121125Y1383292D01*
X121042Y1383584D01*
X120833Y1383834D01*
X120458Y1384000D01*
X119958Y1384084D01*
X119667Y1384250D01*
X119542Y1384542D01*
X119625Y1384834D01*
X119833Y1385042D01*
X120125Y1385167D01*
X120417D01*
X120708Y1385084D01*
X120958Y1384875D01*
G01X122517Y1382667D02*
Y1385167D01*
X123558D01*
X123892Y1385042D01*
X124100Y1384875D01*
X124183Y1384542D01*
X124100Y1384209D01*
X123850Y1384000D01*
X123558Y1383875D01*
X122517D01*
G01X123558D02*
X124183Y1382667D01*
G01X126450D02*
Y1385167D01*
X125950Y1384667D01*
G01Y1382667D02*
X126950D01*
G01X129550D02*
Y1385167D01*
X129050Y1384667D01*
G01Y1382667D02*
X130050D01*
G01X131733Y1383167D02*
X131983Y1382875D01*
X132317Y1382709D01*
X132692Y1382667D01*
X133025Y1382709D01*
X133358Y1382917D01*
X133567Y1383167D01*
X133608Y1383417D01*
X133525Y1383709D01*
X133233Y1383917D01*
X132942Y1384000D01*
X132567D01*
G01X132942D02*
X133192Y1384125D01*
X133400Y1384334D01*
X133483Y1384584D01*
X133400Y1384834D01*
X133192Y1385042D01*
X132817Y1385167D01*
X132442Y1385125D01*
X132067Y1384959D01*
G01X134833Y1383167D02*
X135083Y1382875D01*
X135417Y1382709D01*
X135792Y1382667D01*
X136125Y1382709D01*
X136458Y1382917D01*
X136667Y1383167D01*
X136708Y1383417D01*
X136625Y1383709D01*
X136333Y1383917D01*
X136042Y1384000D01*
X135667D01*
G01X136042D02*
X136292Y1384125D01*
X136500Y1384334D01*
X136583Y1384584D01*
X136500Y1384834D01*
X136292Y1385042D01*
X135917Y1385167D01*
X135542Y1385125D01*
X135167Y1384959D01*
G01X142075Y1376010D02*
Y1380010D01*
X134675D01*
G01X168402Y1361288D02*
X172402D01*
Y1368688D01*
G01X145967Y1383666D02*
Y1386166D01*
X147008D01*
X147342Y1386041D01*
X147550Y1385874D01*
X147633Y1385541D01*
X147550Y1385208D01*
X147300Y1384999D01*
X147008Y1384874D01*
X145967D01*
G01X147008D02*
X147633Y1383666D01*
G01X149192Y1383958D02*
X149483Y1383749D01*
X149817Y1383666D01*
X150150Y1383749D01*
X150442Y1383999D01*
X150650Y1384374D01*
X150733Y1384749D01*
Y1385208D01*
X150650Y1385583D01*
X150442Y1385916D01*
X150192Y1386083D01*
X149900Y1386166D01*
X149567Y1386083D01*
X149317Y1385916D01*
X149150Y1385666D01*
X149067Y1385333D01*
X149150Y1385041D01*
X149358Y1384749D01*
X149608Y1384583D01*
X149900Y1384541D01*
X150233Y1384624D01*
X150483Y1384833D01*
X150733Y1385208D01*
G01X152292Y1383958D02*
X152583Y1383749D01*
X152917Y1383666D01*
X153250Y1383749D01*
X153542Y1383999D01*
X153750Y1384374D01*
X153833Y1384749D01*
Y1385208D01*
X153750Y1385583D01*
X153542Y1385916D01*
X153292Y1386083D01*
X153000Y1386166D01*
X152667Y1386083D01*
X152417Y1385916D01*
X152250Y1385666D01*
X152167Y1385333D01*
X152250Y1385041D01*
X152458Y1384749D01*
X152708Y1384583D01*
X153000Y1384541D01*
X153333Y1384624D01*
X153583Y1384833D01*
X153833Y1385208D01*
G01X156600Y1383666D02*
Y1386166D01*
X155058Y1384374D01*
X157142D01*
G01X159200Y1386166D02*
X158867Y1386083D01*
X158617Y1385874D01*
X158450Y1385624D01*
X158325Y1385291D01*
X158283Y1384916D01*
X158325Y1384541D01*
X158450Y1384208D01*
X158617Y1383958D01*
X158867Y1383749D01*
X159200Y1383666D01*
X159533Y1383749D01*
X159783Y1383958D01*
X159950Y1384208D01*
X160075Y1384541D01*
X160117Y1384916D01*
X160075Y1385291D01*
X159950Y1385624D01*
X159783Y1385874D01*
X159533Y1386083D01*
X159200Y1386166D01*
G01X162066Y1366127D02*
X166066D01*
Y1373527D01*
G01X146067Y1388067D02*
Y1390567D01*
X147108D01*
X147442Y1390442D01*
X147650Y1390275D01*
X147733Y1389942D01*
X147650Y1389609D01*
X147400Y1389400D01*
X147108Y1389275D01*
X146067D01*
G01X147108D02*
X147733Y1388067D01*
G01X149292Y1388359D02*
X149583Y1388150D01*
X149917Y1388067D01*
X150250Y1388150D01*
X150542Y1388400D01*
X150750Y1388775D01*
X150833Y1389150D01*
Y1389609D01*
X150750Y1389984D01*
X150542Y1390317D01*
X150292Y1390484D01*
X150000Y1390567D01*
X149667Y1390484D01*
X149417Y1390317D01*
X149250Y1390067D01*
X149167Y1389734D01*
X149250Y1389442D01*
X149458Y1389150D01*
X149708Y1388984D01*
X150000Y1388942D01*
X150333Y1389025D01*
X150583Y1389234D01*
X150833Y1389609D01*
G01X152392Y1388359D02*
X152683Y1388150D01*
X153017Y1388067D01*
X153350Y1388150D01*
X153642Y1388400D01*
X153850Y1388775D01*
X153933Y1389150D01*
Y1389609D01*
X153850Y1389984D01*
X153642Y1390317D01*
X153392Y1390484D01*
X153100Y1390567D01*
X152767Y1390484D01*
X152517Y1390317D01*
X152350Y1390067D01*
X152267Y1389734D01*
X152350Y1389442D01*
X152558Y1389150D01*
X152808Y1388984D01*
X153100Y1388942D01*
X153433Y1389025D01*
X153683Y1389234D01*
X153933Y1389609D01*
G01X155283Y1388567D02*
X155533Y1388275D01*
X155867Y1388109D01*
X156242Y1388067D01*
X156575Y1388109D01*
X156908Y1388317D01*
X157117Y1388567D01*
X157158Y1388817D01*
X157075Y1389109D01*
X156783Y1389317D01*
X156492Y1389400D01*
X156117D01*
G01X156492D02*
X156742Y1389525D01*
X156950Y1389734D01*
X157033Y1389984D01*
X156950Y1390234D01*
X156742Y1390442D01*
X156367Y1390567D01*
X155992Y1390525D01*
X155617Y1390359D01*
G01X158592Y1388359D02*
X158883Y1388150D01*
X159217Y1388067D01*
X159550Y1388150D01*
X159842Y1388400D01*
X160050Y1388775D01*
X160133Y1389150D01*
Y1389609D01*
X160050Y1389984D01*
X159842Y1390317D01*
X159592Y1390484D01*
X159300Y1390567D01*
X158967Y1390484D01*
X158717Y1390317D01*
X158550Y1390067D01*
X158467Y1389734D01*
X158550Y1389442D01*
X158758Y1389150D01*
X159008Y1388984D01*
X159300Y1388942D01*
X159633Y1389025D01*
X159883Y1389234D01*
X160133Y1389609D01*
G01X173074Y1383323D02*
Y1387323D01*
X165674D01*
G01X159454Y1358988D02*
X172854D01*
G01X143600Y1472917D02*
X143850Y1473125D01*
X144017Y1473375D01*
X144100Y1473667D01*
X144017Y1474000D01*
X143850Y1474250D01*
X143600Y1474500D01*
X143267Y1474583D01*
X141600D01*
G01X143058Y1476058D02*
X142767Y1476350D01*
X142600Y1476600D01*
X142517Y1476933D01*
X142600Y1477225D01*
X142767Y1477433D01*
X143017Y1477600D01*
X143308Y1477642D01*
X143558Y1477600D01*
X143808Y1477433D01*
X144017Y1477183D01*
X144100Y1476892D01*
X144017Y1476558D01*
X143767Y1476267D01*
X143392Y1476100D01*
X142975Y1476058D01*
X142433Y1476142D01*
X142142Y1476267D01*
X141850Y1476475D01*
X141642Y1476767D01*
X141600Y1477058D01*
X141683Y1477350D01*
X141892Y1477558D01*
G01X140500Y1444417D02*
X138000D01*
Y1445417D01*
X138125Y1445750D01*
X138417Y1446000D01*
X138750Y1446083D01*
X139083Y1446000D01*
X139333Y1445792D01*
X139458Y1445417D01*
Y1444417D01*
G01X138208Y1449267D02*
X138083Y1449017D01*
X138000Y1448725D01*
Y1448392D01*
X138125Y1448017D01*
X138333Y1447725D01*
X138583Y1447517D01*
X139000Y1447350D01*
X139375Y1447308D01*
X139750Y1447392D01*
X140000Y1447517D01*
X140250Y1447767D01*
X140417Y1448058D01*
X140500Y1448350D01*
Y1448642D01*
X140417Y1448933D01*
X140292Y1449183D01*
X140125Y1449392D01*
G01X140500Y1451450D02*
X138000D01*
X138500Y1450950D01*
G01X140500D02*
Y1451950D01*
G01X138417Y1453758D02*
X138167Y1454008D01*
X138042Y1454300D01*
X138000Y1454633D01*
X138083Y1455050D01*
X138292Y1455342D01*
X138542Y1455425D01*
X138792Y1455383D01*
X139000Y1455217D01*
X139417Y1454383D01*
X139708Y1454008D01*
X140125Y1453758D01*
X140500Y1453675D01*
Y1455425D01*
G01Y1458150D02*
X138000D01*
X139792Y1456608D01*
Y1458692D01*
G01X140500Y1461250D02*
X138000D01*
X139792Y1459708D01*
Y1461792D01*
G01X129520Y1457117D02*
X127020D01*
Y1458158D01*
X127145Y1458492D01*
X127312Y1458700D01*
X127645Y1458783D01*
X127978Y1458700D01*
X128187Y1458450D01*
X128312Y1458158D01*
Y1457117D01*
G01Y1458158D02*
X129520Y1458783D01*
G01X129020Y1460133D02*
X129312Y1460383D01*
X129478Y1460717D01*
X129520Y1461092D01*
X129478Y1461425D01*
X129270Y1461758D01*
X129020Y1461967D01*
X128770Y1462008D01*
X128478Y1461925D01*
X128270Y1461633D01*
X128187Y1461342D01*
Y1460967D01*
G01Y1461342D02*
X128062Y1461592D01*
X127853Y1461800D01*
X127603Y1461883D01*
X127353Y1461800D01*
X127145Y1461592D01*
X127020Y1461217D01*
X127062Y1460842D01*
X127228Y1460467D01*
G01X129020Y1463233D02*
X129312Y1463483D01*
X129478Y1463817D01*
X129520Y1464192D01*
X129478Y1464525D01*
X129270Y1464858D01*
X129020Y1465067D01*
X128770Y1465108D01*
X128478Y1465025D01*
X128270Y1464733D01*
X128187Y1464442D01*
Y1464067D01*
G01Y1464442D02*
X128062Y1464692D01*
X127853Y1464900D01*
X127603Y1464983D01*
X127353Y1464900D01*
X127145Y1464692D01*
X127020Y1464317D01*
X127062Y1463942D01*
X127228Y1463567D01*
G01X129520Y1467250D02*
X127020D01*
X127520Y1466750D01*
G01X129520D02*
Y1467750D01*
G01X124000Y1471300D02*
X128000D01*
Y1478700D01*
G01X121520Y1457117D02*
X119020D01*
Y1458158D01*
X119145Y1458492D01*
X119312Y1458700D01*
X119645Y1458783D01*
X119978Y1458700D01*
X120187Y1458450D01*
X120312Y1458158D01*
Y1457117D01*
G01Y1458158D02*
X121520Y1458783D01*
G01X121020Y1460133D02*
X121312Y1460383D01*
X121478Y1460717D01*
X121520Y1461092D01*
X121478Y1461425D01*
X121270Y1461758D01*
X121020Y1461967D01*
X120770Y1462008D01*
X120478Y1461925D01*
X120270Y1461633D01*
X120187Y1461342D01*
Y1460967D01*
G01Y1461342D02*
X120062Y1461592D01*
X119853Y1461800D01*
X119603Y1461883D01*
X119353Y1461800D01*
X119145Y1461592D01*
X119020Y1461217D01*
X119062Y1460842D01*
X119228Y1460467D01*
G01X121020Y1463233D02*
X121312Y1463483D01*
X121478Y1463817D01*
X121520Y1464192D01*
X121478Y1464525D01*
X121270Y1464858D01*
X121020Y1465067D01*
X120770Y1465108D01*
X120478Y1465025D01*
X120270Y1464733D01*
X120187Y1464442D01*
Y1464067D01*
G01Y1464442D02*
X120062Y1464692D01*
X119853Y1464900D01*
X119603Y1464983D01*
X119353Y1464900D01*
X119145Y1464692D01*
X119020Y1464317D01*
X119062Y1463942D01*
X119228Y1463567D01*
G01X119437Y1466458D02*
X119187Y1466708D01*
X119062Y1467000D01*
X119020Y1467333D01*
X119103Y1467750D01*
X119312Y1468042D01*
X119562Y1468125D01*
X119812Y1468083D01*
X120020Y1467917D01*
X120437Y1467083D01*
X120728Y1466708D01*
X121145Y1466458D01*
X121520Y1466375D01*
Y1468125D01*
G01X116000Y1471300D02*
X120000D01*
Y1478700D01*
G01X133520Y1457117D02*
X131020D01*
Y1458158D01*
X131145Y1458492D01*
X131312Y1458700D01*
X131645Y1458783D01*
X131978Y1458700D01*
X132187Y1458450D01*
X132312Y1458158D01*
Y1457117D01*
G01Y1458158D02*
X133520Y1458783D01*
G01X133020Y1460133D02*
X133312Y1460383D01*
X133478Y1460717D01*
X133520Y1461092D01*
X133478Y1461425D01*
X133270Y1461758D01*
X133020Y1461967D01*
X132770Y1462008D01*
X132478Y1461925D01*
X132270Y1461633D01*
X132187Y1461342D01*
Y1460967D01*
G01Y1461342D02*
X132062Y1461592D01*
X131853Y1461800D01*
X131603Y1461883D01*
X131353Y1461800D01*
X131145Y1461592D01*
X131020Y1461217D01*
X131062Y1460842D01*
X131228Y1460467D01*
G01X133020Y1463233D02*
X133312Y1463483D01*
X133478Y1463817D01*
X133520Y1464192D01*
X133478Y1464525D01*
X133270Y1464858D01*
X133020Y1465067D01*
X132770Y1465108D01*
X132478Y1465025D01*
X132270Y1464733D01*
X132187Y1464442D01*
Y1464067D01*
G01Y1464442D02*
X132062Y1464692D01*
X131853Y1464900D01*
X131603Y1464983D01*
X131353Y1464900D01*
X131145Y1464692D01*
X131020Y1464317D01*
X131062Y1463942D01*
X131228Y1463567D01*
G01X133228Y1466542D02*
X133437Y1466833D01*
X133520Y1467167D01*
X133437Y1467500D01*
X133187Y1467792D01*
X132812Y1468000D01*
X132437Y1468083D01*
X131978D01*
X131603Y1468000D01*
X131270Y1467792D01*
X131103Y1467542D01*
X131020Y1467250D01*
X131103Y1466917D01*
X131270Y1466667D01*
X131520Y1466500D01*
X131853Y1466417D01*
X132145Y1466500D01*
X132437Y1466708D01*
X132603Y1466958D01*
X132645Y1467250D01*
X132562Y1467583D01*
X132353Y1467833D01*
X131978Y1468083D01*
G01X132000Y1478700D02*
X128000D01*
Y1471300D01*
G01X125520Y1457117D02*
X123020D01*
Y1458158D01*
X123145Y1458492D01*
X123312Y1458700D01*
X123645Y1458783D01*
X123978Y1458700D01*
X124187Y1458450D01*
X124312Y1458158D01*
Y1457117D01*
G01Y1458158D02*
X125520Y1458783D01*
G01X125020Y1460133D02*
X125312Y1460383D01*
X125478Y1460717D01*
X125520Y1461092D01*
X125478Y1461425D01*
X125270Y1461758D01*
X125020Y1461967D01*
X124770Y1462008D01*
X124478Y1461925D01*
X124270Y1461633D01*
X124187Y1461342D01*
Y1460967D01*
G01Y1461342D02*
X124062Y1461592D01*
X123853Y1461800D01*
X123603Y1461883D01*
X123353Y1461800D01*
X123145Y1461592D01*
X123020Y1461217D01*
X123062Y1460842D01*
X123228Y1460467D01*
G01X125520Y1464650D02*
X123020D01*
X124812Y1463108D01*
Y1465192D01*
G01X123020Y1467250D02*
X123103Y1466917D01*
X123312Y1466667D01*
X123562Y1466500D01*
X123895Y1466375D01*
X124270Y1466333D01*
X124645Y1466375D01*
X124978Y1466500D01*
X125228Y1466667D01*
X125437Y1466917D01*
X125520Y1467250D01*
X125437Y1467583D01*
X125228Y1467833D01*
X124978Y1468000D01*
X124645Y1468125D01*
X124270Y1468167D01*
X123895Y1468125D01*
X123562Y1468000D01*
X123312Y1467833D01*
X123103Y1467583D01*
X123020Y1467250D01*
G01X124000Y1478700D02*
X120000D01*
Y1471300D01*
G01X117520Y1457117D02*
X115020D01*
Y1458158D01*
X115145Y1458492D01*
X115312Y1458700D01*
X115645Y1458783D01*
X115978Y1458700D01*
X116187Y1458450D01*
X116312Y1458158D01*
Y1457117D01*
G01Y1458158D02*
X117520Y1458783D01*
G01X117020Y1460133D02*
X117312Y1460383D01*
X117478Y1460717D01*
X117520Y1461092D01*
X117478Y1461425D01*
X117270Y1461758D01*
X117020Y1461967D01*
X116770Y1462008D01*
X116478Y1461925D01*
X116270Y1461633D01*
X116187Y1461342D01*
Y1460967D01*
G01Y1461342D02*
X116062Y1461592D01*
X115853Y1461800D01*
X115603Y1461883D01*
X115353Y1461800D01*
X115145Y1461592D01*
X115020Y1461217D01*
X115062Y1460842D01*
X115228Y1460467D01*
G01X117520Y1464650D02*
X115020D01*
X116812Y1463108D01*
Y1465192D01*
G01X117520Y1467250D02*
X115020D01*
X115520Y1466750D01*
G01X117520D02*
Y1467750D01*
G01X116000Y1478700D02*
X112000D01*
Y1471300D01*
G01X118047Y1487876D02*
X126047D01*
Y1499826D01*
X118047D01*
Y1487876D01*
G01X124197Y1499826D02*
X122197Y1497826D01*
X120197Y1499826D01*
G01X122267Y1510792D02*
X122017Y1510917D01*
X121725Y1511000D01*
X121392D01*
X121017Y1510875D01*
X120725Y1510667D01*
X120517Y1510417D01*
X120350Y1510000D01*
X120308Y1509625D01*
X120392Y1509250D01*
X120517Y1509000D01*
X120767Y1508750D01*
X121058Y1508583D01*
X121350Y1508500D01*
X121642D01*
X121933Y1508583D01*
X122183Y1508708D01*
X122392Y1508875D01*
G01X123533Y1509000D02*
X123783Y1508708D01*
X124117Y1508542D01*
X124492Y1508500D01*
X124825Y1508542D01*
X125158Y1508750D01*
X125367Y1509000D01*
X125408Y1509250D01*
X125325Y1509542D01*
X125033Y1509750D01*
X124742Y1509833D01*
X124367D01*
G01X124742D02*
X124992Y1509958D01*
X125200Y1510167D01*
X125283Y1510417D01*
X125200Y1510667D01*
X124992Y1510875D01*
X124617Y1511000D01*
X124242Y1510958D01*
X123867Y1510792D01*
G01X128050Y1508500D02*
Y1511000D01*
X126508Y1509208D01*
X128592D01*
G01X129733Y1509000D02*
X129983Y1508708D01*
X130317Y1508542D01*
X130692Y1508500D01*
X131025Y1508542D01*
X131358Y1508750D01*
X131567Y1509000D01*
X131608Y1509250D01*
X131525Y1509542D01*
X131233Y1509750D01*
X130942Y1509833D01*
X130567D01*
G01X130942D02*
X131192Y1509958D01*
X131400Y1510167D01*
X131483Y1510417D01*
X131400Y1510667D01*
X131192Y1510875D01*
X130817Y1511000D01*
X130442Y1510958D01*
X130067Y1510792D01*
G01X140500Y1527717D02*
X138000D01*
Y1528717D01*
X138125Y1529050D01*
X138417Y1529300D01*
X138750Y1529383D01*
X139083Y1529300D01*
X139333Y1529092D01*
X139458Y1528717D01*
Y1527717D01*
G01X138208Y1532567D02*
X138083Y1532317D01*
X138000Y1532025D01*
Y1531692D01*
X138125Y1531317D01*
X138333Y1531025D01*
X138583Y1530817D01*
X139000Y1530650D01*
X139375Y1530608D01*
X139750Y1530692D01*
X140000Y1530817D01*
X140250Y1531067D01*
X140417Y1531358D01*
X140500Y1531650D01*
Y1531942D01*
X140417Y1532233D01*
X140292Y1532483D01*
X140125Y1532692D01*
G01X140500Y1534750D02*
X138000D01*
X138500Y1534250D01*
G01X140500D02*
Y1535250D01*
G01X138417Y1537058D02*
X138167Y1537308D01*
X138042Y1537600D01*
X138000Y1537933D01*
X138083Y1538350D01*
X138292Y1538642D01*
X138542Y1538725D01*
X138792Y1538683D01*
X139000Y1538517D01*
X139417Y1537683D01*
X139708Y1537308D01*
X140125Y1537058D01*
X140500Y1536975D01*
Y1538725D01*
G01Y1541450D02*
X138000D01*
X139792Y1539908D01*
Y1541992D01*
G01X140000Y1543133D02*
X140292Y1543383D01*
X140458Y1543717D01*
X140500Y1544092D01*
X140458Y1544425D01*
X140250Y1544758D01*
X140000Y1544967D01*
X139750Y1545008D01*
X139458Y1544925D01*
X139250Y1544633D01*
X139167Y1544342D01*
Y1543967D01*
G01Y1544342D02*
X139042Y1544592D01*
X138833Y1544800D01*
X138583Y1544883D01*
X138333Y1544800D01*
X138125Y1544592D01*
X138000Y1544217D01*
X138042Y1543842D01*
X138208Y1543467D01*
G01X118467Y1526631D02*
Y1529131D01*
X119508D01*
X119842Y1529006D01*
X120050Y1528839D01*
X120133Y1528506D01*
X120050Y1528173D01*
X119800Y1527964D01*
X119508Y1527839D01*
X118467D01*
G01X119508D02*
X120133Y1526631D01*
G01X121483Y1527131D02*
X121733Y1526839D01*
X122067Y1526673D01*
X122442Y1526631D01*
X122775Y1526673D01*
X123108Y1526881D01*
X123317Y1527131D01*
X123358Y1527381D01*
X123275Y1527673D01*
X122983Y1527881D01*
X122692Y1527964D01*
X122317D01*
G01X122692D02*
X122942Y1528089D01*
X123150Y1528298D01*
X123233Y1528548D01*
X123150Y1528798D01*
X122942Y1529006D01*
X122567Y1529131D01*
X122192Y1529089D01*
X121817Y1528923D01*
G01X124792Y1526923D02*
X125083Y1526714D01*
X125417Y1526631D01*
X125750Y1526714D01*
X126042Y1526964D01*
X126250Y1527339D01*
X126333Y1527714D01*
Y1528173D01*
X126250Y1528548D01*
X126042Y1528881D01*
X125792Y1529048D01*
X125500Y1529131D01*
X125167Y1529048D01*
X124917Y1528881D01*
X124750Y1528631D01*
X124667Y1528298D01*
X124750Y1528006D01*
X124958Y1527714D01*
X125208Y1527548D01*
X125500Y1527506D01*
X125833Y1527589D01*
X126083Y1527798D01*
X126333Y1528173D01*
G01X127892Y1526923D02*
X128183Y1526714D01*
X128517Y1526631D01*
X128850Y1526714D01*
X129142Y1526964D01*
X129350Y1527339D01*
X129433Y1527714D01*
Y1528173D01*
X129350Y1528548D01*
X129142Y1528881D01*
X128892Y1529048D01*
X128600Y1529131D01*
X128267Y1529048D01*
X128017Y1528881D01*
X127850Y1528631D01*
X127767Y1528298D01*
X127850Y1528006D01*
X128058Y1527714D01*
X128308Y1527548D01*
X128600Y1527506D01*
X128933Y1527589D01*
X129183Y1527798D01*
X129433Y1528173D01*
G01X130200Y1535500D02*
Y1539500D01*
X122800D01*
G01X118467Y1531631D02*
Y1534131D01*
X119508D01*
X119842Y1534006D01*
X120050Y1533839D01*
X120133Y1533506D01*
X120050Y1533173D01*
X119800Y1532964D01*
X119508Y1532839D01*
X118467D01*
G01X119508D02*
X120133Y1531631D01*
G01X122900D02*
Y1534131D01*
X121358Y1532339D01*
X123442D01*
G01X125500Y1534131D02*
X125167Y1534048D01*
X124917Y1533839D01*
X124750Y1533589D01*
X124625Y1533256D01*
X124583Y1532881D01*
X124625Y1532506D01*
X124750Y1532173D01*
X124917Y1531923D01*
X125167Y1531714D01*
X125500Y1531631D01*
X125833Y1531714D01*
X126083Y1531923D01*
X126250Y1532173D01*
X126375Y1532506D01*
X126417Y1532881D01*
X126375Y1533256D01*
X126250Y1533589D01*
X126083Y1533839D01*
X125833Y1534048D01*
X125500Y1534131D01*
G01X128600D02*
X128267Y1534048D01*
X128017Y1533839D01*
X127850Y1533589D01*
X127725Y1533256D01*
X127683Y1532881D01*
X127725Y1532506D01*
X127850Y1532173D01*
X128017Y1531923D01*
X128267Y1531714D01*
X128600Y1531631D01*
X128933Y1531714D01*
X129183Y1531923D01*
X129350Y1532173D01*
X129475Y1532506D01*
X129517Y1532881D01*
X129475Y1533256D01*
X129350Y1533589D01*
X129183Y1533839D01*
X128933Y1534048D01*
X128600Y1534131D01*
G01X130200Y1540500D02*
Y1544500D01*
X122800D01*
G01X118683Y1576100D02*
Y1574308D01*
X118850Y1573933D01*
X119183Y1573683D01*
X119600Y1573600D01*
X120017Y1573683D01*
X120350Y1573933D01*
X120517Y1574308D01*
Y1576100D01*
G01X122700Y1573600D02*
Y1576100D01*
X122200Y1575600D01*
G01Y1573600D02*
X123200D01*
G01X124883Y1573975D02*
X125133Y1573767D01*
X125425Y1573642D01*
X125800Y1573600D01*
X126175Y1573683D01*
X126467Y1573850D01*
X126675Y1574142D01*
X126717Y1574475D01*
X126633Y1574808D01*
X126425Y1575017D01*
X126133Y1575183D01*
X125842Y1575225D01*
X125550Y1575183D01*
X125175Y1575017D01*
X125300Y1576100D01*
X126425D01*
G01X118700Y1572400D02*
X116700Y1570400D01*
X114700Y1572400D01*
G01X150650Y1585850D02*
Y1567150D01*
X140350D01*
Y1585850D01*
X150650D01*
G01X133500Y1527817D02*
X131000D01*
Y1528817D01*
X131125Y1529150D01*
X131417Y1529400D01*
X131750Y1529483D01*
X132083Y1529400D01*
X132333Y1529192D01*
X132458Y1528817D01*
Y1527817D01*
G01X131208Y1532667D02*
X131083Y1532417D01*
X131000Y1532125D01*
Y1531792D01*
X131125Y1531417D01*
X131333Y1531125D01*
X131583Y1530917D01*
X132000Y1530750D01*
X132375Y1530708D01*
X132750Y1530792D01*
X133000Y1530917D01*
X133250Y1531167D01*
X133417Y1531458D01*
X133500Y1531750D01*
Y1532042D01*
X133417Y1532333D01*
X133292Y1532583D01*
X133125Y1532792D01*
G01X133500Y1534850D02*
X131000D01*
X131500Y1534350D01*
G01X133500D02*
Y1535350D01*
G01X131417Y1537158D02*
X131167Y1537408D01*
X131042Y1537700D01*
X131000Y1538033D01*
X131083Y1538450D01*
X131292Y1538742D01*
X131542Y1538825D01*
X131792Y1538783D01*
X132000Y1538617D01*
X132417Y1537783D01*
X132708Y1537408D01*
X133125Y1537158D01*
X133500Y1537075D01*
Y1538825D01*
G01Y1541550D02*
X131000D01*
X132792Y1540008D01*
Y1542092D01*
G01X133500Y1544150D02*
X131000D01*
X131500Y1543650D01*
G01X133500D02*
Y1544650D01*
G01X132450Y1546950D02*
Y1565650D01*
X142750D01*
Y1546950D01*
X132450D01*
G01X134217Y1592400D02*
Y1594900D01*
X135217D01*
X135550Y1594775D01*
X135800Y1594483D01*
X135883Y1594150D01*
X135800Y1593817D01*
X135592Y1593567D01*
X135217Y1593442D01*
X134217D01*
G01X139067Y1594692D02*
X138817Y1594817D01*
X138525Y1594900D01*
X138192D01*
X137817Y1594775D01*
X137525Y1594567D01*
X137317Y1594317D01*
X137150Y1593900D01*
X137108Y1593525D01*
X137192Y1593150D01*
X137317Y1592900D01*
X137567Y1592650D01*
X137858Y1592483D01*
X138150Y1592400D01*
X138442D01*
X138733Y1592483D01*
X138983Y1592608D01*
X139192Y1592775D01*
G01X141250Y1592400D02*
Y1594900D01*
X140750Y1594400D01*
G01Y1592400D02*
X141750D01*
G01X143558Y1594483D02*
X143808Y1594733D01*
X144100Y1594858D01*
X144433Y1594900D01*
X144850Y1594817D01*
X145142Y1594608D01*
X145225Y1594358D01*
X145183Y1594108D01*
X145017Y1593900D01*
X144183Y1593483D01*
X143808Y1593192D01*
X143558Y1592775D01*
X143475Y1592400D01*
X145225D01*
G01X147950D02*
Y1594900D01*
X146408Y1593108D01*
X148492D01*
G01X149758Y1594483D02*
X150008Y1594733D01*
X150300Y1594858D01*
X150633Y1594900D01*
X151050Y1594817D01*
X151342Y1594608D01*
X151425Y1594358D01*
X151383Y1594108D01*
X151217Y1593900D01*
X150383Y1593483D01*
X150008Y1593192D01*
X149758Y1592775D01*
X149675Y1592400D01*
X151425D01*
G01X168400Y1632000D02*
X168358Y1631667D01*
X168192Y1631375D01*
X167942Y1631125D01*
X167650Y1630958D01*
X167317Y1630875D01*
X166983D01*
X166650Y1630958D01*
X166358Y1631125D01*
X166108Y1631375D01*
X165942Y1631667D01*
X165900Y1632000D01*
X165942Y1632333D01*
X166108Y1632625D01*
X166358Y1632875D01*
X166650Y1633042D01*
X166983Y1633125D01*
X167317D01*
X167650Y1633042D01*
X167942Y1632875D01*
X168192Y1632625D01*
X168358Y1632333D01*
X168400Y1632000D01*
G01X167733Y1632333D02*
X168400Y1632833D01*
G01Y1635100D02*
X165900D01*
X166400Y1634600D01*
G01X168400D02*
Y1635600D01*
G01Y1638200D02*
X168358Y1638492D01*
X168233Y1638825D01*
X168025Y1639033D01*
X167733Y1639117D01*
X167442Y1639033D01*
X167192Y1638783D01*
X167067Y1638408D01*
Y1637992D01*
X166983Y1637742D01*
X166775Y1637533D01*
X166483Y1637450D01*
X166192Y1637575D01*
X165983Y1637867D01*
X165900Y1638200D01*
X165983Y1638533D01*
X166192Y1638825D01*
X166483Y1638950D01*
X166775Y1638867D01*
X166983Y1638658D01*
X167067Y1638408D01*
Y1637992D01*
X167192Y1637617D01*
X167442Y1637367D01*
X167733Y1637283D01*
X168025Y1637367D01*
X168233Y1637575D01*
X168358Y1637908D01*
X168400Y1638200D01*
G01X143400Y1640100D02*
Y1626100D01*
G01X156400Y1640100D02*
X143400D01*
G01X156400Y1626100D02*
Y1640100D01*
G01X143400Y1626100D02*
X156400D01*
G01X119875Y1578275D02*
Y1591275D01*
G01X141400Y1608000D02*
X141067Y1608042D01*
X140775Y1608208D01*
X140525Y1608458D01*
X140358Y1608750D01*
X140275Y1609083D01*
Y1609417D01*
X140358Y1609750D01*
X140525Y1610042D01*
X140775Y1610292D01*
X141067Y1610458D01*
X141400Y1610500D01*
X141733Y1610458D01*
X142025Y1610292D01*
X142275Y1610042D01*
X142442Y1609750D01*
X142525Y1609417D01*
Y1609083D01*
X142442Y1608750D01*
X142275Y1608458D01*
X142025Y1608208D01*
X141733Y1608042D01*
X141400Y1608000D01*
G01X141733Y1608667D02*
X142233Y1608000D01*
G01X144417D02*
X144500Y1608542D01*
X144625Y1609000D01*
X144792Y1609417D01*
X145000Y1609875D01*
X145333Y1610500D01*
X143667D01*
G01X146808Y1609042D02*
X147100Y1609333D01*
X147350Y1609500D01*
X147683Y1609583D01*
X147975Y1609500D01*
X148183Y1609333D01*
X148350Y1609083D01*
X148392Y1608792D01*
X148350Y1608542D01*
X148183Y1608292D01*
X147933Y1608083D01*
X147642Y1608000D01*
X147308Y1608083D01*
X147017Y1608333D01*
X146850Y1608708D01*
X146808Y1609125D01*
X146892Y1609667D01*
X147017Y1609958D01*
X147225Y1610250D01*
X147517Y1610458D01*
X147808Y1610500D01*
X148100Y1610417D01*
X148308Y1610208D01*
G01X133000Y1611600D02*
X147000D01*
G01X133000Y1624600D02*
Y1611600D01*
G01X147000Y1624600D02*
X133000D01*
G01X147000Y1611600D02*
Y1624600D01*
G01X113900Y1608000D02*
X113567Y1608042D01*
X113275Y1608208D01*
X113025Y1608458D01*
X112858Y1608750D01*
X112775Y1609083D01*
Y1609417D01*
X112858Y1609750D01*
X113025Y1610042D01*
X113275Y1610292D01*
X113567Y1610458D01*
X113900Y1610500D01*
X114233Y1610458D01*
X114525Y1610292D01*
X114775Y1610042D01*
X114942Y1609750D01*
X115025Y1609417D01*
Y1609083D01*
X114942Y1608750D01*
X114775Y1608458D01*
X114525Y1608208D01*
X114233Y1608042D01*
X113900Y1608000D01*
G01X114233Y1608667D02*
X114733Y1608000D01*
G01X116917D02*
X117000Y1608542D01*
X117125Y1609000D01*
X117292Y1609417D01*
X117500Y1609875D01*
X117833Y1610500D01*
X116167D01*
G01X120017Y1608000D02*
X120100Y1608542D01*
X120225Y1609000D01*
X120392Y1609417D01*
X120600Y1609875D01*
X120933Y1610500D01*
X119267D01*
G01X113500Y1611600D02*
X127500D01*
G01X113500Y1624600D02*
Y1611600D01*
G01X127500Y1624600D02*
X113500D01*
G01X127500Y1611600D02*
Y1624600D01*
G01X144200Y1645100D02*
Y1641100D01*
X151600D01*
G01X152400Y1645400D02*
X156400D01*
Y1652800D01*
G01X151900D02*
X147900D01*
Y1645400D01*
G01X169500Y1612967D02*
X167000D01*
Y1614008D01*
X167125Y1614342D01*
X167292Y1614550D01*
X167625Y1614633D01*
X167958Y1614550D01*
X168167Y1614300D01*
X168292Y1614008D01*
Y1612967D01*
G01Y1614008D02*
X169500Y1614633D01*
G01X169208Y1616192D02*
X169417Y1616483D01*
X169500Y1616817D01*
X169417Y1617150D01*
X169167Y1617442D01*
X168792Y1617650D01*
X168417Y1617733D01*
X167958D01*
X167583Y1617650D01*
X167250Y1617442D01*
X167083Y1617192D01*
X167000Y1616900D01*
X167083Y1616567D01*
X167250Y1616317D01*
X167500Y1616150D01*
X167833Y1616067D01*
X168125Y1616150D01*
X168417Y1616358D01*
X168583Y1616608D01*
X168625Y1616900D01*
X168542Y1617233D01*
X168333Y1617483D01*
X167958Y1617733D01*
G01X169500Y1619917D02*
X168958Y1620000D01*
X168500Y1620125D01*
X168083Y1620292D01*
X167625Y1620500D01*
X167000Y1620833D01*
Y1619167D01*
G01X169125Y1622183D02*
X169333Y1622433D01*
X169458Y1622725D01*
X169500Y1623100D01*
X169417Y1623475D01*
X169250Y1623767D01*
X168958Y1623975D01*
X168625Y1624017D01*
X168292Y1623933D01*
X168083Y1623725D01*
X167917Y1623433D01*
X167875Y1623142D01*
X167917Y1622850D01*
X168083Y1622475D01*
X167000Y1622600D01*
Y1623725D01*
G01X169500Y1626200D02*
X167000D01*
X167500Y1625700D01*
G01X169500D02*
Y1626700D01*
G01X156000Y1624700D02*
X152000D01*
Y1617300D01*
G01X165500Y1612967D02*
X163000D01*
Y1614008D01*
X163125Y1614342D01*
X163292Y1614550D01*
X163625Y1614633D01*
X163958Y1614550D01*
X164167Y1614300D01*
X164292Y1614008D01*
Y1612967D01*
G01Y1614008D02*
X165500Y1614633D01*
G01X165208Y1616192D02*
X165417Y1616483D01*
X165500Y1616817D01*
X165417Y1617150D01*
X165167Y1617442D01*
X164792Y1617650D01*
X164417Y1617733D01*
X163958D01*
X163583Y1617650D01*
X163250Y1617442D01*
X163083Y1617192D01*
X163000Y1616900D01*
X163083Y1616567D01*
X163250Y1616317D01*
X163500Y1616150D01*
X163833Y1616067D01*
X164125Y1616150D01*
X164417Y1616358D01*
X164583Y1616608D01*
X164625Y1616900D01*
X164542Y1617233D01*
X164333Y1617483D01*
X163958Y1617733D01*
G01X165500Y1619917D02*
X164958Y1620000D01*
X164500Y1620125D01*
X164083Y1620292D01*
X163625Y1620500D01*
X163000Y1620833D01*
Y1619167D01*
G01X165500Y1623017D02*
X164958Y1623100D01*
X164500Y1623225D01*
X164083Y1623392D01*
X163625Y1623600D01*
X163000Y1623933D01*
Y1622267D01*
G01Y1626200D02*
X163083Y1625867D01*
X163292Y1625617D01*
X163542Y1625450D01*
X163875Y1625325D01*
X164250Y1625283D01*
X164625Y1625325D01*
X164958Y1625450D01*
X165208Y1625617D01*
X165417Y1625867D01*
X165500Y1626200D01*
X165417Y1626533D01*
X165208Y1626783D01*
X164958Y1626950D01*
X164625Y1627075D01*
X164250Y1627117D01*
X163875Y1627075D01*
X163542Y1626950D01*
X163292Y1626783D01*
X163083Y1626533D01*
X163000Y1626200D01*
G01X147500Y1617300D02*
X151500D01*
Y1624700D01*
G01X155467Y1608000D02*
Y1610500D01*
X156508D01*
X156842Y1610375D01*
X157050Y1610208D01*
X157133Y1609875D01*
X157050Y1609542D01*
X156800Y1609333D01*
X156508Y1609208D01*
X155467D01*
G01X156508D02*
X157133Y1608000D01*
G01X158692Y1608292D02*
X158983Y1608083D01*
X159317Y1608000D01*
X159650Y1608083D01*
X159942Y1608333D01*
X160150Y1608708D01*
X160233Y1609083D01*
Y1609542D01*
X160150Y1609917D01*
X159942Y1610250D01*
X159692Y1610417D01*
X159400Y1610500D01*
X159067Y1610417D01*
X158817Y1610250D01*
X158650Y1610000D01*
X158567Y1609667D01*
X158650Y1609375D01*
X158858Y1609083D01*
X159108Y1608917D01*
X159400Y1608875D01*
X159733Y1608958D01*
X159983Y1609167D01*
X160233Y1609542D01*
G01X162500Y1608000D02*
X162792Y1608042D01*
X163125Y1608167D01*
X163333Y1608375D01*
X163417Y1608667D01*
X163333Y1608958D01*
X163083Y1609208D01*
X162708Y1609333D01*
X162292D01*
X162042Y1609417D01*
X161833Y1609625D01*
X161750Y1609917D01*
X161875Y1610208D01*
X162167Y1610417D01*
X162500Y1610500D01*
X162833Y1610417D01*
X163125Y1610208D01*
X163250Y1609917D01*
X163167Y1609625D01*
X162958Y1609417D01*
X162708Y1609333D01*
X162292D01*
X161917Y1609208D01*
X161667Y1608958D01*
X161583Y1608667D01*
X161667Y1608375D01*
X161875Y1608167D01*
X162208Y1608042D01*
X162500Y1608000D01*
G01X166100D02*
Y1610500D01*
X164558Y1608708D01*
X166642D01*
G01X167783Y1608375D02*
X168033Y1608167D01*
X168325Y1608042D01*
X168700Y1608000D01*
X169075Y1608083D01*
X169367Y1608250D01*
X169575Y1608542D01*
X169617Y1608875D01*
X169533Y1609208D01*
X169325Y1609417D01*
X169033Y1609583D01*
X168742Y1609625D01*
X168450Y1609583D01*
X168075Y1609417D01*
X168200Y1610500D01*
X169325D01*
G01X160525Y1612225D02*
Y1616225D01*
X153125D01*
G01X123967Y1608000D02*
Y1610500D01*
X125008D01*
X125342Y1610375D01*
X125550Y1610208D01*
X125633Y1609875D01*
X125550Y1609542D01*
X125300Y1609333D01*
X125008Y1609208D01*
X123967D01*
G01X125008D02*
X125633Y1608000D01*
G01X127192Y1608292D02*
X127483Y1608083D01*
X127817Y1608000D01*
X128150Y1608083D01*
X128442Y1608333D01*
X128650Y1608708D01*
X128733Y1609083D01*
Y1609542D01*
X128650Y1609917D01*
X128442Y1610250D01*
X128192Y1610417D01*
X127900Y1610500D01*
X127567Y1610417D01*
X127317Y1610250D01*
X127150Y1610000D01*
X127067Y1609667D01*
X127150Y1609375D01*
X127358Y1609083D01*
X127608Y1608917D01*
X127900Y1608875D01*
X128233Y1608958D01*
X128483Y1609167D01*
X128733Y1609542D01*
G01X131000Y1608000D02*
X131292Y1608042D01*
X131625Y1608167D01*
X131833Y1608375D01*
X131917Y1608667D01*
X131833Y1608958D01*
X131583Y1609208D01*
X131208Y1609333D01*
X130792D01*
X130542Y1609417D01*
X130333Y1609625D01*
X130250Y1609917D01*
X130375Y1610208D01*
X130667Y1610417D01*
X131000Y1610500D01*
X131333Y1610417D01*
X131625Y1610208D01*
X131750Y1609917D01*
X131667Y1609625D01*
X131458Y1609417D01*
X131208Y1609333D01*
X130792D01*
X130417Y1609208D01*
X130167Y1608958D01*
X130083Y1608667D01*
X130167Y1608375D01*
X130375Y1608167D01*
X130708Y1608042D01*
X131000Y1608000D01*
G01X134600D02*
Y1610500D01*
X133058Y1608708D01*
X135142D01*
G01X136408Y1609042D02*
X136700Y1609333D01*
X136950Y1609500D01*
X137283Y1609583D01*
X137575Y1609500D01*
X137783Y1609333D01*
X137950Y1609083D01*
X137992Y1608792D01*
X137950Y1608542D01*
X137783Y1608292D01*
X137533Y1608083D01*
X137242Y1608000D01*
X136908Y1608083D01*
X136617Y1608333D01*
X136450Y1608708D01*
X136408Y1609125D01*
X136492Y1609667D01*
X136617Y1609958D01*
X136825Y1610250D01*
X137117Y1610458D01*
X137408Y1610500D01*
X137700Y1610417D01*
X137908Y1610208D01*
G01X132350Y1624550D02*
X128350D01*
Y1617150D01*
G01X121642Y1596325D02*
Y1598825D01*
X122683D01*
X123017Y1598700D01*
X123225Y1598533D01*
X123308Y1598200D01*
X123225Y1597867D01*
X122975Y1597658D01*
X122683Y1597533D01*
X121642D01*
G01X122683D02*
X123308Y1596325D01*
G01X124867Y1596617D02*
X125158Y1596408D01*
X125492Y1596325D01*
X125825Y1596408D01*
X126117Y1596658D01*
X126325Y1597033D01*
X126408Y1597408D01*
Y1597867D01*
X126325Y1598242D01*
X126117Y1598575D01*
X125867Y1598742D01*
X125575Y1598825D01*
X125242Y1598742D01*
X124992Y1598575D01*
X124825Y1598325D01*
X124742Y1597992D01*
X124825Y1597700D01*
X125033Y1597408D01*
X125283Y1597242D01*
X125575Y1597200D01*
X125908Y1597283D01*
X126158Y1597492D01*
X126408Y1597867D01*
G01X128675Y1596325D02*
X128967Y1596367D01*
X129300Y1596492D01*
X129508Y1596700D01*
X129592Y1596992D01*
X129508Y1597283D01*
X129258Y1597533D01*
X128883Y1597658D01*
X128467D01*
X128217Y1597742D01*
X128008Y1597950D01*
X127925Y1598242D01*
X128050Y1598533D01*
X128342Y1598742D01*
X128675Y1598825D01*
X129008Y1598742D01*
X129300Y1598533D01*
X129425Y1598242D01*
X129342Y1597950D01*
X129133Y1597742D01*
X128883Y1597658D01*
X128467D01*
X128092Y1597533D01*
X127842Y1597283D01*
X127758Y1596992D01*
X127842Y1596700D01*
X128050Y1596492D01*
X128383Y1596367D01*
X128675Y1596325D01*
G01X131775D02*
Y1598825D01*
X131275Y1598325D01*
G01Y1596325D02*
X132275D01*
G01X134875D02*
X135167Y1596367D01*
X135500Y1596492D01*
X135708Y1596700D01*
X135792Y1596992D01*
X135708Y1597283D01*
X135458Y1597533D01*
X135083Y1597658D01*
X134667D01*
X134417Y1597742D01*
X134208Y1597950D01*
X134125Y1598242D01*
X134250Y1598533D01*
X134542Y1598742D01*
X134875Y1598825D01*
X135208Y1598742D01*
X135500Y1598533D01*
X135625Y1598242D01*
X135542Y1597950D01*
X135333Y1597742D01*
X135083Y1597658D01*
X134667D01*
X134292Y1597533D01*
X134042Y1597283D01*
X133958Y1596992D01*
X134042Y1596700D01*
X134250Y1596492D01*
X134583Y1596367D01*
X134875Y1596325D01*
G01X133225Y1591625D02*
Y1586425D01*
G01X126225Y1591625D02*
Y1583825D01*
G01X133225Y1591625D02*
X126225D01*
G01X133225Y1578225D02*
Y1586925D01*
G01X126225Y1578225D02*
X133225D01*
G01X126225Y1584625D02*
Y1578225D01*
G01X126400Y1631300D02*
X128400Y1633300D01*
X130400Y1631300D01*
G01X134000D02*
Y1650500D01*
X122800D01*
Y1631300D01*
X134000D01*
G01X164467Y1597000D02*
Y1599500D01*
X165508D01*
X165842Y1599375D01*
X166050Y1599208D01*
X166133Y1598875D01*
X166050Y1598542D01*
X165800Y1598333D01*
X165508Y1598208D01*
X164467D01*
G01X165508D02*
X166133Y1597000D01*
G01X167692Y1597292D02*
X167983Y1597083D01*
X168317Y1597000D01*
X168650Y1597083D01*
X168942Y1597333D01*
X169150Y1597708D01*
X169233Y1598083D01*
Y1598542D01*
X169150Y1598917D01*
X168942Y1599250D01*
X168692Y1599417D01*
X168400Y1599500D01*
X168067Y1599417D01*
X167817Y1599250D01*
X167650Y1599000D01*
X167567Y1598667D01*
X167650Y1598375D01*
X167858Y1598083D01*
X168108Y1597917D01*
X168400Y1597875D01*
X168733Y1597958D01*
X168983Y1598167D01*
X169233Y1598542D01*
G01X170708Y1599083D02*
X170958Y1599333D01*
X171250Y1599458D01*
X171583Y1599500D01*
X172000Y1599417D01*
X172292Y1599208D01*
X172375Y1598958D01*
X172333Y1598708D01*
X172167Y1598500D01*
X171333Y1598083D01*
X170958Y1597792D01*
X170708Y1597375D01*
X170625Y1597000D01*
X172375D01*
G01X173683Y1597375D02*
X173933Y1597167D01*
X174225Y1597042D01*
X174600Y1597000D01*
X174975Y1597083D01*
X175267Y1597250D01*
X175475Y1597542D01*
X175517Y1597875D01*
X175433Y1598208D01*
X175225Y1598417D01*
X174933Y1598583D01*
X174642Y1598625D01*
X174350Y1598583D01*
X173975Y1598417D01*
X174100Y1599500D01*
X175225D01*
G01X177700Y1597000D02*
Y1599500D01*
X177200Y1599000D01*
G01Y1597000D02*
X178200D01*
G01X183400Y1579200D02*
Y1592200D01*
G01X157400Y1579200D02*
X183400D01*
G01X157400Y1592200D02*
Y1579200D01*
G01X183400Y1592200D02*
X157400D01*
G01X135017Y1588400D02*
Y1590900D01*
X136017D01*
X136350Y1590775D01*
X136600Y1590483D01*
X136683Y1590150D01*
X136600Y1589817D01*
X136392Y1589567D01*
X136017Y1589442D01*
X135017D01*
G01X139867Y1590692D02*
X139617Y1590817D01*
X139325Y1590900D01*
X138992D01*
X138617Y1590775D01*
X138325Y1590567D01*
X138117Y1590317D01*
X137950Y1589900D01*
X137908Y1589525D01*
X137992Y1589150D01*
X138117Y1588900D01*
X138367Y1588650D01*
X138658Y1588483D01*
X138950Y1588400D01*
X139242D01*
X139533Y1588483D01*
X139783Y1588608D01*
X139992Y1588775D01*
G01X142050Y1588400D02*
Y1590900D01*
X141550Y1590400D01*
G01Y1588400D02*
X142550D01*
G01X144358Y1590483D02*
X144608Y1590733D01*
X144900Y1590858D01*
X145233Y1590900D01*
X145650Y1590817D01*
X145942Y1590608D01*
X146025Y1590358D01*
X145983Y1590108D01*
X145817Y1589900D01*
X144983Y1589483D01*
X144608Y1589192D01*
X144358Y1588775D01*
X144275Y1588400D01*
X146025D01*
G01X148750D02*
Y1590900D01*
X147208Y1589108D01*
X149292D01*
G01X151350Y1590900D02*
X151017Y1590817D01*
X150767Y1590608D01*
X150600Y1590358D01*
X150475Y1590025D01*
X150433Y1589650D01*
X150475Y1589275D01*
X150600Y1588942D01*
X150767Y1588692D01*
X151017Y1588483D01*
X151350Y1588400D01*
X151683Y1588483D01*
X151933Y1588692D01*
X152100Y1588942D01*
X152225Y1589275D01*
X152267Y1589650D01*
X152225Y1590025D01*
X152100Y1590358D01*
X151933Y1590608D01*
X151683Y1590817D01*
X151350Y1590900D01*
G01X172334Y1630983D02*
X169834D01*
Y1631817D01*
X169959Y1632150D01*
X170126Y1632400D01*
X170376Y1632608D01*
X170667Y1632775D01*
X171084Y1632817D01*
X171501Y1632775D01*
X171792Y1632608D01*
X172042Y1632400D01*
X172209Y1632150D01*
X172334Y1631817D01*
Y1630983D01*
G01X170251Y1634208D02*
X170001Y1634458D01*
X169876Y1634750D01*
X169834Y1635083D01*
X169917Y1635500D01*
X170126Y1635792D01*
X170376Y1635875D01*
X170626Y1635833D01*
X170834Y1635667D01*
X171251Y1634833D01*
X171542Y1634458D01*
X171959Y1634208D01*
X172334Y1634125D01*
Y1635875D01*
G01Y1638100D02*
X172292Y1638392D01*
X172167Y1638725D01*
X171959Y1638933D01*
X171667Y1639017D01*
X171376Y1638933D01*
X171126Y1638683D01*
X171001Y1638308D01*
Y1637892D01*
X170917Y1637642D01*
X170709Y1637433D01*
X170417Y1637350D01*
X170126Y1637475D01*
X169917Y1637767D01*
X169834Y1638100D01*
X169917Y1638433D01*
X170126Y1638725D01*
X170417Y1638850D01*
X170709Y1638767D01*
X170917Y1638558D01*
X171001Y1638308D01*
Y1637892D01*
X171126Y1637517D01*
X171376Y1637267D01*
X171667Y1637183D01*
X171959Y1637267D01*
X172167Y1637475D01*
X172292Y1637808D01*
X172334Y1638100D01*
G01X164400Y1648100D02*
Y1632000D01*
G01X157400Y1648100D02*
X164400D01*
G01X157400Y1632000D02*
Y1648100D01*
G01X164400Y1632000D02*
X157400D01*
G01X146828Y1662037D02*
X146703Y1661787D01*
X146620Y1661495D01*
Y1661162D01*
X146745Y1660787D01*
X146953Y1660495D01*
X147203Y1660287D01*
X147620Y1660120D01*
X147995Y1660078D01*
X148370Y1660162D01*
X148620Y1660287D01*
X148870Y1660537D01*
X149037Y1660828D01*
X149120Y1661120D01*
Y1661412D01*
X149037Y1661703D01*
X148912Y1661953D01*
X148745Y1662162D01*
G01X148620Y1663303D02*
X148912Y1663553D01*
X149078Y1663887D01*
X149120Y1664262D01*
X149078Y1664595D01*
X148870Y1664928D01*
X148620Y1665137D01*
X148370Y1665178D01*
X148078Y1665095D01*
X147870Y1664803D01*
X147787Y1664512D01*
Y1664137D01*
G01Y1664512D02*
X147662Y1664762D01*
X147453Y1664970D01*
X147203Y1665053D01*
X146953Y1664970D01*
X146745Y1664762D01*
X146620Y1664387D01*
X146662Y1664012D01*
X146828Y1663637D01*
G01X148828Y1666612D02*
X149037Y1666903D01*
X149120Y1667237D01*
X149037Y1667570D01*
X148787Y1667862D01*
X148412Y1668070D01*
X148037Y1668153D01*
X147578D01*
X147203Y1668070D01*
X146870Y1667862D01*
X146703Y1667612D01*
X146620Y1667320D01*
X146703Y1666987D01*
X146870Y1666737D01*
X147120Y1666570D01*
X147453Y1666487D01*
X147745Y1666570D01*
X148037Y1666778D01*
X148203Y1667028D01*
X148245Y1667320D01*
X148162Y1667653D01*
X147953Y1667903D01*
X147578Y1668153D01*
G01X147037Y1669628D02*
X146787Y1669878D01*
X146662Y1670170D01*
X146620Y1670503D01*
X146703Y1670920D01*
X146912Y1671212D01*
X147162Y1671295D01*
X147412Y1671253D01*
X147620Y1671087D01*
X148037Y1670253D01*
X148328Y1669878D01*
X148745Y1669628D01*
X149120Y1669545D01*
Y1671295D01*
G01X146917Y1655600D02*
Y1658100D01*
X147958D01*
X148292Y1657975D01*
X148500Y1657808D01*
X148583Y1657475D01*
X148500Y1657142D01*
X148250Y1656933D01*
X147958Y1656808D01*
X146917D01*
G01X147958D02*
X148583Y1655600D01*
G01X150850D02*
Y1658100D01*
X150350Y1657600D01*
G01Y1655600D02*
X151350D01*
G01X154450D02*
Y1658100D01*
X152908Y1656308D01*
X154992D01*
G01X157050Y1655600D02*
X157342Y1655642D01*
X157675Y1655767D01*
X157883Y1655975D01*
X157967Y1656267D01*
X157883Y1656558D01*
X157633Y1656808D01*
X157258Y1656933D01*
X156842D01*
X156592Y1657017D01*
X156383Y1657225D01*
X156300Y1657517D01*
X156425Y1657808D01*
X156717Y1658017D01*
X157050Y1658100D01*
X157383Y1658017D01*
X157675Y1657808D01*
X157800Y1657517D01*
X157717Y1657225D01*
X157508Y1657017D01*
X157258Y1656933D01*
X156842D01*
X156467Y1656808D01*
X156217Y1656558D01*
X156133Y1656267D01*
X156217Y1655975D01*
X156425Y1655767D01*
X156758Y1655642D01*
X157050Y1655600D01*
G01X157120Y1660287D02*
X154620D01*
Y1661328D01*
X154745Y1661662D01*
X154912Y1661870D01*
X155245Y1661953D01*
X155578Y1661870D01*
X155787Y1661620D01*
X155912Y1661328D01*
Y1660287D01*
G01Y1661328D02*
X157120Y1661953D01*
G01X156745Y1663303D02*
X156953Y1663553D01*
X157078Y1663845D01*
X157120Y1664220D01*
X157037Y1664595D01*
X156870Y1664887D01*
X156578Y1665095D01*
X156245Y1665137D01*
X155912Y1665053D01*
X155703Y1664845D01*
X155537Y1664553D01*
X155495Y1664262D01*
X155537Y1663970D01*
X155703Y1663595D01*
X154620Y1663720D01*
Y1664845D01*
G01X156078Y1666528D02*
X155787Y1666820D01*
X155620Y1667070D01*
X155537Y1667403D01*
X155620Y1667695D01*
X155787Y1667903D01*
X156037Y1668070D01*
X156328Y1668112D01*
X156578Y1668070D01*
X156828Y1667903D01*
X157037Y1667653D01*
X157120Y1667362D01*
X157037Y1667028D01*
X156787Y1666737D01*
X156412Y1666570D01*
X155995Y1666528D01*
X155453Y1666612D01*
X155162Y1666737D01*
X154870Y1666945D01*
X154662Y1667237D01*
X154620Y1667528D01*
X154703Y1667820D01*
X154912Y1668028D01*
G01X157120Y1670420D02*
X154620D01*
X155120Y1669920D01*
G01X157120D02*
Y1670920D01*
G01X153120Y1660287D02*
X150620D01*
Y1661328D01*
X150745Y1661662D01*
X150912Y1661870D01*
X151245Y1661953D01*
X151578Y1661870D01*
X151787Y1661620D01*
X151912Y1661328D01*
Y1660287D01*
G01Y1661328D02*
X153120Y1661953D01*
G01X152745Y1663303D02*
X152953Y1663553D01*
X153078Y1663845D01*
X153120Y1664220D01*
X153037Y1664595D01*
X152870Y1664887D01*
X152578Y1665095D01*
X152245Y1665137D01*
X151912Y1665053D01*
X151703Y1664845D01*
X151537Y1664553D01*
X151495Y1664262D01*
X151537Y1663970D01*
X151703Y1663595D01*
X150620Y1663720D01*
Y1664845D01*
G01X153120Y1667237D02*
X152578Y1667320D01*
X152120Y1667445D01*
X151703Y1667612D01*
X151245Y1667820D01*
X150620Y1668153D01*
Y1666487D01*
G01X152078Y1669628D02*
X151787Y1669920D01*
X151620Y1670170D01*
X151537Y1670503D01*
X151620Y1670795D01*
X151787Y1671003D01*
X152037Y1671170D01*
X152328Y1671212D01*
X152578Y1671170D01*
X152828Y1671003D01*
X153037Y1670753D01*
X153120Y1670462D01*
X153037Y1670128D01*
X152787Y1669837D01*
X152412Y1669670D01*
X151995Y1669628D01*
X151453Y1669712D01*
X151162Y1669837D01*
X150870Y1670045D01*
X150662Y1670337D01*
X150620Y1670628D01*
X150703Y1670920D01*
X150912Y1671128D01*
G01X114517Y1678800D02*
Y1681300D01*
X115558D01*
X115892Y1681175D01*
X116100Y1681008D01*
X116183Y1680675D01*
X116100Y1680342D01*
X115850Y1680133D01*
X115558Y1680008D01*
X114517D01*
G01X115558D02*
X116183Y1678800D01*
G01X118950D02*
Y1681300D01*
X117408Y1679508D01*
X119492D01*
G01X121550Y1681300D02*
X121217Y1681217D01*
X120967Y1681008D01*
X120800Y1680758D01*
X120675Y1680425D01*
X120633Y1680050D01*
X120675Y1679675D01*
X120800Y1679342D01*
X120967Y1679092D01*
X121217Y1678883D01*
X121550Y1678800D01*
X121883Y1678883D01*
X122133Y1679092D01*
X122300Y1679342D01*
X122425Y1679675D01*
X122467Y1680050D01*
X122425Y1680425D01*
X122300Y1680758D01*
X122133Y1681008D01*
X121883Y1681217D01*
X121550Y1681300D01*
G01X124650Y1678800D02*
X124942Y1678842D01*
X125275Y1678967D01*
X125483Y1679175D01*
X125567Y1679467D01*
X125483Y1679758D01*
X125233Y1680008D01*
X124858Y1680133D01*
X124442D01*
X124192Y1680217D01*
X123983Y1680425D01*
X123900Y1680717D01*
X124025Y1681008D01*
X124317Y1681217D01*
X124650Y1681300D01*
X124983Y1681217D01*
X125275Y1681008D01*
X125400Y1680717D01*
X125317Y1680425D01*
X125108Y1680217D01*
X124858Y1680133D01*
X124442D01*
X124067Y1680008D01*
X123817Y1679758D01*
X123733Y1679467D01*
X123817Y1679175D01*
X124025Y1678967D01*
X124358Y1678842D01*
X124650Y1678800D01*
G01X113800Y1673000D02*
Y1669000D01*
X121200D01*
G01X114517Y1674800D02*
Y1677300D01*
X115558D01*
X115892Y1677175D01*
X116100Y1677008D01*
X116183Y1676675D01*
X116100Y1676342D01*
X115850Y1676133D01*
X115558Y1676008D01*
X114517D01*
G01X115558D02*
X116183Y1674800D01*
G01X118950D02*
Y1677300D01*
X117408Y1675508D01*
X119492D01*
G01X121550Y1677300D02*
X121217Y1677217D01*
X120967Y1677008D01*
X120800Y1676758D01*
X120675Y1676425D01*
X120633Y1676050D01*
X120675Y1675675D01*
X120800Y1675342D01*
X120967Y1675092D01*
X121217Y1674883D01*
X121550Y1674800D01*
X121883Y1674883D01*
X122133Y1675092D01*
X122300Y1675342D01*
X122425Y1675675D01*
X122467Y1676050D01*
X122425Y1676425D01*
X122300Y1676758D01*
X122133Y1677008D01*
X121883Y1677217D01*
X121550Y1677300D01*
G01X123942Y1675092D02*
X124233Y1674883D01*
X124567Y1674800D01*
X124900Y1674883D01*
X125192Y1675133D01*
X125400Y1675508D01*
X125483Y1675883D01*
Y1676342D01*
X125400Y1676717D01*
X125192Y1677050D01*
X124942Y1677217D01*
X124650Y1677300D01*
X124317Y1677217D01*
X124067Y1677050D01*
X123900Y1676800D01*
X123817Y1676467D01*
X123900Y1676175D01*
X124108Y1675883D01*
X124358Y1675717D01*
X124650Y1675675D01*
X124983Y1675758D01*
X125233Y1675967D01*
X125483Y1676342D01*
G01X113800Y1668000D02*
Y1664000D01*
X121200D01*
G01X140667Y1659375D02*
X140875Y1659708D01*
X141000Y1660083D01*
Y1660417D01*
X140875Y1660750D01*
X140667Y1661000D01*
X140375Y1661125D01*
X140083Y1661042D01*
X139833Y1660833D01*
X139667Y1660458D01*
X139583Y1659958D01*
X139417Y1659667D01*
X139125Y1659542D01*
X138833Y1659625D01*
X138625Y1659833D01*
X138500Y1660125D01*
Y1660417D01*
X138583Y1660708D01*
X138792Y1660958D01*
G01X141000Y1662517D02*
X138500D01*
Y1663558D01*
X138625Y1663892D01*
X138792Y1664100D01*
X139125Y1664183D01*
X139458Y1664100D01*
X139667Y1663850D01*
X139792Y1663558D01*
Y1662517D01*
G01Y1663558D02*
X141000Y1664183D01*
G01Y1666450D02*
X138500D01*
X139000Y1665950D01*
G01X141000D02*
Y1666950D01*
G01Y1669550D02*
X138500D01*
X139000Y1669050D01*
G01X141000D02*
Y1670050D01*
G01Y1672650D02*
X138500D01*
X139000Y1672150D01*
G01X141000D02*
Y1673150D01*
G01Y1675750D02*
X138500D01*
X139000Y1675250D01*
G01X141000D02*
Y1676250D01*
G01X124900Y1655800D02*
X128900D01*
Y1663200D01*
G01X135167Y1658875D02*
X135375Y1659208D01*
X135500Y1659583D01*
Y1659917D01*
X135375Y1660250D01*
X135167Y1660500D01*
X134875Y1660625D01*
X134583Y1660542D01*
X134333Y1660333D01*
X134167Y1659958D01*
X134083Y1659458D01*
X133917Y1659167D01*
X133625Y1659042D01*
X133333Y1659125D01*
X133125Y1659333D01*
X133000Y1659625D01*
Y1659917D01*
X133083Y1660208D01*
X133292Y1660458D01*
G01X135500Y1662017D02*
X133000D01*
Y1663058D01*
X133125Y1663392D01*
X133292Y1663600D01*
X133625Y1663683D01*
X133958Y1663600D01*
X134167Y1663350D01*
X134292Y1663058D01*
Y1662017D01*
G01Y1663058D02*
X135500Y1663683D01*
G01Y1665950D02*
X133000D01*
X133500Y1665450D01*
G01X135500D02*
Y1666450D01*
G01Y1669050D02*
X133000D01*
X133500Y1668550D01*
G01X135500D02*
Y1669550D01*
G01Y1672150D02*
X133000D01*
X133500Y1671650D01*
G01X135500D02*
Y1672650D01*
G01X133417Y1674458D02*
X133167Y1674708D01*
X133042Y1675000D01*
X133000Y1675333D01*
X133083Y1675750D01*
X133292Y1676042D01*
X133542Y1676125D01*
X133792Y1676083D01*
X134000Y1675917D01*
X134417Y1675083D01*
X134708Y1674708D01*
X135125Y1674458D01*
X135500Y1674375D01*
Y1676125D01*
G01X119000Y1663200D02*
X115000D01*
Y1655800D01*
G01X132983Y1656500D02*
Y1654708D01*
X133150Y1654333D01*
X133483Y1654083D01*
X133900Y1654000D01*
X134317Y1654083D01*
X134650Y1654333D01*
X134817Y1654708D01*
Y1656500D01*
G01X137000Y1654000D02*
Y1656500D01*
X136500Y1656000D01*
G01Y1654000D02*
X137500D01*
G01X139392Y1654292D02*
X139683Y1654083D01*
X140017Y1654000D01*
X140350Y1654083D01*
X140642Y1654333D01*
X140850Y1654708D01*
X140933Y1655083D01*
Y1655542D01*
X140850Y1655917D01*
X140642Y1656250D01*
X140392Y1656417D01*
X140100Y1656500D01*
X139767Y1656417D01*
X139517Y1656250D01*
X139350Y1656000D01*
X139267Y1655667D01*
X139350Y1655375D01*
X139558Y1655083D01*
X139808Y1654917D01*
X140100Y1654875D01*
X140433Y1654958D01*
X140683Y1655167D01*
X140933Y1655542D01*
G01X144875Y1763833D02*
X145208Y1763625D01*
X145583Y1763500D01*
X145917D01*
X146250Y1763625D01*
X146500Y1763833D01*
X146625Y1764125D01*
X146542Y1764417D01*
X146333Y1764667D01*
X145958Y1764833D01*
X145458Y1764917D01*
X145167Y1765083D01*
X145042Y1765375D01*
X145125Y1765667D01*
X145333Y1765875D01*
X145625Y1766000D01*
X145917D01*
X146208Y1765917D01*
X146458Y1765708D01*
G01X147933Y1763500D02*
Y1766000D01*
X148767D01*
X149100Y1765875D01*
X149350Y1765708D01*
X149558Y1765458D01*
X149725Y1765167D01*
X149767Y1764750D01*
X149725Y1764333D01*
X149558Y1764042D01*
X149350Y1763792D01*
X149100Y1763625D01*
X148767Y1763500D01*
X147933D01*
G01X151033D02*
Y1766000D01*
X151867D01*
X152200Y1765875D01*
X152450Y1765708D01*
X152658Y1765458D01*
X152825Y1765167D01*
X152867Y1764750D01*
X152825Y1764333D01*
X152658Y1764042D01*
X152450Y1763792D01*
X152200Y1763625D01*
X151867Y1763500D01*
X151033D01*
G01X157108D02*
X158150Y1766000D01*
X159192Y1763500D01*
G01X158817Y1764375D02*
X157483D01*
G01X162167Y1765792D02*
X161917Y1765917D01*
X161625Y1766000D01*
X161292D01*
X160917Y1765875D01*
X160625Y1765667D01*
X160417Y1765417D01*
X160250Y1765000D01*
X160208Y1764625D01*
X160292Y1764250D01*
X160417Y1764000D01*
X160667Y1763750D01*
X160958Y1763583D01*
X161250Y1763500D01*
X161542D01*
X161833Y1763583D01*
X162083Y1763708D01*
X162292Y1763875D01*
G01X164350Y1766000D02*
Y1763500D01*
G01X163392Y1766000D02*
X165308D01*
G01X166533Y1763875D02*
X166783Y1763667D01*
X167075Y1763542D01*
X167450Y1763500D01*
X167825Y1763583D01*
X168117Y1763750D01*
X168325Y1764042D01*
X168367Y1764375D01*
X168283Y1764708D01*
X168075Y1764917D01*
X167783Y1765083D01*
X167492Y1765125D01*
X167200Y1765083D01*
X166825Y1764917D01*
X166950Y1766000D01*
X168075D01*
G01X116278Y1783191D02*
X115445Y1781858D01*
X114945Y1780358D01*
Y1779024D01*
X115445Y1777691D01*
X116278Y1776691D01*
X117445Y1776191D01*
X118611Y1776524D01*
X119612Y1777358D01*
X120278Y1778858D01*
X120612Y1780858D01*
X121278Y1782024D01*
X122445Y1782524D01*
X123612Y1782191D01*
X124445Y1781358D01*
X124945Y1780191D01*
Y1779024D01*
X124612Y1777858D01*
X123778Y1776858D01*
G01X116278Y1772591D02*
X115445Y1771258D01*
X114945Y1769758D01*
Y1768424D01*
X115445Y1767091D01*
X116278Y1766091D01*
X117445Y1765591D01*
X118611Y1765924D01*
X119612Y1766758D01*
X120278Y1768258D01*
X120612Y1770258D01*
X121278Y1771424D01*
X122445Y1771924D01*
X123612Y1771591D01*
X124445Y1770758D01*
X124945Y1769591D01*
Y1768424D01*
X124612Y1767258D01*
X123778Y1766258D01*
G01X114945Y1762158D02*
X124945D01*
Y1758824D01*
X124445Y1757491D01*
X123778Y1756491D01*
X122778Y1755658D01*
X121611Y1754991D01*
X119945Y1754824D01*
X118278Y1754991D01*
X117112Y1755658D01*
X116111Y1756491D01*
X115445Y1757491D01*
X114945Y1758824D01*
Y1762158D01*
G01Y1747891D02*
X124945D01*
X122945Y1749891D01*
G01X114945D02*
Y1745891D01*
G01X124945Y1737291D02*
X124612Y1738625D01*
X123778Y1739624D01*
X122778Y1740291D01*
X121445Y1740791D01*
X119945Y1740958D01*
X118445Y1740791D01*
X117112Y1740291D01*
X116111Y1739624D01*
X115278Y1738625D01*
X114945Y1737291D01*
X115278Y1735958D01*
X116111Y1734958D01*
X117112Y1734291D01*
X118445Y1733791D01*
X119945Y1733624D01*
X121445Y1733791D01*
X122778Y1734291D01*
X123778Y1734958D01*
X124612Y1735958D01*
X124945Y1737291D01*
G01X151517Y1786167D02*
Y1783667D01*
X153183D01*
G01X156283D02*
X154617D01*
Y1786167D01*
X156283D01*
G01X155617Y1784959D02*
X154617D01*
G01X157633Y1783667D02*
Y1786167D01*
X158467D01*
X158800Y1786042D01*
X159050Y1785875D01*
X159258Y1785625D01*
X159425Y1785334D01*
X159467Y1784917D01*
X159425Y1784500D01*
X159258Y1784209D01*
X159050Y1783959D01*
X158800Y1783792D01*
X158467Y1783667D01*
X157633D01*
G01X160733Y1784042D02*
X160983Y1783834D01*
X161275Y1783709D01*
X161650Y1783667D01*
X162025Y1783750D01*
X162317Y1783917D01*
X162525Y1784209D01*
X162567Y1784542D01*
X162483Y1784875D01*
X162275Y1785084D01*
X161983Y1785250D01*
X161692Y1785292D01*
X161400Y1785250D01*
X161025Y1785084D01*
X161150Y1786167D01*
X162275D01*
G01X165560Y1780058D02*
Y1787658D01*
X176960D01*
Y1780058D01*
X165560D01*
G01X174500Y1753900D02*
X174458Y1753567D01*
X174292Y1753275D01*
X174042Y1753025D01*
X173750Y1752858D01*
X173417Y1752775D01*
X173083D01*
X172750Y1752858D01*
X172458Y1753025D01*
X172208Y1753275D01*
X172042Y1753567D01*
X172000Y1753900D01*
X172042Y1754233D01*
X172208Y1754525D01*
X172458Y1754775D01*
X172750Y1754942D01*
X173083Y1755025D01*
X173417D01*
X173750Y1754942D01*
X174042Y1754775D01*
X174292Y1754525D01*
X174458Y1754233D01*
X174500Y1753900D01*
G01X173833Y1754233D02*
X174500Y1754733D01*
G01X174125Y1756083D02*
X174333Y1756333D01*
X174458Y1756625D01*
X174500Y1757000D01*
X174417Y1757375D01*
X174250Y1757667D01*
X173958Y1757875D01*
X173625Y1757917D01*
X173292Y1757833D01*
X173083Y1757625D01*
X172917Y1757333D01*
X172875Y1757042D01*
X172917Y1756750D01*
X173083Y1756375D01*
X172000Y1756500D01*
Y1757625D01*
G01X174000Y1759183D02*
X174292Y1759433D01*
X174458Y1759767D01*
X174500Y1760142D01*
X174458Y1760475D01*
X174250Y1760808D01*
X174000Y1761017D01*
X173750Y1761058D01*
X173458Y1760975D01*
X173250Y1760683D01*
X173167Y1760392D01*
Y1760017D01*
G01Y1760392D02*
X173042Y1760642D01*
X172833Y1760850D01*
X172583Y1760933D01*
X172333Y1760850D01*
X172125Y1760642D01*
X172000Y1760267D01*
X172042Y1759892D01*
X172208Y1759517D01*
G01X177346Y1757000D02*
X191346D01*
G01X177346Y1770000D02*
Y1757000D01*
G01X191346Y1770000D02*
X177346D01*
G01X160467Y1767667D02*
Y1770167D01*
X161508D01*
X161842Y1770042D01*
X162050Y1769875D01*
X162133Y1769542D01*
X162050Y1769209D01*
X161800Y1769000D01*
X161508Y1768875D01*
X160467D01*
G01X161508D02*
X162133Y1767667D01*
G01X163692Y1767959D02*
X163983Y1767750D01*
X164317Y1767667D01*
X164650Y1767750D01*
X164942Y1768000D01*
X165150Y1768375D01*
X165233Y1768750D01*
Y1769209D01*
X165150Y1769584D01*
X164942Y1769917D01*
X164692Y1770084D01*
X164400Y1770167D01*
X164067Y1770084D01*
X163817Y1769917D01*
X163650Y1769667D01*
X163567Y1769334D01*
X163650Y1769042D01*
X163858Y1768750D01*
X164108Y1768584D01*
X164400Y1768542D01*
X164733Y1768625D01*
X164983Y1768834D01*
X165233Y1769209D01*
G01X167500Y1767667D02*
X167792Y1767709D01*
X168125Y1767834D01*
X168333Y1768042D01*
X168417Y1768334D01*
X168333Y1768625D01*
X168083Y1768875D01*
X167708Y1769000D01*
X167292D01*
X167042Y1769084D01*
X166833Y1769292D01*
X166750Y1769584D01*
X166875Y1769875D01*
X167167Y1770084D01*
X167500Y1770167D01*
X167833Y1770084D01*
X168125Y1769875D01*
X168250Y1769584D01*
X168167Y1769292D01*
X167958Y1769084D01*
X167708Y1769000D01*
X167292D01*
X166917Y1768875D01*
X166667Y1768625D01*
X166583Y1768334D01*
X166667Y1768042D01*
X166875Y1767834D01*
X167208Y1767709D01*
X167500Y1767667D01*
G01X170600D02*
Y1770167D01*
X170100Y1769667D01*
G01Y1767667D02*
X171100D01*
G01X172783Y1768042D02*
X173033Y1767834D01*
X173325Y1767709D01*
X173700Y1767667D01*
X174075Y1767750D01*
X174367Y1767917D01*
X174575Y1768209D01*
X174617Y1768542D01*
X174533Y1768875D01*
X174325Y1769084D01*
X174033Y1769250D01*
X173742Y1769292D01*
X173450Y1769250D01*
X173075Y1769084D01*
X173200Y1770167D01*
X174325D01*
G01X187046Y1772500D02*
Y1776500D01*
X179646D01*
G01X155834Y1767967D02*
X153334D01*
Y1769008D01*
X153459Y1769342D01*
X153626Y1769550D01*
X153959Y1769633D01*
X154292Y1769550D01*
X154501Y1769300D01*
X154626Y1769008D01*
Y1767967D01*
G01Y1769008D02*
X155834Y1769633D01*
G01X155542Y1771192D02*
X155751Y1771483D01*
X155834Y1771817D01*
X155751Y1772150D01*
X155501Y1772442D01*
X155126Y1772650D01*
X154751Y1772733D01*
X154292D01*
X153917Y1772650D01*
X153584Y1772442D01*
X153417Y1772192D01*
X153334Y1771900D01*
X153417Y1771567D01*
X153584Y1771317D01*
X153834Y1771150D01*
X154167Y1771067D01*
X154459Y1771150D01*
X154751Y1771358D01*
X154917Y1771608D01*
X154959Y1771900D01*
X154876Y1772233D01*
X154667Y1772483D01*
X154292Y1772733D01*
G01X155542Y1774292D02*
X155751Y1774583D01*
X155834Y1774917D01*
X155751Y1775250D01*
X155501Y1775542D01*
X155126Y1775750D01*
X154751Y1775833D01*
X154292D01*
X153917Y1775750D01*
X153584Y1775542D01*
X153417Y1775292D01*
X153334Y1775000D01*
X153417Y1774667D01*
X153584Y1774417D01*
X153834Y1774250D01*
X154167Y1774167D01*
X154459Y1774250D01*
X154751Y1774458D01*
X154917Y1774708D01*
X154959Y1775000D01*
X154876Y1775333D01*
X154667Y1775583D01*
X154292Y1775833D01*
G01X155334Y1777183D02*
X155626Y1777433D01*
X155792Y1777767D01*
X155834Y1778142D01*
X155792Y1778475D01*
X155584Y1778808D01*
X155334Y1779017D01*
X155084Y1779058D01*
X154792Y1778975D01*
X154584Y1778683D01*
X154501Y1778392D01*
Y1778017D01*
G01Y1778392D02*
X154376Y1778642D01*
X154167Y1778850D01*
X153917Y1778933D01*
X153667Y1778850D01*
X153459Y1778642D01*
X153334Y1778267D01*
X153376Y1777892D01*
X153542Y1777517D01*
G01X155834Y1781200D02*
X155792Y1781492D01*
X155667Y1781825D01*
X155459Y1782033D01*
X155167Y1782117D01*
X154876Y1782033D01*
X154626Y1781783D01*
X154501Y1781408D01*
Y1780992D01*
X154417Y1780742D01*
X154209Y1780533D01*
X153917Y1780450D01*
X153626Y1780575D01*
X153417Y1780867D01*
X153334Y1781200D01*
X153417Y1781533D01*
X153626Y1781825D01*
X153917Y1781950D01*
X154209Y1781867D01*
X154417Y1781658D01*
X154501Y1781408D01*
Y1780992D01*
X154626Y1780617D01*
X154876Y1780367D01*
X155167Y1780283D01*
X155459Y1780367D01*
X155667Y1780575D01*
X155792Y1780908D01*
X155834Y1781200D01*
G01X172080Y1778928D02*
X168080D01*
Y1771528D01*
G01X149967Y1789167D02*
Y1791667D01*
X151008D01*
X151342Y1791542D01*
X151550Y1791375D01*
X151633Y1791042D01*
X151550Y1790709D01*
X151300Y1790500D01*
X151008Y1790375D01*
X149967D01*
G01X151008D02*
X151633Y1789167D01*
G01X153192Y1789459D02*
X153483Y1789250D01*
X153817Y1789167D01*
X154150Y1789250D01*
X154442Y1789500D01*
X154650Y1789875D01*
X154733Y1790250D01*
Y1790709D01*
X154650Y1791084D01*
X154442Y1791417D01*
X154192Y1791584D01*
X153900Y1791667D01*
X153567Y1791584D01*
X153317Y1791417D01*
X153150Y1791167D01*
X153067Y1790834D01*
X153150Y1790542D01*
X153358Y1790250D01*
X153608Y1790084D01*
X153900Y1790042D01*
X154233Y1790125D01*
X154483Y1790334D01*
X154733Y1790709D01*
G01X156292Y1789459D02*
X156583Y1789250D01*
X156917Y1789167D01*
X157250Y1789250D01*
X157542Y1789500D01*
X157750Y1789875D01*
X157833Y1790250D01*
Y1790709D01*
X157750Y1791084D01*
X157542Y1791417D01*
X157292Y1791584D01*
X157000Y1791667D01*
X156667Y1791584D01*
X156417Y1791417D01*
X156250Y1791167D01*
X156167Y1790834D01*
X156250Y1790542D01*
X156458Y1790250D01*
X156708Y1790084D01*
X157000Y1790042D01*
X157333Y1790125D01*
X157583Y1790334D01*
X157833Y1790709D01*
G01X159183Y1789667D02*
X159433Y1789375D01*
X159767Y1789209D01*
X160142Y1789167D01*
X160475Y1789209D01*
X160808Y1789417D01*
X161017Y1789667D01*
X161058Y1789917D01*
X160975Y1790209D01*
X160683Y1790417D01*
X160392Y1790500D01*
X160017D01*
G01X160392D02*
X160642Y1790625D01*
X160850Y1790834D01*
X160933Y1791084D01*
X160850Y1791334D01*
X160642Y1791542D01*
X160267Y1791667D01*
X159892Y1791625D01*
X159517Y1791459D01*
G01X163117Y1789167D02*
X163200Y1789709D01*
X163325Y1790167D01*
X163492Y1790584D01*
X163700Y1791042D01*
X164033Y1791667D01*
X162367D01*
G01X172892Y1788692D02*
Y1792692D01*
X165492D01*
G01X182267Y1795167D02*
Y1797667D01*
X183267D01*
X183600Y1797542D01*
X183850Y1797250D01*
X183933Y1796917D01*
X183850Y1796584D01*
X183642Y1796334D01*
X183267Y1796209D01*
X182267D01*
G01X187033Y1795167D02*
X185367D01*
Y1797667D01*
X187033D01*
G01X186367Y1796459D02*
X185367D01*
G01X189633Y1796500D02*
X189800Y1796625D01*
X189925Y1796834D01*
X190008Y1797125D01*
X189925Y1797375D01*
X189758Y1797542D01*
X189467Y1797667D01*
X188342D01*
Y1795167D01*
X189717D01*
X190008Y1795334D01*
X190175Y1795584D01*
X190258Y1795875D01*
X190175Y1796167D01*
X189925Y1796417D01*
X189633Y1796500D01*
X188342D01*
G01X194458Y1795167D02*
X195500Y1797667D01*
X196542Y1795167D01*
G01X196167Y1796042D02*
X194833D01*
G01X198600Y1797667D02*
Y1795167D01*
G01X197642Y1797667D02*
X199558D01*
G01X201700D02*
Y1795167D01*
G01X200742Y1797667D02*
X202658D01*
G01X203842Y1795167D02*
Y1797667D01*
X205758Y1795167D01*
Y1797667D01*
G01X206983Y1795542D02*
X207233Y1795334D01*
X207525Y1795209D01*
X207900Y1795167D01*
X208275Y1795250D01*
X208567Y1795417D01*
X208775Y1795709D01*
X208817Y1796042D01*
X208733Y1796375D01*
X208525Y1796584D01*
X208233Y1796750D01*
X207942Y1796792D01*
X207650Y1796750D01*
X207275Y1796584D01*
X207400Y1797667D01*
X208525D01*
G01X209308Y1807865D02*
X180408D01*
Y1794965D01*
X162108D01*
Y1807865D01*
X148608D01*
Y1969065D01*
X162108D01*
Y1981965D01*
X180408D01*
Y1969065D01*
X209308D01*
Y1958715D01*
X202608D01*
Y1818215D01*
X209308D01*
Y1807865D01*
G01X140000Y1848417D02*
X137500D01*
Y1849417D01*
X137625Y1849750D01*
X137917Y1850000D01*
X138250Y1850083D01*
X138583Y1850000D01*
X138833Y1849792D01*
X138958Y1849417D01*
Y1848417D01*
G01X137708Y1853267D02*
X137583Y1853017D01*
X137500Y1852725D01*
Y1852392D01*
X137625Y1852017D01*
X137833Y1851725D01*
X138083Y1851517D01*
X138500Y1851350D01*
X138875Y1851308D01*
X139250Y1851392D01*
X139500Y1851517D01*
X139750Y1851767D01*
X139917Y1852058D01*
X140000Y1852350D01*
Y1852642D01*
X139917Y1852933D01*
X139792Y1853183D01*
X139625Y1853392D01*
G01X140000Y1855450D02*
X137500D01*
X138000Y1854950D01*
G01X140000D02*
Y1855950D01*
G01X137917Y1857758D02*
X137667Y1858008D01*
X137542Y1858300D01*
X137500Y1858633D01*
X137583Y1859050D01*
X137792Y1859342D01*
X138042Y1859425D01*
X138292Y1859383D01*
X138500Y1859217D01*
X138917Y1858383D01*
X139208Y1858008D01*
X139625Y1857758D01*
X140000Y1857675D01*
Y1859425D01*
G01X137500Y1861650D02*
X137583Y1861317D01*
X137792Y1861067D01*
X138042Y1860900D01*
X138375Y1860775D01*
X138750Y1860733D01*
X139125Y1860775D01*
X139458Y1860900D01*
X139708Y1861067D01*
X139917Y1861317D01*
X140000Y1861650D01*
X139917Y1861983D01*
X139708Y1862233D01*
X139458Y1862400D01*
X139125Y1862525D01*
X138750Y1862567D01*
X138375Y1862525D01*
X138042Y1862400D01*
X137792Y1862233D01*
X137583Y1861983D01*
X137500Y1861650D01*
G01X139708Y1864042D02*
X139917Y1864333D01*
X140000Y1864667D01*
X139917Y1865000D01*
X139667Y1865292D01*
X139292Y1865500D01*
X138917Y1865583D01*
X138458D01*
X138083Y1865500D01*
X137750Y1865292D01*
X137583Y1865042D01*
X137500Y1864750D01*
X137583Y1864417D01*
X137750Y1864167D01*
X138000Y1864000D01*
X138333Y1863917D01*
X138625Y1864000D01*
X138917Y1864208D01*
X139083Y1864458D01*
X139125Y1864750D01*
X139042Y1865083D01*
X138833Y1865333D01*
X138458Y1865583D01*
G01X115800Y1859800D02*
X115758Y1859467D01*
X115592Y1859175D01*
X115342Y1858925D01*
X115050Y1858758D01*
X114717Y1858675D01*
X114383D01*
X114050Y1858758D01*
X113758Y1858925D01*
X113508Y1859175D01*
X113342Y1859467D01*
X113300Y1859800D01*
X113342Y1860133D01*
X113508Y1860425D01*
X113758Y1860675D01*
X114050Y1860842D01*
X114383Y1860925D01*
X114717D01*
X115050Y1860842D01*
X115342Y1860675D01*
X115592Y1860425D01*
X115758Y1860133D01*
X115800Y1859800D01*
G01X115133Y1860133D02*
X115800Y1860633D01*
G01Y1862817D02*
X115258Y1862900D01*
X114800Y1863025D01*
X114383Y1863192D01*
X113925Y1863400D01*
X113300Y1863733D01*
Y1862067D01*
G01X115800Y1866000D02*
X115758Y1866292D01*
X115633Y1866625D01*
X115425Y1866833D01*
X115133Y1866917D01*
X114842Y1866833D01*
X114592Y1866583D01*
X114467Y1866208D01*
Y1865792D01*
X114383Y1865542D01*
X114175Y1865333D01*
X113883Y1865250D01*
X113592Y1865375D01*
X113383Y1865667D01*
X113300Y1866000D01*
X113383Y1866333D01*
X113592Y1866625D01*
X113883Y1866750D01*
X114175Y1866667D01*
X114383Y1866458D01*
X114467Y1866208D01*
Y1865792D01*
X114592Y1865417D01*
X114842Y1865167D01*
X115133Y1865083D01*
X115425Y1865167D01*
X115633Y1865375D01*
X115758Y1865708D01*
X115800Y1866000D01*
G01X114834Y1838967D02*
X112334D01*
Y1840008D01*
X112459Y1840342D01*
X112626Y1840550D01*
X112959Y1840633D01*
X113292Y1840550D01*
X113501Y1840300D01*
X113626Y1840008D01*
Y1838967D01*
G01Y1840008D02*
X114834Y1840633D01*
G01X114542Y1842192D02*
X114751Y1842483D01*
X114834Y1842817D01*
X114751Y1843150D01*
X114501Y1843442D01*
X114126Y1843650D01*
X113751Y1843733D01*
X113292D01*
X112917Y1843650D01*
X112584Y1843442D01*
X112417Y1843192D01*
X112334Y1842900D01*
X112417Y1842567D01*
X112584Y1842317D01*
X112834Y1842150D01*
X113167Y1842067D01*
X113459Y1842150D01*
X113751Y1842358D01*
X113917Y1842608D01*
X113959Y1842900D01*
X113876Y1843233D01*
X113667Y1843483D01*
X113292Y1843733D01*
G01X114834Y1846000D02*
X114792Y1846292D01*
X114667Y1846625D01*
X114459Y1846833D01*
X114167Y1846917D01*
X113876Y1846833D01*
X113626Y1846583D01*
X113501Y1846208D01*
Y1845792D01*
X113417Y1845542D01*
X113209Y1845333D01*
X112917Y1845250D01*
X112626Y1845375D01*
X112417Y1845667D01*
X112334Y1846000D01*
X112417Y1846333D01*
X112626Y1846625D01*
X112917Y1846750D01*
X113209Y1846667D01*
X113417Y1846458D01*
X113501Y1846208D01*
Y1845792D01*
X113626Y1845417D01*
X113876Y1845167D01*
X114167Y1845083D01*
X114459Y1845167D01*
X114667Y1845375D01*
X114792Y1845708D01*
X114834Y1846000D01*
G01Y1849600D02*
X112334D01*
X114126Y1848058D01*
Y1850142D01*
G01X114834Y1852200D02*
X114792Y1852492D01*
X114667Y1852825D01*
X114459Y1853033D01*
X114167Y1853117D01*
X113876Y1853033D01*
X113626Y1852783D01*
X113501Y1852408D01*
Y1851992D01*
X113417Y1851742D01*
X113209Y1851533D01*
X112917Y1851450D01*
X112626Y1851575D01*
X112417Y1851867D01*
X112334Y1852200D01*
X112417Y1852533D01*
X112626Y1852825D01*
X112917Y1852950D01*
X113209Y1852867D01*
X113417Y1852658D01*
X113501Y1852408D01*
Y1851992D01*
X113626Y1851617D01*
X113876Y1851367D01*
X114167Y1851283D01*
X114459Y1851367D01*
X114667Y1851575D01*
X114792Y1851908D01*
X114834Y1852200D01*
G01X124334Y1839467D02*
X121834D01*
Y1840508D01*
X121959Y1840842D01*
X122126Y1841050D01*
X122459Y1841133D01*
X122792Y1841050D01*
X123001Y1840800D01*
X123126Y1840508D01*
Y1839467D01*
G01Y1840508D02*
X124334Y1841133D01*
G01X124042Y1842692D02*
X124251Y1842983D01*
X124334Y1843317D01*
X124251Y1843650D01*
X124001Y1843942D01*
X123626Y1844150D01*
X123251Y1844233D01*
X122792D01*
X122417Y1844150D01*
X122084Y1843942D01*
X121917Y1843692D01*
X121834Y1843400D01*
X121917Y1843067D01*
X122084Y1842817D01*
X122334Y1842650D01*
X122667Y1842567D01*
X122959Y1842650D01*
X123251Y1842858D01*
X123417Y1843108D01*
X123459Y1843400D01*
X123376Y1843733D01*
X123167Y1843983D01*
X122792Y1844233D01*
G01X124334Y1846500D02*
X124292Y1846792D01*
X124167Y1847125D01*
X123959Y1847333D01*
X123667Y1847417D01*
X123376Y1847333D01*
X123126Y1847083D01*
X123001Y1846708D01*
Y1846292D01*
X122917Y1846042D01*
X122709Y1845833D01*
X122417Y1845750D01*
X122126Y1845875D01*
X121917Y1846167D01*
X121834Y1846500D01*
X121917Y1846833D01*
X122126Y1847125D01*
X122417Y1847250D01*
X122709Y1847167D01*
X122917Y1846958D01*
X123001Y1846708D01*
Y1846292D01*
X123126Y1845917D01*
X123376Y1845667D01*
X123667Y1845583D01*
X123959Y1845667D01*
X124167Y1845875D01*
X124292Y1846208D01*
X124334Y1846500D01*
G01Y1850100D02*
X121834D01*
X123626Y1848558D01*
Y1850642D01*
G01X124042Y1851992D02*
X124251Y1852283D01*
X124334Y1852617D01*
X124251Y1852950D01*
X124001Y1853242D01*
X123626Y1853450D01*
X123251Y1853533D01*
X122792D01*
X122417Y1853450D01*
X122084Y1853242D01*
X121917Y1852992D01*
X121834Y1852700D01*
X121917Y1852367D01*
X122084Y1852117D01*
X122334Y1851950D01*
X122667Y1851867D01*
X122959Y1851950D01*
X123251Y1852158D01*
X123417Y1852408D01*
X123459Y1852700D01*
X123376Y1853033D01*
X123167Y1853283D01*
X122792Y1853533D01*
G01X119501Y1838875D02*
X119709Y1839208D01*
X119834Y1839583D01*
Y1839917D01*
X119709Y1840250D01*
X119501Y1840500D01*
X119209Y1840625D01*
X118917Y1840542D01*
X118667Y1840333D01*
X118501Y1839958D01*
X118417Y1839458D01*
X118251Y1839167D01*
X117959Y1839042D01*
X117667Y1839125D01*
X117459Y1839333D01*
X117334Y1839625D01*
Y1839917D01*
X117417Y1840208D01*
X117626Y1840458D01*
G01X119834Y1842017D02*
X117334D01*
Y1843058D01*
X117459Y1843392D01*
X117626Y1843600D01*
X117959Y1843683D01*
X118292Y1843600D01*
X118501Y1843350D01*
X118626Y1843058D01*
Y1842017D01*
G01Y1843058D02*
X119834Y1843683D01*
G01Y1845950D02*
X117334D01*
X117834Y1845450D01*
G01X119834D02*
Y1846450D01*
G01Y1849050D02*
X117334D01*
X117834Y1848550D01*
G01X119834D02*
Y1849550D01*
G01Y1852650D02*
X117334D01*
X119126Y1851108D01*
Y1853192D01*
G01X117751Y1854458D02*
X117501Y1854708D01*
X117376Y1855000D01*
X117334Y1855333D01*
X117417Y1855750D01*
X117626Y1856042D01*
X117876Y1856125D01*
X118126Y1856083D01*
X118334Y1855917D01*
X118751Y1855083D01*
X119042Y1854708D01*
X119459Y1854458D01*
X119834Y1854375D01*
Y1856125D01*
G01X122793Y1919561D02*
X121960Y1918228D01*
X121460Y1916728D01*
Y1915394D01*
X121960Y1914061D01*
X122793Y1913061D01*
X123960Y1912561D01*
X125126Y1912894D01*
X126127Y1913728D01*
X126793Y1915228D01*
X127127Y1917228D01*
X127793Y1918394D01*
X128960Y1918894D01*
X130127Y1918561D01*
X130960Y1917728D01*
X131460Y1916561D01*
Y1915394D01*
X131127Y1914228D01*
X130293Y1913228D01*
G01X122793Y1908961D02*
X121960Y1907628D01*
X121460Y1906128D01*
Y1904794D01*
X121960Y1903461D01*
X122793Y1902461D01*
X123960Y1901961D01*
X125126Y1902294D01*
X126127Y1903128D01*
X126793Y1904628D01*
X127127Y1906628D01*
X127793Y1907794D01*
X128960Y1908294D01*
X130127Y1907961D01*
X130960Y1907128D01*
X131460Y1905961D01*
Y1904794D01*
X131127Y1903628D01*
X130293Y1902628D01*
G01X121460Y1898528D02*
X131460D01*
Y1895194D01*
X130960Y1893861D01*
X130293Y1892861D01*
X129293Y1892028D01*
X128126Y1891361D01*
X126460Y1891194D01*
X124793Y1891361D01*
X123627Y1892028D01*
X122626Y1892861D01*
X121960Y1893861D01*
X121460Y1895194D01*
Y1898528D01*
G01X122960Y1887928D02*
X122127Y1886928D01*
X121627Y1885761D01*
X121460Y1884261D01*
X121793Y1882761D01*
X122460Y1881594D01*
X123627Y1880761D01*
X124960Y1880594D01*
X126293Y1880928D01*
X127127Y1881761D01*
X127793Y1882928D01*
X127960Y1884094D01*
X127793Y1885261D01*
X127127Y1886761D01*
X131460Y1886261D01*
Y1881761D01*
G01X141371Y1915039D02*
X141621Y1915247D01*
X141788Y1915497D01*
X141871Y1915789D01*
X141788Y1916122D01*
X141621Y1916372D01*
X141371Y1916622D01*
X141038Y1916705D01*
X139371D01*
G01X141496Y1918055D02*
X141704Y1918305D01*
X141829Y1918597D01*
X141871Y1918972D01*
X141788Y1919347D01*
X141621Y1919639D01*
X141329Y1919847D01*
X140996Y1919889D01*
X140663Y1919805D01*
X140454Y1919597D01*
X140288Y1919305D01*
X140246Y1919014D01*
X140288Y1918722D01*
X140454Y1918347D01*
X139371Y1918472D01*
Y1919597D01*
G01X117517Y1924400D02*
Y1926900D01*
X118558D01*
X118892Y1926775D01*
X119100Y1926608D01*
X119183Y1926275D01*
X119100Y1925942D01*
X118850Y1925733D01*
X118558Y1925608D01*
X117517D01*
G01X118558D02*
X119183Y1924400D01*
G01X120533Y1924900D02*
X120783Y1924608D01*
X121117Y1924442D01*
X121492Y1924400D01*
X121825Y1924442D01*
X122158Y1924650D01*
X122367Y1924900D01*
X122408Y1925150D01*
X122325Y1925442D01*
X122033Y1925650D01*
X121742Y1925733D01*
X121367D01*
G01X121742D02*
X121992Y1925858D01*
X122200Y1926067D01*
X122283Y1926317D01*
X122200Y1926567D01*
X121992Y1926775D01*
X121617Y1926900D01*
X121242Y1926858D01*
X120867Y1926692D01*
G01X123842Y1924692D02*
X124133Y1924483D01*
X124467Y1924400D01*
X124800Y1924483D01*
X125092Y1924733D01*
X125300Y1925108D01*
X125383Y1925483D01*
Y1925942D01*
X125300Y1926317D01*
X125092Y1926650D01*
X124842Y1926817D01*
X124550Y1926900D01*
X124217Y1926817D01*
X123967Y1926650D01*
X123800Y1926400D01*
X123717Y1926067D01*
X123800Y1925775D01*
X124008Y1925483D01*
X124258Y1925317D01*
X124550Y1925275D01*
X124883Y1925358D01*
X125133Y1925567D01*
X125383Y1925942D01*
G01X127567Y1924400D02*
X127650Y1924942D01*
X127775Y1925400D01*
X127942Y1925817D01*
X128150Y1926275D01*
X128483Y1926900D01*
X126817D01*
G01X128500Y1932100D02*
Y1936100D01*
X121100D01*
G01X117517Y1928400D02*
Y1930900D01*
X118558D01*
X118892Y1930775D01*
X119100Y1930608D01*
X119183Y1930275D01*
X119100Y1929942D01*
X118850Y1929733D01*
X118558Y1929608D01*
X117517D01*
G01X118558D02*
X119183Y1928400D01*
G01X120533Y1928900D02*
X120783Y1928608D01*
X121117Y1928442D01*
X121492Y1928400D01*
X121825Y1928442D01*
X122158Y1928650D01*
X122367Y1928900D01*
X122408Y1929150D01*
X122325Y1929442D01*
X122033Y1929650D01*
X121742Y1929733D01*
X121367D01*
G01X121742D02*
X121992Y1929858D01*
X122200Y1930067D01*
X122283Y1930317D01*
X122200Y1930567D01*
X121992Y1930775D01*
X121617Y1930900D01*
X121242Y1930858D01*
X120867Y1930692D01*
G01X123842Y1928692D02*
X124133Y1928483D01*
X124467Y1928400D01*
X124800Y1928483D01*
X125092Y1928733D01*
X125300Y1929108D01*
X125383Y1929483D01*
Y1929942D01*
X125300Y1930317D01*
X125092Y1930650D01*
X124842Y1930817D01*
X124550Y1930900D01*
X124217Y1930817D01*
X123967Y1930650D01*
X123800Y1930400D01*
X123717Y1930067D01*
X123800Y1929775D01*
X124008Y1929483D01*
X124258Y1929317D01*
X124550Y1929275D01*
X124883Y1929358D01*
X125133Y1929567D01*
X125383Y1929942D01*
G01X127650Y1928400D02*
X127942Y1928442D01*
X128275Y1928567D01*
X128483Y1928775D01*
X128567Y1929067D01*
X128483Y1929358D01*
X128233Y1929608D01*
X127858Y1929733D01*
X127442D01*
X127192Y1929817D01*
X126983Y1930025D01*
X126900Y1930317D01*
X127025Y1930608D01*
X127317Y1930817D01*
X127650Y1930900D01*
X127983Y1930817D01*
X128275Y1930608D01*
X128400Y1930317D01*
X128317Y1930025D01*
X128108Y1929817D01*
X127858Y1929733D01*
X127442D01*
X127067Y1929608D01*
X126817Y1929358D01*
X126733Y1929067D01*
X126817Y1928775D01*
X127025Y1928567D01*
X127358Y1928442D01*
X127650Y1928400D01*
G01X128500Y1937100D02*
Y1941100D01*
X121100D01*
G01X136267Y1926975D02*
X136475Y1927308D01*
X136600Y1927683D01*
Y1928017D01*
X136475Y1928350D01*
X136267Y1928600D01*
X135975Y1928725D01*
X135683Y1928642D01*
X135433Y1928433D01*
X135267Y1928058D01*
X135183Y1927558D01*
X135017Y1927267D01*
X134725Y1927142D01*
X134433Y1927225D01*
X134225Y1927433D01*
X134100Y1927725D01*
Y1928017D01*
X134183Y1928308D01*
X134392Y1928558D01*
G01X136600Y1930117D02*
X134100D01*
Y1931158D01*
X134225Y1931492D01*
X134392Y1931700D01*
X134725Y1931783D01*
X135058Y1931700D01*
X135267Y1931450D01*
X135392Y1931158D01*
Y1930117D01*
G01Y1931158D02*
X136600Y1931783D01*
G01Y1934050D02*
X134100D01*
X134600Y1933550D01*
G01X136600D02*
Y1934550D01*
G01Y1937150D02*
X134100D01*
X134600Y1936650D01*
G01X136600D02*
Y1937650D01*
G01X134100Y1940250D02*
X134183Y1939917D01*
X134392Y1939667D01*
X134642Y1939500D01*
X134975Y1939375D01*
X135350Y1939333D01*
X135725Y1939375D01*
X136058Y1939500D01*
X136308Y1939667D01*
X136517Y1939917D01*
X136600Y1940250D01*
X136517Y1940583D01*
X136308Y1940833D01*
X136058Y1941000D01*
X135725Y1941125D01*
X135350Y1941167D01*
X134975Y1941125D01*
X134642Y1941000D01*
X134392Y1940833D01*
X134183Y1940583D01*
X134100Y1940250D01*
G01X134517Y1942558D02*
X134267Y1942808D01*
X134142Y1943100D01*
X134100Y1943433D01*
X134183Y1943850D01*
X134392Y1944142D01*
X134642Y1944225D01*
X134892Y1944183D01*
X135100Y1944017D01*
X135517Y1943183D01*
X135808Y1942808D01*
X136225Y1942558D01*
X136600Y1942475D01*
Y1944225D01*
G01X144950Y1940467D02*
X142450D01*
Y1941467D01*
X142575Y1941800D01*
X142867Y1942050D01*
X143200Y1942133D01*
X143533Y1942050D01*
X143783Y1941842D01*
X143908Y1941467D01*
Y1940467D01*
G01X142658Y1945317D02*
X142533Y1945067D01*
X142450Y1944775D01*
Y1944442D01*
X142575Y1944067D01*
X142783Y1943775D01*
X143033Y1943567D01*
X143450Y1943400D01*
X143825Y1943358D01*
X144200Y1943442D01*
X144450Y1943567D01*
X144700Y1943817D01*
X144867Y1944108D01*
X144950Y1944400D01*
Y1944692D01*
X144867Y1944983D01*
X144742Y1945233D01*
X144575Y1945442D01*
G01X144950Y1947500D02*
X142450D01*
X142950Y1947000D01*
G01X144950D02*
Y1948000D01*
G01X142867Y1949808D02*
X142617Y1950058D01*
X142492Y1950350D01*
X142450Y1950683D01*
X142533Y1951100D01*
X142742Y1951392D01*
X142992Y1951475D01*
X143242Y1951433D01*
X143450Y1951267D01*
X143867Y1950433D01*
X144158Y1950058D01*
X144575Y1949808D01*
X144950Y1949725D01*
Y1951475D01*
G01X142450Y1953700D02*
X142533Y1953367D01*
X142742Y1953117D01*
X142992Y1952950D01*
X143325Y1952825D01*
X143700Y1952783D01*
X144075Y1952825D01*
X144408Y1952950D01*
X144658Y1953117D01*
X144867Y1953367D01*
X144950Y1953700D01*
X144867Y1954033D01*
X144658Y1954283D01*
X144408Y1954450D01*
X144075Y1954575D01*
X143700Y1954617D01*
X143325Y1954575D01*
X142992Y1954450D01*
X142742Y1954283D01*
X142533Y1954033D01*
X142450Y1953700D01*
G01X144950Y1956800D02*
X144908Y1957092D01*
X144783Y1957425D01*
X144575Y1957633D01*
X144283Y1957717D01*
X143992Y1957633D01*
X143742Y1957383D01*
X143617Y1957008D01*
Y1956592D01*
X143533Y1956342D01*
X143325Y1956133D01*
X143033Y1956050D01*
X142742Y1956175D01*
X142533Y1956467D01*
X142450Y1956800D01*
X142533Y1957133D01*
X142742Y1957425D01*
X143033Y1957550D01*
X143325Y1957467D01*
X143533Y1957258D01*
X143617Y1957008D01*
Y1956592D01*
X143742Y1956217D01*
X143992Y1955967D01*
X144283Y1955883D01*
X144575Y1955967D01*
X144783Y1956175D01*
X144908Y1956508D01*
X144950Y1956800D01*
G01X114217Y1976000D02*
Y1978500D01*
X115217D01*
X115550Y1978375D01*
X115800Y1978083D01*
X115883Y1977750D01*
X115800Y1977417D01*
X115592Y1977167D01*
X115217Y1977042D01*
X114217D01*
G01X119067Y1978292D02*
X118817Y1978417D01*
X118525Y1978500D01*
X118192D01*
X117817Y1978375D01*
X117525Y1978167D01*
X117317Y1977917D01*
X117150Y1977500D01*
X117108Y1977125D01*
X117192Y1976750D01*
X117317Y1976500D01*
X117567Y1976250D01*
X117858Y1976083D01*
X118150Y1976000D01*
X118442D01*
X118733Y1976083D01*
X118983Y1976208D01*
X119192Y1976375D01*
G01X121250Y1976000D02*
Y1978500D01*
X120750Y1978000D01*
G01Y1976000D02*
X121750D01*
G01X123558Y1978083D02*
X123808Y1978333D01*
X124100Y1978458D01*
X124433Y1978500D01*
X124850Y1978417D01*
X125142Y1978208D01*
X125225Y1977958D01*
X125183Y1977708D01*
X125017Y1977500D01*
X124183Y1977083D01*
X123808Y1976792D01*
X123558Y1976375D01*
X123475Y1976000D01*
X125225D01*
G01X127450Y1978500D02*
X127117Y1978417D01*
X126867Y1978208D01*
X126700Y1977958D01*
X126575Y1977625D01*
X126533Y1977250D01*
X126575Y1976875D01*
X126700Y1976542D01*
X126867Y1976292D01*
X127117Y1976083D01*
X127450Y1976000D01*
X127783Y1976083D01*
X128033Y1976292D01*
X128200Y1976542D01*
X128325Y1976875D01*
X128367Y1977250D01*
X128325Y1977625D01*
X128200Y1977958D01*
X128033Y1978208D01*
X127783Y1978417D01*
X127450Y1978500D01*
G01X130467Y1976000D02*
X130550Y1976542D01*
X130675Y1977000D01*
X130842Y1977417D01*
X131050Y1977875D01*
X131383Y1978500D01*
X129717D01*
G01X117000Y1945900D02*
Y1941900D01*
X124400D01*
G01X124500Y1941800D02*
X128500D01*
Y1949200D01*
G01X125467Y1972800D02*
Y1975300D01*
X126508D01*
X126842Y1975175D01*
X127050Y1975008D01*
X127133Y1974675D01*
X127050Y1974342D01*
X126800Y1974133D01*
X126508Y1974008D01*
X125467D01*
G01X126508D02*
X127133Y1972800D01*
G01X128692Y1973092D02*
X128983Y1972883D01*
X129317Y1972800D01*
X129650Y1972883D01*
X129942Y1973133D01*
X130150Y1973508D01*
X130233Y1973883D01*
Y1974342D01*
X130150Y1974717D01*
X129942Y1975050D01*
X129692Y1975217D01*
X129400Y1975300D01*
X129067Y1975217D01*
X128817Y1975050D01*
X128650Y1974800D01*
X128567Y1974467D01*
X128650Y1974175D01*
X128858Y1973883D01*
X129108Y1973717D01*
X129400Y1973675D01*
X129733Y1973758D01*
X129983Y1973967D01*
X130233Y1974342D01*
G01X131708Y1974883D02*
X131958Y1975133D01*
X132250Y1975258D01*
X132583Y1975300D01*
X133000Y1975217D01*
X133292Y1975008D01*
X133375Y1974758D01*
X133333Y1974508D01*
X133167Y1974300D01*
X132333Y1973883D01*
X131958Y1973592D01*
X131708Y1973175D01*
X131625Y1972800D01*
X133375D01*
G01X136100D02*
Y1975300D01*
X134558Y1973508D01*
X136642D01*
G01X137783Y1973175D02*
X138033Y1972967D01*
X138325Y1972842D01*
X138700Y1972800D01*
X139075Y1972883D01*
X139367Y1973050D01*
X139575Y1973342D01*
X139617Y1973675D01*
X139533Y1974008D01*
X139325Y1974217D01*
X139033Y1974383D01*
X138742Y1974425D01*
X138450Y1974383D01*
X138075Y1974217D01*
X138200Y1975300D01*
X139325D01*
G01X147200Y1958700D02*
Y1971700D01*
G01X121200Y1958700D02*
X147200D01*
G01X121200Y1971700D02*
Y1958700D01*
G01X147200Y1971700D02*
X121200D01*
G01X216000Y41400D02*
X215958Y41067D01*
X215792Y40775D01*
X215542Y40525D01*
X215250Y40358D01*
X214917Y40275D01*
X214583D01*
X214250Y40358D01*
X213958Y40525D01*
X213708Y40775D01*
X213542Y41067D01*
X213500Y41400D01*
X213542Y41733D01*
X213708Y42025D01*
X213958Y42275D01*
X214250Y42442D01*
X214583Y42525D01*
X214917D01*
X215250Y42442D01*
X215542Y42275D01*
X215792Y42025D01*
X215958Y41733D01*
X216000Y41400D01*
G01X215333Y41733D02*
X216000Y42233D01*
G01X213917Y43708D02*
X213667Y43958D01*
X213542Y44250D01*
X213500Y44583D01*
X213583Y45000D01*
X213792Y45292D01*
X214042Y45375D01*
X214292Y45333D01*
X214500Y45167D01*
X214917Y44333D01*
X215208Y43958D01*
X215625Y43708D01*
X216000Y43625D01*
Y45375D01*
G01X213917Y46808D02*
X213667Y47058D01*
X213542Y47350D01*
X213500Y47683D01*
X213583Y48100D01*
X213792Y48392D01*
X214042Y48475D01*
X214292Y48433D01*
X214500Y48267D01*
X214917Y47433D01*
X215208Y47058D01*
X215625Y46808D01*
X216000Y46725D01*
Y48475D01*
G01X190500Y49500D02*
Y35500D01*
G01X203500D02*
Y49500D01*
G01X190500Y35500D02*
X203500D01*
G01X192900Y16000D02*
X192567Y16042D01*
X192275Y16208D01*
X192025Y16458D01*
X191858Y16750D01*
X191775Y17083D01*
Y17417D01*
X191858Y17750D01*
X192025Y18042D01*
X192275Y18292D01*
X192567Y18458D01*
X192900Y18500D01*
X193233Y18458D01*
X193525Y18292D01*
X193775Y18042D01*
X193942Y17750D01*
X194025Y17417D01*
Y17083D01*
X193942Y16750D01*
X193775Y16458D01*
X193525Y16208D01*
X193233Y16042D01*
X192900Y16000D01*
G01X193233Y16667D02*
X193733Y16000D01*
G01X195292Y16292D02*
X195583Y16083D01*
X195917Y16000D01*
X196250Y16083D01*
X196542Y16333D01*
X196750Y16708D01*
X196833Y17083D01*
Y17542D01*
X196750Y17917D01*
X196542Y18250D01*
X196292Y18417D01*
X196000Y18500D01*
X195667Y18417D01*
X195417Y18250D01*
X195250Y18000D01*
X195167Y17667D01*
X195250Y17375D01*
X195458Y17083D01*
X195708Y16917D01*
X196000Y16875D01*
X196333Y16958D01*
X196583Y17167D01*
X196833Y17542D01*
G01X199017Y16000D02*
X199100Y16542D01*
X199225Y17000D01*
X199392Y17417D01*
X199600Y17875D01*
X199933Y18500D01*
X198267D01*
G01X197500Y21100D02*
Y34100D01*
G01X222500Y24467D02*
X220000D01*
Y25508D01*
X220125Y25842D01*
X220292Y26050D01*
X220625Y26133D01*
X220958Y26050D01*
X221167Y25800D01*
X221292Y25508D01*
Y24467D01*
G01Y25508D02*
X222500Y26133D01*
G01X222208Y27692D02*
X222417Y27983D01*
X222500Y28317D01*
X222417Y28650D01*
X222167Y28942D01*
X221792Y29150D01*
X221417Y29233D01*
X220958D01*
X220583Y29150D01*
X220250Y28942D01*
X220083Y28692D01*
X220000Y28400D01*
X220083Y28067D01*
X220250Y27817D01*
X220500Y27650D01*
X220833Y27567D01*
X221125Y27650D01*
X221417Y27858D01*
X221583Y28108D01*
X221625Y28400D01*
X221542Y28733D01*
X221333Y28983D01*
X220958Y29233D01*
G01X222500Y31417D02*
X221958Y31500D01*
X221500Y31625D01*
X221083Y31792D01*
X220625Y32000D01*
X220000Y32333D01*
Y30667D01*
G01X222125Y33683D02*
X222333Y33933D01*
X222458Y34225D01*
X222500Y34600D01*
X222417Y34975D01*
X222250Y35267D01*
X221958Y35475D01*
X221625Y35517D01*
X221292Y35433D01*
X221083Y35225D01*
X220917Y34933D01*
X220875Y34642D01*
X220917Y34350D01*
X221083Y33975D01*
X220000Y34100D01*
Y35225D01*
G01X222125Y36783D02*
X222333Y37033D01*
X222458Y37325D01*
X222500Y37700D01*
X222417Y38075D01*
X222250Y38367D01*
X221958Y38575D01*
X221625Y38617D01*
X221292Y38533D01*
X221083Y38325D01*
X220917Y38033D01*
X220875Y37742D01*
X220917Y37450D01*
X221083Y37075D01*
X220000Y37200D01*
Y38325D01*
G01X206500Y34200D02*
X202500D01*
Y26800D01*
G01X218500Y24467D02*
X216000D01*
Y25508D01*
X216125Y25842D01*
X216292Y26050D01*
X216625Y26133D01*
X216958Y26050D01*
X217167Y25800D01*
X217292Y25508D01*
Y24467D01*
G01Y25508D02*
X218500Y26133D01*
G01X218208Y27692D02*
X218417Y27983D01*
X218500Y28317D01*
X218417Y28650D01*
X218167Y28942D01*
X217792Y29150D01*
X217417Y29233D01*
X216958D01*
X216583Y29150D01*
X216250Y28942D01*
X216083Y28692D01*
X216000Y28400D01*
X216083Y28067D01*
X216250Y27817D01*
X216500Y27650D01*
X216833Y27567D01*
X217125Y27650D01*
X217417Y27858D01*
X217583Y28108D01*
X217625Y28400D01*
X217542Y28733D01*
X217333Y28983D01*
X216958Y29233D01*
G01X218500Y31417D02*
X217958Y31500D01*
X217500Y31625D01*
X217083Y31792D01*
X216625Y32000D01*
X216000Y32333D01*
Y30667D01*
G01X218500Y34517D02*
X217958Y34600D01*
X217500Y34725D01*
X217083Y34892D01*
X216625Y35100D01*
X216000Y35433D01*
Y33767D01*
G01X218500Y38200D02*
X216000D01*
X217792Y36658D01*
Y38742D01*
G01X198000Y26800D02*
X202000D01*
Y34200D01*
G01X203967Y16500D02*
Y19000D01*
X205008D01*
X205342Y18875D01*
X205550Y18708D01*
X205633Y18375D01*
X205550Y18042D01*
X205300Y17833D01*
X205008Y17708D01*
X203967D01*
G01X205008D02*
X205633Y16500D01*
G01X207192Y16792D02*
X207483Y16583D01*
X207817Y16500D01*
X208150Y16583D01*
X208442Y16833D01*
X208650Y17208D01*
X208733Y17583D01*
Y18042D01*
X208650Y18417D01*
X208442Y18750D01*
X208192Y18917D01*
X207900Y19000D01*
X207567Y18917D01*
X207317Y18750D01*
X207150Y18500D01*
X207067Y18167D01*
X207150Y17875D01*
X207358Y17583D01*
X207608Y17417D01*
X207900Y17375D01*
X208233Y17458D01*
X208483Y17667D01*
X208733Y18042D01*
G01X211000Y16500D02*
X211292Y16542D01*
X211625Y16667D01*
X211833Y16875D01*
X211917Y17167D01*
X211833Y17458D01*
X211583Y17708D01*
X211208Y17833D01*
X210792D01*
X210542Y17917D01*
X210333Y18125D01*
X210250Y18417D01*
X210375Y18708D01*
X210667Y18917D01*
X211000Y19000D01*
X211333Y18917D01*
X211625Y18708D01*
X211750Y18417D01*
X211667Y18125D01*
X211458Y17917D01*
X211208Y17833D01*
X210792D01*
X210417Y17708D01*
X210167Y17458D01*
X210083Y17167D01*
X210167Y16875D01*
X210375Y16667D01*
X210708Y16542D01*
X211000Y16500D01*
G01X214017D02*
X214100Y17042D01*
X214225Y17500D01*
X214392Y17917D01*
X214600Y18375D01*
X214933Y19000D01*
X213267D01*
G01X217200Y16500D02*
Y19000D01*
X216700Y18500D01*
G01Y16500D02*
X217700D01*
G01X211025Y21725D02*
Y25725D01*
X203625D01*
G01X220334Y40983D02*
X217834D01*
Y41817D01*
X217959Y42150D01*
X218126Y42400D01*
X218376Y42608D01*
X218667Y42775D01*
X219084Y42817D01*
X219501Y42775D01*
X219792Y42608D01*
X220042Y42400D01*
X220209Y42150D01*
X220334Y41817D01*
Y40983D01*
G01X219834Y44083D02*
X220126Y44333D01*
X220292Y44667D01*
X220334Y45042D01*
X220292Y45375D01*
X220084Y45708D01*
X219834Y45917D01*
X219584Y45958D01*
X219292Y45875D01*
X219084Y45583D01*
X219001Y45292D01*
Y44917D01*
G01Y45292D02*
X218876Y45542D01*
X218667Y45750D01*
X218417Y45833D01*
X218167Y45750D01*
X217959Y45542D01*
X217834Y45167D01*
X217876Y44792D01*
X218042Y44417D01*
G01X218251Y47308D02*
X218001Y47558D01*
X217876Y47850D01*
X217834Y48183D01*
X217917Y48600D01*
X218126Y48892D01*
X218376Y48975D01*
X218626Y48933D01*
X218834Y48767D01*
X219251Y47933D01*
X219542Y47558D01*
X219959Y47308D01*
X220334Y47225D01*
Y48975D01*
G01X211500Y57500D02*
Y41400D01*
G01X204500D02*
Y57500D01*
G01X211500Y41400D02*
X204500D01*
G01X190847Y71947D02*
X190722Y71697D01*
X190639Y71405D01*
Y71072D01*
X190764Y70697D01*
X190972Y70405D01*
X191222Y70197D01*
X191639Y70030D01*
X192014Y69988D01*
X192389Y70072D01*
X192639Y70197D01*
X192889Y70447D01*
X193056Y70738D01*
X193139Y71030D01*
Y71322D01*
X193056Y71613D01*
X192931Y71863D01*
X192764Y72072D01*
G01X192639Y73213D02*
X192931Y73463D01*
X193097Y73797D01*
X193139Y74172D01*
X193097Y74505D01*
X192889Y74838D01*
X192639Y75047D01*
X192389Y75088D01*
X192097Y75005D01*
X191889Y74713D01*
X191806Y74422D01*
Y74047D01*
G01Y74422D02*
X191681Y74672D01*
X191472Y74880D01*
X191222Y74963D01*
X190972Y74880D01*
X190764Y74672D01*
X190639Y74297D01*
X190681Y73922D01*
X190847Y73547D01*
G01X192847Y76522D02*
X193056Y76813D01*
X193139Y77147D01*
X193056Y77480D01*
X192806Y77772D01*
X192431Y77980D01*
X192056Y78063D01*
X191597D01*
X191222Y77980D01*
X190889Y77772D01*
X190722Y77522D01*
X190639Y77230D01*
X190722Y76897D01*
X190889Y76647D01*
X191139Y76480D01*
X191472Y76397D01*
X191764Y76480D01*
X192056Y76688D01*
X192222Y76938D01*
X192264Y77230D01*
X192181Y77563D01*
X191972Y77813D01*
X191597Y78063D01*
G01X192097Y79538D02*
X191806Y79830D01*
X191639Y80080D01*
X191556Y80413D01*
X191639Y80705D01*
X191806Y80913D01*
X192056Y81080D01*
X192347Y81122D01*
X192597Y81080D01*
X192847Y80913D01*
X193056Y80663D01*
X193139Y80372D01*
X193056Y80038D01*
X192806Y79747D01*
X192431Y79580D01*
X192014Y79538D01*
X191472Y79622D01*
X191181Y79747D01*
X190889Y79955D01*
X190681Y80247D01*
X190639Y80538D01*
X190722Y80830D01*
X190931Y81038D01*
G01X203500Y49500D02*
X190500D01*
G01X189977Y65051D02*
Y67551D01*
X191018D01*
X191352Y67426D01*
X191560Y67259D01*
X191643Y66926D01*
X191560Y66593D01*
X191310Y66384D01*
X191018Y66259D01*
X189977D01*
G01X191018D02*
X191643Y65051D01*
G01X193910D02*
Y67551D01*
X193410Y67051D01*
G01Y65051D02*
X194410D01*
G01X196093Y65426D02*
X196343Y65218D01*
X196635Y65093D01*
X197010Y65051D01*
X197385Y65134D01*
X197677Y65301D01*
X197885Y65593D01*
X197927Y65926D01*
X197843Y66259D01*
X197635Y66468D01*
X197343Y66634D01*
X197052Y66676D01*
X196760Y66634D01*
X196385Y66468D01*
X196510Y67551D01*
X197635D01*
G01X199318Y67134D02*
X199568Y67384D01*
X199860Y67509D01*
X200193Y67551D01*
X200610Y67468D01*
X200902Y67259D01*
X200985Y67009D01*
X200943Y66759D01*
X200777Y66551D01*
X199943Y66134D01*
X199568Y65843D01*
X199318Y65426D01*
X199235Y65051D01*
X200985D01*
G01X191300Y54500D02*
Y50500D01*
X198700D01*
G01X205000Y70017D02*
X202500D01*
Y71058D01*
X202625Y71392D01*
X202792Y71600D01*
X203125Y71683D01*
X203458Y71600D01*
X203667Y71350D01*
X203792Y71058D01*
Y70017D01*
G01Y71058D02*
X205000Y71683D01*
G01X204625Y73033D02*
X204833Y73283D01*
X204958Y73575D01*
X205000Y73950D01*
X204917Y74325D01*
X204750Y74617D01*
X204458Y74825D01*
X204125Y74867D01*
X203792Y74783D01*
X203583Y74575D01*
X203417Y74283D01*
X203375Y73992D01*
X203417Y73700D01*
X203583Y73325D01*
X202500Y73450D01*
Y74575D01*
G01X205000Y77050D02*
X204958Y77342D01*
X204833Y77675D01*
X204625Y77883D01*
X204333Y77967D01*
X204042Y77883D01*
X203792Y77633D01*
X203667Y77258D01*
Y76842D01*
X203583Y76592D01*
X203375Y76383D01*
X203083Y76300D01*
X202792Y76425D01*
X202583Y76717D01*
X202500Y77050D01*
X202583Y77383D01*
X202792Y77675D01*
X203083Y77800D01*
X203375Y77717D01*
X203583Y77508D01*
X203667Y77258D01*
Y76842D01*
X203792Y76467D01*
X204042Y76217D01*
X204333Y76133D01*
X204625Y76217D01*
X204833Y76425D01*
X204958Y76758D01*
X205000Y77050D01*
G01X202917Y79358D02*
X202667Y79608D01*
X202542Y79900D01*
X202500Y80233D01*
X202583Y80650D01*
X202792Y80942D01*
X203042Y81025D01*
X203292Y80983D01*
X203500Y80817D01*
X203917Y79983D01*
X204208Y79608D01*
X204625Y79358D01*
X205000Y79275D01*
Y81025D01*
G01X199500Y54800D02*
X203500D01*
Y62200D01*
G01X197139Y70197D02*
X194639D01*
Y71238D01*
X194764Y71572D01*
X194931Y71780D01*
X195264Y71863D01*
X195597Y71780D01*
X195806Y71530D01*
X195931Y71238D01*
Y70197D01*
G01Y71238D02*
X197139Y71863D01*
G01X196764Y73213D02*
X196972Y73463D01*
X197097Y73755D01*
X197139Y74130D01*
X197056Y74505D01*
X196889Y74797D01*
X196597Y75005D01*
X196264Y75047D01*
X195931Y74963D01*
X195722Y74755D01*
X195556Y74463D01*
X195514Y74172D01*
X195556Y73880D01*
X195722Y73505D01*
X194639Y73630D01*
Y74755D01*
G01X197139Y77230D02*
X197097Y77522D01*
X196972Y77855D01*
X196764Y78063D01*
X196472Y78147D01*
X196181Y78063D01*
X195931Y77813D01*
X195806Y77438D01*
Y77022D01*
X195722Y76772D01*
X195514Y76563D01*
X195222Y76480D01*
X194931Y76605D01*
X194722Y76897D01*
X194639Y77230D01*
X194722Y77563D01*
X194931Y77855D01*
X195222Y77980D01*
X195514Y77897D01*
X195722Y77688D01*
X195806Y77438D01*
Y77022D01*
X195931Y76647D01*
X196181Y76397D01*
X196472Y76313D01*
X196764Y76397D01*
X196972Y76605D01*
X197097Y76938D01*
X197139Y77230D01*
G01X196639Y79413D02*
X196931Y79663D01*
X197097Y79997D01*
X197139Y80372D01*
X197097Y80705D01*
X196889Y81038D01*
X196639Y81247D01*
X196389Y81288D01*
X196097Y81205D01*
X195889Y80913D01*
X195806Y80622D01*
Y80247D01*
G01Y80622D02*
X195681Y80872D01*
X195472Y81080D01*
X195222Y81163D01*
X194972Y81080D01*
X194764Y80872D01*
X194639Y80497D01*
X194681Y80122D01*
X194847Y79747D01*
G01X199000Y62200D02*
X195000D01*
Y54800D01*
G01X204500Y57500D02*
X211500D01*
G01X189875Y153000D02*
X190208Y152792D01*
X190583Y152667D01*
X190917D01*
X191250Y152792D01*
X191500Y153000D01*
X191625Y153292D01*
X191542Y153584D01*
X191333Y153834D01*
X190958Y154000D01*
X190458Y154084D01*
X190167Y154250D01*
X190042Y154542D01*
X190125Y154834D01*
X190333Y155042D01*
X190625Y155167D01*
X190917D01*
X191208Y155084D01*
X191458Y154875D01*
G01X192933Y152667D02*
Y155167D01*
X193767D01*
X194100Y155042D01*
X194350Y154875D01*
X194558Y154625D01*
X194725Y154334D01*
X194767Y153917D01*
X194725Y153500D01*
X194558Y153209D01*
X194350Y152959D01*
X194100Y152792D01*
X193767Y152667D01*
X192933D01*
G01X196033D02*
Y155167D01*
X196867D01*
X197200Y155042D01*
X197450Y154875D01*
X197658Y154625D01*
X197825Y154334D01*
X197867Y153917D01*
X197825Y153500D01*
X197658Y153209D01*
X197450Y152959D01*
X197200Y152792D01*
X196867Y152667D01*
X196033D01*
G01X202108D02*
X203150Y155167D01*
X204192Y152667D01*
G01X203817Y153542D02*
X202483D01*
G01X207167Y154959D02*
X206917Y155084D01*
X206625Y155167D01*
X206292D01*
X205917Y155042D01*
X205625Y154834D01*
X205417Y154584D01*
X205250Y154167D01*
X205208Y153792D01*
X205292Y153417D01*
X205417Y153167D01*
X205667Y152917D01*
X205958Y152750D01*
X206250Y152667D01*
X206542D01*
X206833Y152750D01*
X207083Y152875D01*
X207292Y153042D01*
G01X209350Y155167D02*
Y152667D01*
G01X208392Y155167D02*
X210308D01*
G01X211742Y152959D02*
X212033Y152750D01*
X212367Y152667D01*
X212700Y152750D01*
X212992Y153000D01*
X213200Y153375D01*
X213283Y153750D01*
Y154209D01*
X213200Y154584D01*
X212992Y154917D01*
X212742Y155084D01*
X212450Y155167D01*
X212117Y155084D01*
X211867Y154917D01*
X211700Y154667D01*
X211617Y154334D01*
X211700Y154042D01*
X211908Y153750D01*
X212158Y153584D01*
X212450Y153542D01*
X212783Y153625D01*
X213033Y153834D01*
X213283Y154209D01*
G01X202100Y142800D02*
X202058Y142467D01*
X201892Y142175D01*
X201642Y141925D01*
X201350Y141758D01*
X201017Y141675D01*
X200683D01*
X200350Y141758D01*
X200058Y141925D01*
X199808Y142175D01*
X199642Y142467D01*
X199600Y142800D01*
X199642Y143133D01*
X199808Y143425D01*
X200058Y143675D01*
X200350Y143842D01*
X200683Y143925D01*
X201017D01*
X201350Y143842D01*
X201642Y143675D01*
X201892Y143425D01*
X202058Y143133D01*
X202100Y142800D01*
G01X201433Y143133D02*
X202100Y143633D01*
G01Y145817D02*
X201558Y145900D01*
X201100Y146025D01*
X200683Y146192D01*
X200225Y146400D01*
X199600Y146733D01*
Y145067D01*
G01X201600Y148083D02*
X201892Y148333D01*
X202058Y148667D01*
X202100Y149042D01*
X202058Y149375D01*
X201850Y149708D01*
X201600Y149917D01*
X201350Y149958D01*
X201058Y149875D01*
X200850Y149583D01*
X200767Y149292D01*
Y148917D01*
G01Y149292D02*
X200642Y149542D01*
X200433Y149750D01*
X200183Y149833D01*
X199933Y149750D01*
X199725Y149542D01*
X199600Y149167D01*
X199642Y148792D01*
X199808Y148417D01*
G01X198000Y137500D02*
Y151500D01*
G01X185000Y137500D02*
X198000D01*
G01X185000Y151500D02*
Y137500D01*
G01X198000Y151500D02*
X185000D01*
G01X197467Y133000D02*
Y135500D01*
X198508D01*
X198842Y135375D01*
X199050Y135208D01*
X199133Y134875D01*
X199050Y134542D01*
X198800Y134333D01*
X198508Y134208D01*
X197467D01*
G01X198508D02*
X199133Y133000D01*
G01X200692Y133292D02*
X200983Y133083D01*
X201317Y133000D01*
X201650Y133083D01*
X201942Y133333D01*
X202150Y133708D01*
X202233Y134083D01*
Y134542D01*
X202150Y134917D01*
X201942Y135250D01*
X201692Y135417D01*
X201400Y135500D01*
X201067Y135417D01*
X200817Y135250D01*
X200650Y135000D01*
X200567Y134667D01*
X200650Y134375D01*
X200858Y134083D01*
X201108Y133917D01*
X201400Y133875D01*
X201733Y133958D01*
X201983Y134167D01*
X202233Y134542D01*
G01X204500Y133000D02*
X204792Y133042D01*
X205125Y133167D01*
X205333Y133375D01*
X205417Y133667D01*
X205333Y133958D01*
X205083Y134208D01*
X204708Y134333D01*
X204292D01*
X204042Y134417D01*
X203833Y134625D01*
X203750Y134917D01*
X203875Y135208D01*
X204167Y135417D01*
X204500Y135500D01*
X204833Y135417D01*
X205125Y135208D01*
X205250Y134917D01*
X205167Y134625D01*
X204958Y134417D01*
X204708Y134333D01*
X204292D01*
X203917Y134208D01*
X203667Y133958D01*
X203583Y133667D01*
X203667Y133375D01*
X203875Y133167D01*
X204208Y133042D01*
X204500Y133000D01*
G01X208100D02*
Y135500D01*
X206558Y133708D01*
X208642D01*
G01X210700Y133000D02*
Y135500D01*
X210200Y135000D01*
G01Y133000D02*
X211200D01*
G01X188300Y137000D02*
Y133000D01*
X195700D01*
G01X201767Y164900D02*
Y167400D01*
X202808D01*
X203142Y167275D01*
X203350Y167108D01*
X203433Y166775D01*
X203350Y166442D01*
X203100Y166233D01*
X202808Y166108D01*
X201767D01*
G01X202808D02*
X203433Y164900D01*
G01X204992Y165192D02*
X205283Y164983D01*
X205617Y164900D01*
X205950Y164983D01*
X206242Y165233D01*
X206450Y165608D01*
X206533Y165983D01*
Y166442D01*
X206450Y166817D01*
X206242Y167150D01*
X205992Y167317D01*
X205700Y167400D01*
X205367Y167317D01*
X205117Y167150D01*
X204950Y166900D01*
X204867Y166567D01*
X204950Y166275D01*
X205158Y165983D01*
X205408Y165817D01*
X205700Y165775D01*
X206033Y165858D01*
X206283Y166067D01*
X206533Y166442D01*
G01X209300Y164900D02*
Y167400D01*
X207758Y165608D01*
X209842D01*
G01X211192Y165192D02*
X211483Y164983D01*
X211817Y164900D01*
X212150Y164983D01*
X212442Y165233D01*
X212650Y165608D01*
X212733Y165983D01*
Y166442D01*
X212650Y166817D01*
X212442Y167150D01*
X212192Y167317D01*
X211900Y167400D01*
X211567Y167317D01*
X211317Y167150D01*
X211150Y166900D01*
X211067Y166567D01*
X211150Y166275D01*
X211358Y165983D01*
X211608Y165817D01*
X211900Y165775D01*
X212233Y165858D01*
X212483Y166067D01*
X212733Y166442D01*
G01X214083Y165400D02*
X214333Y165108D01*
X214667Y164942D01*
X215042Y164900D01*
X215375Y164942D01*
X215708Y165150D01*
X215917Y165400D01*
X215958Y165650D01*
X215875Y165942D01*
X215583Y166150D01*
X215292Y166233D01*
X214917D01*
G01X215292D02*
X215542Y166358D01*
X215750Y166567D01*
X215833Y166817D01*
X215750Y167067D01*
X215542Y167275D01*
X215167Y167400D01*
X214792Y167358D01*
X214417Y167192D01*
G01X197700Y165000D02*
Y169000D01*
X190300D01*
G01X201767Y156900D02*
Y159400D01*
X202808D01*
X203142Y159275D01*
X203350Y159108D01*
X203433Y158775D01*
X203350Y158442D01*
X203100Y158233D01*
X202808Y158108D01*
X201767D01*
G01X202808D02*
X203433Y156900D01*
G01X204992Y157192D02*
X205283Y156983D01*
X205617Y156900D01*
X205950Y156983D01*
X206242Y157233D01*
X206450Y157608D01*
X206533Y157983D01*
Y158442D01*
X206450Y158817D01*
X206242Y159150D01*
X205992Y159317D01*
X205700Y159400D01*
X205367Y159317D01*
X205117Y159150D01*
X204950Y158900D01*
X204867Y158567D01*
X204950Y158275D01*
X205158Y157983D01*
X205408Y157817D01*
X205700Y157775D01*
X206033Y157858D01*
X206283Y158067D01*
X206533Y158442D01*
G01X208092Y157192D02*
X208383Y156983D01*
X208717Y156900D01*
X209050Y156983D01*
X209342Y157233D01*
X209550Y157608D01*
X209633Y157983D01*
Y158442D01*
X209550Y158817D01*
X209342Y159150D01*
X209092Y159317D01*
X208800Y159400D01*
X208467Y159317D01*
X208217Y159150D01*
X208050Y158900D01*
X207967Y158567D01*
X208050Y158275D01*
X208258Y157983D01*
X208508Y157817D01*
X208800Y157775D01*
X209133Y157858D01*
X209383Y158067D01*
X209633Y158442D01*
G01X211900Y159400D02*
X211567Y159317D01*
X211317Y159108D01*
X211150Y158858D01*
X211025Y158525D01*
X210983Y158150D01*
X211025Y157775D01*
X211150Y157442D01*
X211317Y157192D01*
X211567Y156983D01*
X211900Y156900D01*
X212233Y156983D01*
X212483Y157192D01*
X212650Y157442D01*
X212775Y157775D01*
X212817Y158150D01*
X212775Y158525D01*
X212650Y158858D01*
X212483Y159108D01*
X212233Y159317D01*
X211900Y159400D01*
G01X215000Y156900D02*
Y159400D01*
X214500Y158900D01*
G01Y156900D02*
X215500D01*
G01X197700Y156000D02*
Y160000D01*
X190300D01*
G01X201767Y160900D02*
Y163400D01*
X202808D01*
X203142Y163275D01*
X203350Y163108D01*
X203433Y162775D01*
X203350Y162442D01*
X203100Y162233D01*
X202808Y162108D01*
X201767D01*
G01X202808D02*
X203433Y160900D01*
G01X204992Y161192D02*
X205283Y160983D01*
X205617Y160900D01*
X205950Y160983D01*
X206242Y161233D01*
X206450Y161608D01*
X206533Y161983D01*
Y162442D01*
X206450Y162817D01*
X206242Y163150D01*
X205992Y163317D01*
X205700Y163400D01*
X205367Y163317D01*
X205117Y163150D01*
X204950Y162900D01*
X204867Y162567D01*
X204950Y162275D01*
X205158Y161983D01*
X205408Y161817D01*
X205700Y161775D01*
X206033Y161858D01*
X206283Y162067D01*
X206533Y162442D01*
G01X207883Y161400D02*
X208133Y161108D01*
X208467Y160942D01*
X208842Y160900D01*
X209175Y160942D01*
X209508Y161150D01*
X209717Y161400D01*
X209758Y161650D01*
X209675Y161942D01*
X209383Y162150D01*
X209092Y162233D01*
X208717D01*
G01X209092D02*
X209342Y162358D01*
X209550Y162567D01*
X209633Y162817D01*
X209550Y163067D01*
X209342Y163275D01*
X208967Y163400D01*
X208592Y163358D01*
X208217Y163192D01*
G01X211192Y161192D02*
X211483Y160983D01*
X211817Y160900D01*
X212150Y160983D01*
X212442Y161233D01*
X212650Y161608D01*
X212733Y161983D01*
Y162442D01*
X212650Y162817D01*
X212442Y163150D01*
X212192Y163317D01*
X211900Y163400D01*
X211567Y163317D01*
X211317Y163150D01*
X211150Y162900D01*
X211067Y162567D01*
X211150Y162275D01*
X211358Y161983D01*
X211608Y161817D01*
X211900Y161775D01*
X212233Y161858D01*
X212483Y162067D01*
X212733Y162442D01*
G01X215500Y160900D02*
Y163400D01*
X213958Y161608D01*
X216042D01*
G01X197700Y160500D02*
Y164500D01*
X190300D01*
G01X218800Y550300D02*
X218467Y550342D01*
X218175Y550508D01*
X217925Y550758D01*
X217758Y551050D01*
X217675Y551383D01*
Y551717D01*
X217758Y552050D01*
X217925Y552342D01*
X218175Y552592D01*
X218467Y552758D01*
X218800Y552800D01*
X219133Y552758D01*
X219425Y552592D01*
X219675Y552342D01*
X219842Y552050D01*
X219925Y551717D01*
Y551383D01*
X219842Y551050D01*
X219675Y550758D01*
X219425Y550508D01*
X219133Y550342D01*
X218800Y550300D01*
G01X219133Y550967D02*
X219633Y550300D01*
G01X221108Y551342D02*
X221400Y551633D01*
X221650Y551800D01*
X221983Y551883D01*
X222275Y551800D01*
X222483Y551633D01*
X222650Y551383D01*
X222692Y551092D01*
X222650Y550842D01*
X222483Y550592D01*
X222233Y550383D01*
X221942Y550300D01*
X221608Y550383D01*
X221317Y550633D01*
X221150Y551008D01*
X221108Y551425D01*
X221192Y551967D01*
X221317Y552258D01*
X221525Y552550D01*
X221817Y552758D01*
X222108Y552800D01*
X222400Y552717D01*
X222608Y552508D01*
G01X225000Y550300D02*
X225292Y550342D01*
X225625Y550467D01*
X225833Y550675D01*
X225917Y550967D01*
X225833Y551258D01*
X225583Y551508D01*
X225208Y551633D01*
X224792D01*
X224542Y551717D01*
X224333Y551925D01*
X224250Y552217D01*
X224375Y552508D01*
X224667Y552717D01*
X225000Y552800D01*
X225333Y552717D01*
X225625Y552508D01*
X225750Y552217D01*
X225667Y551925D01*
X225458Y551717D01*
X225208Y551633D01*
X224792D01*
X224417Y551508D01*
X224167Y551258D01*
X224083Y550967D01*
X224167Y550675D01*
X224375Y550467D01*
X224708Y550342D01*
X225000Y550300D01*
G01X199000Y552500D02*
X213000D01*
G01X199000Y565500D02*
Y552500D01*
G01X213000D02*
Y565500D01*
G01X215509Y524827D02*
X213009D01*
Y525868D01*
X213134Y526202D01*
X213301Y526410D01*
X213634Y526493D01*
X213967Y526410D01*
X214176Y526160D01*
X214301Y525868D01*
Y524827D01*
G01Y525868D02*
X215509Y526493D01*
G01X215009Y527843D02*
X215301Y528093D01*
X215467Y528427D01*
X215509Y528802D01*
X215467Y529135D01*
X215259Y529468D01*
X215009Y529677D01*
X214759Y529718D01*
X214467Y529635D01*
X214259Y529343D01*
X214176Y529052D01*
Y528677D01*
G01Y529052D02*
X214051Y529302D01*
X213842Y529510D01*
X213592Y529593D01*
X213342Y529510D01*
X213134Y529302D01*
X213009Y528927D01*
X213051Y528552D01*
X213217Y528177D01*
G01X215509Y531860D02*
X213009D01*
X213509Y531360D01*
G01X215509D02*
Y532360D01*
G01Y534960D02*
X215467Y535252D01*
X215342Y535585D01*
X215134Y535793D01*
X214842Y535877D01*
X214551Y535793D01*
X214301Y535543D01*
X214176Y535168D01*
Y534752D01*
X214092Y534502D01*
X213884Y534293D01*
X213592Y534210D01*
X213301Y534335D01*
X213092Y534627D01*
X213009Y534960D01*
X213092Y535293D01*
X213301Y535585D01*
X213592Y535710D01*
X213884Y535627D01*
X214092Y535418D01*
X214176Y535168D01*
Y534752D01*
X214301Y534377D01*
X214551Y534127D01*
X214842Y534043D01*
X215134Y534127D01*
X215342Y534335D01*
X215467Y534668D01*
X215509Y534960D01*
G01X205000Y540700D02*
X201000D01*
Y533300D01*
G01X215439Y537607D02*
X212939D01*
Y538648D01*
X213064Y538982D01*
X213231Y539190D01*
X213564Y539273D01*
X213897Y539190D01*
X214106Y538940D01*
X214231Y538648D01*
Y537607D01*
G01Y538648D02*
X215439Y539273D01*
G01X214939Y540623D02*
X215231Y540873D01*
X215397Y541207D01*
X215439Y541582D01*
X215397Y541915D01*
X215189Y542248D01*
X214939Y542457D01*
X214689Y542498D01*
X214397Y542415D01*
X214189Y542123D01*
X214106Y541832D01*
Y541457D01*
G01Y541832D02*
X213981Y542082D01*
X213772Y542290D01*
X213522Y542373D01*
X213272Y542290D01*
X213064Y542082D01*
X212939Y541707D01*
X212981Y541332D01*
X213147Y540957D01*
G01X213356Y543848D02*
X213106Y544098D01*
X212981Y544390D01*
X212939Y544723D01*
X213022Y545140D01*
X213231Y545432D01*
X213481Y545515D01*
X213731Y545473D01*
X213939Y545307D01*
X214356Y544473D01*
X214647Y544098D01*
X215064Y543848D01*
X215439Y543765D01*
Y545515D01*
G01X213356Y546948D02*
X213106Y547198D01*
X212981Y547490D01*
X212939Y547823D01*
X213022Y548240D01*
X213231Y548532D01*
X213481Y548615D01*
X213731Y548573D01*
X213939Y548407D01*
X214356Y547573D01*
X214647Y547198D01*
X215064Y546948D01*
X215439Y546865D01*
Y548615D01*
G01X205000Y548200D02*
X201000D01*
Y540800D01*
G01X211509Y524827D02*
X209009D01*
Y525868D01*
X209134Y526202D01*
X209301Y526410D01*
X209634Y526493D01*
X209967Y526410D01*
X210176Y526160D01*
X210301Y525868D01*
Y524827D01*
G01Y525868D02*
X211509Y526493D01*
G01X211009Y527843D02*
X211301Y528093D01*
X211467Y528427D01*
X211509Y528802D01*
X211467Y529135D01*
X211259Y529468D01*
X211009Y529677D01*
X210759Y529718D01*
X210467Y529635D01*
X210259Y529343D01*
X210176Y529052D01*
Y528677D01*
G01Y529052D02*
X210051Y529302D01*
X209842Y529510D01*
X209592Y529593D01*
X209342Y529510D01*
X209134Y529302D01*
X209009Y528927D01*
X209051Y528552D01*
X209217Y528177D01*
G01X211509Y532360D02*
X209009D01*
X210801Y530818D01*
Y532902D01*
G01X209426Y534168D02*
X209176Y534418D01*
X209051Y534710D01*
X209009Y535043D01*
X209092Y535460D01*
X209301Y535752D01*
X209551Y535835D01*
X209801Y535793D01*
X210009Y535627D01*
X210426Y534793D01*
X210717Y534418D01*
X211134Y534168D01*
X211509Y534085D01*
Y535835D01*
G01X197000Y533300D02*
X201000D01*
Y540700D01*
G01X211509Y512357D02*
X209009D01*
Y513398D01*
X209134Y513732D01*
X209301Y513940D01*
X209634Y514023D01*
X209967Y513940D01*
X210176Y513690D01*
X210301Y513398D01*
Y512357D01*
G01Y513398D02*
X211509Y514023D01*
G01X211009Y515373D02*
X211301Y515623D01*
X211467Y515957D01*
X211509Y516332D01*
X211467Y516665D01*
X211259Y516998D01*
X211009Y517207D01*
X210759Y517248D01*
X210467Y517165D01*
X210259Y516873D01*
X210176Y516582D01*
Y516207D01*
G01Y516582D02*
X210051Y516832D01*
X209842Y517040D01*
X209592Y517123D01*
X209342Y517040D01*
X209134Y516832D01*
X209009Y516457D01*
X209051Y516082D01*
X209217Y515707D01*
G01X211509Y519890D02*
X209009D01*
X210801Y518348D01*
Y520432D01*
G01X211009Y521573D02*
X211301Y521823D01*
X211467Y522157D01*
X211509Y522532D01*
X211467Y522865D01*
X211259Y523198D01*
X211009Y523407D01*
X210759Y523448D01*
X210467Y523365D01*
X210259Y523073D01*
X210176Y522782D01*
Y522407D01*
G01Y522782D02*
X210051Y523032D01*
X209842Y523240D01*
X209592Y523323D01*
X209342Y523240D01*
X209134Y523032D01*
X209009Y522657D01*
X209051Y522282D01*
X209217Y521907D01*
G01X197000Y525800D02*
X201000D01*
Y533200D01*
G01X211439Y537607D02*
X208939D01*
Y538648D01*
X209064Y538982D01*
X209231Y539190D01*
X209564Y539273D01*
X209897Y539190D01*
X210106Y538940D01*
X210231Y538648D01*
Y537607D01*
G01Y538648D02*
X211439Y539273D01*
G01X210939Y540623D02*
X211231Y540873D01*
X211397Y541207D01*
X211439Y541582D01*
X211397Y541915D01*
X211189Y542248D01*
X210939Y542457D01*
X210689Y542498D01*
X210397Y542415D01*
X210189Y542123D01*
X210106Y541832D01*
Y541457D01*
G01Y541832D02*
X209981Y542082D01*
X209772Y542290D01*
X209522Y542373D01*
X209272Y542290D01*
X209064Y542082D01*
X208939Y541707D01*
X208981Y541332D01*
X209147Y540957D01*
G01X211439Y545140D02*
X208939D01*
X210731Y543598D01*
Y545682D01*
G01X211439Y548240D02*
X208939D01*
X210731Y546698D01*
Y548782D01*
G01X197000Y540800D02*
X201000D01*
Y548200D01*
G01X215509Y512357D02*
X213009D01*
Y513398D01*
X213134Y513732D01*
X213301Y513940D01*
X213634Y514023D01*
X213967Y513940D01*
X214176Y513690D01*
X214301Y513398D01*
Y512357D01*
G01Y513398D02*
X215509Y514023D01*
G01X215009Y515373D02*
X215301Y515623D01*
X215467Y515957D01*
X215509Y516332D01*
X215467Y516665D01*
X215259Y516998D01*
X215009Y517207D01*
X214759Y517248D01*
X214467Y517165D01*
X214259Y516873D01*
X214176Y516582D01*
Y516207D01*
G01Y516582D02*
X214051Y516832D01*
X213842Y517040D01*
X213592Y517123D01*
X213342Y517040D01*
X213134Y516832D01*
X213009Y516457D01*
X213051Y516082D01*
X213217Y515707D01*
G01X215134Y518473D02*
X215342Y518723D01*
X215467Y519015D01*
X215509Y519390D01*
X215426Y519765D01*
X215259Y520057D01*
X214967Y520265D01*
X214634Y520307D01*
X214301Y520223D01*
X214092Y520015D01*
X213926Y519723D01*
X213884Y519432D01*
X213926Y519140D01*
X214092Y518765D01*
X213009Y518890D01*
Y520015D01*
G01X215009Y521573D02*
X215301Y521823D01*
X215467Y522157D01*
X215509Y522532D01*
X215467Y522865D01*
X215259Y523198D01*
X215009Y523407D01*
X214759Y523448D01*
X214467Y523365D01*
X214259Y523073D01*
X214176Y522782D01*
Y522407D01*
G01Y522782D02*
X214051Y523032D01*
X213842Y523240D01*
X213592Y523323D01*
X213342Y523240D01*
X213134Y523032D01*
X213009Y522657D01*
X213051Y522282D01*
X213217Y521907D01*
G01X205000Y533200D02*
X201000D01*
Y525800D01*
G01X221367Y553967D02*
Y556467D01*
X222408D01*
X222742Y556342D01*
X222950Y556175D01*
X223033Y555842D01*
X222950Y555509D01*
X222700Y555300D01*
X222408Y555175D01*
X221367D01*
G01X222408D02*
X223033Y553967D01*
G01X224592Y554259D02*
X224883Y554050D01*
X225217Y553967D01*
X225550Y554050D01*
X225842Y554300D01*
X226050Y554675D01*
X226133Y555050D01*
Y555509D01*
X226050Y555884D01*
X225842Y556217D01*
X225592Y556384D01*
X225300Y556467D01*
X224967Y556384D01*
X224717Y556217D01*
X224550Y555967D01*
X224467Y555634D01*
X224550Y555342D01*
X224758Y555050D01*
X225008Y554884D01*
X225300Y554842D01*
X225633Y554925D01*
X225883Y555134D01*
X226133Y555509D01*
G01X228400Y553967D02*
X228692Y554009D01*
X229025Y554134D01*
X229233Y554342D01*
X229317Y554634D01*
X229233Y554925D01*
X228983Y555175D01*
X228608Y555300D01*
X228192D01*
X227942Y555384D01*
X227733Y555592D01*
X227650Y555884D01*
X227775Y556175D01*
X228067Y556384D01*
X228400Y556467D01*
X228733Y556384D01*
X229025Y556175D01*
X229150Y555884D01*
X229067Y555592D01*
X228858Y555384D01*
X228608Y555300D01*
X228192D01*
X227817Y555175D01*
X227567Y554925D01*
X227483Y554634D01*
X227567Y554342D01*
X227775Y554134D01*
X228108Y554009D01*
X228400Y553967D01*
G01X230583Y554467D02*
X230833Y554175D01*
X231167Y554009D01*
X231542Y553967D01*
X231875Y554009D01*
X232208Y554217D01*
X232417Y554467D01*
X232458Y554717D01*
X232375Y555009D01*
X232083Y555217D01*
X231792Y555300D01*
X231417D01*
G01X231792D02*
X232042Y555425D01*
X232250Y555634D01*
X232333Y555884D01*
X232250Y556134D01*
X232042Y556342D01*
X231667Y556467D01*
X231292Y556425D01*
X230917Y556259D01*
G01X234517Y553967D02*
X234600Y554509D01*
X234725Y554967D01*
X234892Y555384D01*
X235100Y555842D01*
X235433Y556467D01*
X233767D01*
G01X213000Y565500D02*
X199000D01*
G01X197200Y571500D02*
Y575500D01*
X189800D01*
G01X252835Y572653D02*
X253168Y572445D01*
X253543Y572320D01*
X253877D01*
X254210Y572445D01*
X254460Y572653D01*
X254585Y572945D01*
X254502Y573237D01*
X254293Y573487D01*
X253918Y573653D01*
X253418Y573737D01*
X253127Y573903D01*
X253002Y574195D01*
X253085Y574487D01*
X253293Y574695D01*
X253585Y574820D01*
X253877D01*
X254168Y574737D01*
X254418Y574528D01*
G01X255977Y572320D02*
Y574820D01*
X257018D01*
X257352Y574695D01*
X257560Y574528D01*
X257643Y574195D01*
X257560Y573862D01*
X257310Y573653D01*
X257018Y573528D01*
X255977D01*
G01X257018D02*
X257643Y572320D01*
G01X259202Y572612D02*
X259493Y572403D01*
X259827Y572320D01*
X260160Y572403D01*
X260452Y572653D01*
X260660Y573028D01*
X260743Y573403D01*
Y573862D01*
X260660Y574237D01*
X260452Y574570D01*
X260202Y574737D01*
X259910Y574820D01*
X259577Y574737D01*
X259327Y574570D01*
X259160Y574320D01*
X259077Y573987D01*
X259160Y573695D01*
X259368Y573403D01*
X259618Y573237D01*
X259910Y573195D01*
X260243Y573278D01*
X260493Y573487D01*
X260743Y573862D01*
G01X262218Y573362D02*
X262510Y573653D01*
X262760Y573820D01*
X263093Y573903D01*
X263385Y573820D01*
X263593Y573653D01*
X263760Y573403D01*
X263802Y573112D01*
X263760Y572862D01*
X263593Y572612D01*
X263343Y572403D01*
X263052Y572320D01*
X262718Y572403D01*
X262427Y572653D01*
X262260Y573028D01*
X262218Y573445D01*
X262302Y573987D01*
X262427Y574278D01*
X262635Y574570D01*
X262927Y574778D01*
X263218Y574820D01*
X263510Y574737D01*
X263718Y574528D01*
G01X265318Y573362D02*
X265610Y573653D01*
X265860Y573820D01*
X266193Y573903D01*
X266485Y573820D01*
X266693Y573653D01*
X266860Y573403D01*
X266902Y573112D01*
X266860Y572862D01*
X266693Y572612D01*
X266443Y572403D01*
X266152Y572320D01*
X265818Y572403D01*
X265527Y572653D01*
X265360Y573028D01*
X265318Y573445D01*
X265402Y573987D01*
X265527Y574278D01*
X265735Y574570D01*
X266027Y574778D01*
X266318Y574820D01*
X266610Y574737D01*
X266818Y574528D01*
G01X252425Y565333D02*
X252758Y565125D01*
X253133Y565000D01*
X253467D01*
X253800Y565125D01*
X254050Y565333D01*
X254175Y565625D01*
X254092Y565917D01*
X253883Y566167D01*
X253508Y566333D01*
X253008Y566417D01*
X252717Y566583D01*
X252592Y566875D01*
X252675Y567167D01*
X252883Y567375D01*
X253175Y567500D01*
X253467D01*
X253758Y567417D01*
X254008Y567208D01*
G01X255567Y565000D02*
Y567500D01*
X256608D01*
X256942Y567375D01*
X257150Y567208D01*
X257233Y566875D01*
X257150Y566542D01*
X256900Y566333D01*
X256608Y566208D01*
X255567D01*
G01X256608D02*
X257233Y565000D01*
G01X258792Y565292D02*
X259083Y565083D01*
X259417Y565000D01*
X259750Y565083D01*
X260042Y565333D01*
X260250Y565708D01*
X260333Y566083D01*
Y566542D01*
X260250Y566917D01*
X260042Y567250D01*
X259792Y567417D01*
X259500Y567500D01*
X259167Y567417D01*
X258917Y567250D01*
X258750Y567000D01*
X258667Y566667D01*
X258750Y566375D01*
X258958Y566083D01*
X259208Y565917D01*
X259500Y565875D01*
X259833Y565958D01*
X260083Y566167D01*
X260333Y566542D01*
G01X261808Y566042D02*
X262100Y566333D01*
X262350Y566500D01*
X262683Y566583D01*
X262975Y566500D01*
X263183Y566333D01*
X263350Y566083D01*
X263392Y565792D01*
X263350Y565542D01*
X263183Y565292D01*
X262933Y565083D01*
X262642Y565000D01*
X262308Y565083D01*
X262017Y565333D01*
X261850Y565708D01*
X261808Y566125D01*
X261892Y566667D01*
X262017Y566958D01*
X262225Y567250D01*
X262517Y567458D01*
X262808Y567500D01*
X263100Y567417D01*
X263308Y567208D01*
G01X265617Y565000D02*
X265700Y565542D01*
X265825Y566000D01*
X265992Y566417D01*
X266200Y566875D01*
X266533Y567500D01*
X264867D01*
G01X252335Y583653D02*
X252668Y583445D01*
X253043Y583320D01*
X253377D01*
X253710Y583445D01*
X253960Y583653D01*
X254085Y583945D01*
X254002Y584237D01*
X253793Y584487D01*
X253418Y584653D01*
X252918Y584737D01*
X252627Y584903D01*
X252502Y585195D01*
X252585Y585487D01*
X252793Y585695D01*
X253085Y585820D01*
X253377D01*
X253668Y585737D01*
X253918Y585528D01*
G01X255477Y583320D02*
Y585820D01*
X256518D01*
X256852Y585695D01*
X257060Y585528D01*
X257143Y585195D01*
X257060Y584862D01*
X256810Y584653D01*
X256518Y584528D01*
X255477D01*
G01X256518D02*
X257143Y583320D01*
G01X258702Y583612D02*
X258993Y583403D01*
X259327Y583320D01*
X259660Y583403D01*
X259952Y583653D01*
X260160Y584028D01*
X260243Y584403D01*
Y584862D01*
X260160Y585237D01*
X259952Y585570D01*
X259702Y585737D01*
X259410Y585820D01*
X259077Y585737D01*
X258827Y585570D01*
X258660Y585320D01*
X258577Y584987D01*
X258660Y584695D01*
X258868Y584403D01*
X259118Y584237D01*
X259410Y584195D01*
X259743Y584278D01*
X259993Y584487D01*
X260243Y584862D01*
G01X261718Y584362D02*
X262010Y584653D01*
X262260Y584820D01*
X262593Y584903D01*
X262885Y584820D01*
X263093Y584653D01*
X263260Y584403D01*
X263302Y584112D01*
X263260Y583862D01*
X263093Y583612D01*
X262843Y583403D01*
X262552Y583320D01*
X262218Y583403D01*
X261927Y583653D01*
X261760Y584028D01*
X261718Y584445D01*
X261802Y584987D01*
X261927Y585278D01*
X262135Y585570D01*
X262427Y585778D01*
X262718Y585820D01*
X263010Y585737D01*
X263218Y585528D01*
G01X265610Y583320D02*
X265902Y583362D01*
X266235Y583487D01*
X266443Y583695D01*
X266527Y583987D01*
X266443Y584278D01*
X266193Y584528D01*
X265818Y584653D01*
X265402D01*
X265152Y584737D01*
X264943Y584945D01*
X264860Y585237D01*
X264985Y585528D01*
X265277Y585737D01*
X265610Y585820D01*
X265943Y585737D01*
X266235Y585528D01*
X266360Y585237D01*
X266277Y584945D01*
X266068Y584737D01*
X265818Y584653D01*
X265402D01*
X265027Y584528D01*
X264777Y584278D01*
X264693Y583987D01*
X264777Y583695D01*
X264985Y583487D01*
X265318Y583362D01*
X265610Y583320D01*
G01X252835Y576653D02*
X253168Y576445D01*
X253543Y576320D01*
X253877D01*
X254210Y576445D01*
X254460Y576653D01*
X254585Y576945D01*
X254502Y577237D01*
X254293Y577487D01*
X253918Y577653D01*
X253418Y577737D01*
X253127Y577903D01*
X253002Y578195D01*
X253085Y578487D01*
X253293Y578695D01*
X253585Y578820D01*
X253877D01*
X254168Y578737D01*
X254418Y578528D01*
G01X255977Y576320D02*
Y578820D01*
X257018D01*
X257352Y578695D01*
X257560Y578528D01*
X257643Y578195D01*
X257560Y577862D01*
X257310Y577653D01*
X257018Y577528D01*
X255977D01*
G01X257018D02*
X257643Y576320D01*
G01X259202Y576612D02*
X259493Y576403D01*
X259827Y576320D01*
X260160Y576403D01*
X260452Y576653D01*
X260660Y577028D01*
X260743Y577403D01*
Y577862D01*
X260660Y578237D01*
X260452Y578570D01*
X260202Y578737D01*
X259910Y578820D01*
X259577Y578737D01*
X259327Y578570D01*
X259160Y578320D01*
X259077Y577987D01*
X259160Y577695D01*
X259368Y577403D01*
X259618Y577237D01*
X259910Y577195D01*
X260243Y577278D01*
X260493Y577487D01*
X260743Y577862D01*
G01X262218Y577362D02*
X262510Y577653D01*
X262760Y577820D01*
X263093Y577903D01*
X263385Y577820D01*
X263593Y577653D01*
X263760Y577403D01*
X263802Y577112D01*
X263760Y576862D01*
X263593Y576612D01*
X263343Y576403D01*
X263052Y576320D01*
X262718Y576403D01*
X262427Y576653D01*
X262260Y577028D01*
X262218Y577445D01*
X262302Y577987D01*
X262427Y578278D01*
X262635Y578570D01*
X262927Y578778D01*
X263218Y578820D01*
X263510Y578737D01*
X263718Y578528D01*
G01X265402Y576612D02*
X265693Y576403D01*
X266027Y576320D01*
X266360Y576403D01*
X266652Y576653D01*
X266860Y577028D01*
X266943Y577403D01*
Y577862D01*
X266860Y578237D01*
X266652Y578570D01*
X266402Y578737D01*
X266110Y578820D01*
X265777Y578737D01*
X265527Y578570D01*
X265360Y578320D01*
X265277Y577987D01*
X265360Y577695D01*
X265568Y577403D01*
X265818Y577237D01*
X266110Y577195D01*
X266443Y577278D01*
X266693Y577487D01*
X266943Y577862D01*
G01X252335Y592653D02*
X252668Y592445D01*
X253043Y592320D01*
X253377D01*
X253710Y592445D01*
X253960Y592653D01*
X254085Y592945D01*
X254002Y593237D01*
X253793Y593487D01*
X253418Y593653D01*
X252918Y593737D01*
X252627Y593903D01*
X252502Y594195D01*
X252585Y594487D01*
X252793Y594695D01*
X253085Y594820D01*
X253377D01*
X253668Y594737D01*
X253918Y594528D01*
G01X255477Y592320D02*
Y594820D01*
X256518D01*
X256852Y594695D01*
X257060Y594528D01*
X257143Y594195D01*
X257060Y593862D01*
X256810Y593653D01*
X256518Y593528D01*
X255477D01*
G01X256518D02*
X257143Y592320D01*
G01X258702Y592612D02*
X258993Y592403D01*
X259327Y592320D01*
X259660Y592403D01*
X259952Y592653D01*
X260160Y593028D01*
X260243Y593403D01*
Y593862D01*
X260160Y594237D01*
X259952Y594570D01*
X259702Y594737D01*
X259410Y594820D01*
X259077Y594737D01*
X258827Y594570D01*
X258660Y594320D01*
X258577Y593987D01*
X258660Y593695D01*
X258868Y593403D01*
X259118Y593237D01*
X259410Y593195D01*
X259743Y593278D01*
X259993Y593487D01*
X260243Y593862D01*
G01X262427Y592320D02*
X262510Y592862D01*
X262635Y593320D01*
X262802Y593737D01*
X263010Y594195D01*
X263343Y594820D01*
X261677D01*
G01X265610D02*
X265277Y594737D01*
X265027Y594528D01*
X264860Y594278D01*
X264735Y593945D01*
X264693Y593570D01*
X264735Y593195D01*
X264860Y592862D01*
X265027Y592612D01*
X265277Y592403D01*
X265610Y592320D01*
X265943Y592403D01*
X266193Y592612D01*
X266360Y592862D01*
X266485Y593195D01*
X266527Y593570D01*
X266485Y593945D01*
X266360Y594278D01*
X266193Y594528D01*
X265943Y594737D01*
X265610Y594820D01*
G01X252335Y587653D02*
X252668Y587445D01*
X253043Y587320D01*
X253377D01*
X253710Y587445D01*
X253960Y587653D01*
X254085Y587945D01*
X254002Y588237D01*
X253793Y588487D01*
X253418Y588653D01*
X252918Y588737D01*
X252627Y588903D01*
X252502Y589195D01*
X252585Y589487D01*
X252793Y589695D01*
X253085Y589820D01*
X253377D01*
X253668Y589737D01*
X253918Y589528D01*
G01X255477Y587320D02*
Y589820D01*
X256518D01*
X256852Y589695D01*
X257060Y589528D01*
X257143Y589195D01*
X257060Y588862D01*
X256810Y588653D01*
X256518Y588528D01*
X255477D01*
G01X256518D02*
X257143Y587320D01*
G01X258702Y587612D02*
X258993Y587403D01*
X259327Y587320D01*
X259660Y587403D01*
X259952Y587653D01*
X260160Y588028D01*
X260243Y588403D01*
Y588862D01*
X260160Y589237D01*
X259952Y589570D01*
X259702Y589737D01*
X259410Y589820D01*
X259077Y589737D01*
X258827Y589570D01*
X258660Y589320D01*
X258577Y588987D01*
X258660Y588695D01*
X258868Y588403D01*
X259118Y588237D01*
X259410Y588195D01*
X259743Y588278D01*
X259993Y588487D01*
X260243Y588862D01*
G01X262427Y587320D02*
X262510Y587862D01*
X262635Y588320D01*
X262802Y588737D01*
X263010Y589195D01*
X263343Y589820D01*
X261677D01*
G01X264818Y589403D02*
X265068Y589653D01*
X265360Y589778D01*
X265693Y589820D01*
X266110Y589737D01*
X266402Y589528D01*
X266485Y589278D01*
X266443Y589028D01*
X266277Y588820D01*
X265443Y588403D01*
X265068Y588112D01*
X264818Y587695D01*
X264735Y587320D01*
X266485D01*
G01X214700Y567000D02*
Y571000D01*
X207300D01*
G01X214675Y558300D02*
X215008Y558092D01*
X215383Y557967D01*
X215717D01*
X216050Y558092D01*
X216300Y558300D01*
X216425Y558592D01*
X216342Y558884D01*
X216133Y559134D01*
X215758Y559300D01*
X215258Y559384D01*
X214967Y559550D01*
X214842Y559842D01*
X214925Y560134D01*
X215133Y560342D01*
X215425Y560467D01*
X215717D01*
X216008Y560384D01*
X216258Y560175D01*
G01X217817Y557967D02*
Y560467D01*
X218858D01*
X219192Y560342D01*
X219400Y560175D01*
X219483Y559842D01*
X219400Y559509D01*
X219150Y559300D01*
X218858Y559175D01*
X217817D01*
G01X218858D02*
X219483Y557967D01*
G01X221750D02*
Y560467D01*
X221250Y559967D01*
G01Y557967D02*
X222250D01*
G01X224850D02*
Y560467D01*
X224350Y559967D01*
G01Y557967D02*
X225350D01*
G01X227033Y558467D02*
X227283Y558175D01*
X227617Y558009D01*
X227992Y557967D01*
X228325Y558009D01*
X228658Y558217D01*
X228867Y558467D01*
X228908Y558717D01*
X228825Y559009D01*
X228533Y559217D01*
X228242Y559300D01*
X227867D01*
G01X228242D02*
X228492Y559425D01*
X228700Y559634D01*
X228783Y559884D01*
X228700Y560134D01*
X228492Y560342D01*
X228117Y560467D01*
X227742Y560425D01*
X227367Y560259D01*
G01X231050Y557967D02*
X231342Y558009D01*
X231675Y558134D01*
X231883Y558342D01*
X231967Y558634D01*
X231883Y558925D01*
X231633Y559175D01*
X231258Y559300D01*
X230842D01*
X230592Y559384D01*
X230383Y559592D01*
X230300Y559884D01*
X230425Y560175D01*
X230717Y560384D01*
X231050Y560467D01*
X231383Y560384D01*
X231675Y560175D01*
X231800Y559884D01*
X231717Y559592D01*
X231508Y559384D01*
X231258Y559300D01*
X230842D01*
X230467Y559175D01*
X230217Y558925D01*
X230133Y558634D01*
X230217Y558342D01*
X230425Y558134D01*
X230758Y558009D01*
X231050Y557967D01*
G01X198300Y571000D02*
Y567000D01*
X205700D01*
G01X197200D02*
Y571000D01*
X189800D01*
G01X200900Y937500D02*
X200567Y937542D01*
X200275Y937708D01*
X200025Y937958D01*
X199858Y938250D01*
X199775Y938583D01*
Y938917D01*
X199858Y939250D01*
X200025Y939542D01*
X200275Y939792D01*
X200567Y939958D01*
X200900Y940000D01*
X201233Y939958D01*
X201525Y939792D01*
X201775Y939542D01*
X201942Y939250D01*
X202025Y938917D01*
Y938583D01*
X201942Y938250D01*
X201775Y937958D01*
X201525Y937708D01*
X201233Y937542D01*
X200900Y937500D01*
G01X201233Y938167D02*
X201733Y937500D01*
G01X203208Y938542D02*
X203500Y938833D01*
X203750Y939000D01*
X204083Y939083D01*
X204375Y939000D01*
X204583Y938833D01*
X204750Y938583D01*
X204792Y938292D01*
X204750Y938042D01*
X204583Y937792D01*
X204333Y937583D01*
X204042Y937500D01*
X203708Y937583D01*
X203417Y937833D01*
X203250Y938208D01*
X203208Y938625D01*
X203292Y939167D01*
X203417Y939458D01*
X203625Y939750D01*
X203917Y939958D01*
X204208Y940000D01*
X204500Y939917D01*
X204708Y939708D01*
G01X207600Y937500D02*
Y940000D01*
X206058Y938208D01*
X208142D01*
G01X211500Y941977D02*
Y955977D01*
G01X198500Y941977D02*
X211500D01*
G01X198500Y955977D02*
Y941977D01*
G01X211500Y955977D02*
X198500D01*
G01X223400Y937600D02*
X223067Y937642D01*
X222775Y937808D01*
X222525Y938058D01*
X222358Y938350D01*
X222275Y938683D01*
Y939017D01*
X222358Y939350D01*
X222525Y939642D01*
X222775Y939892D01*
X223067Y940058D01*
X223400Y940100D01*
X223733Y940058D01*
X224025Y939892D01*
X224275Y939642D01*
X224442Y939350D01*
X224525Y939017D01*
Y938683D01*
X224442Y938350D01*
X224275Y938058D01*
X224025Y937808D01*
X223733Y937642D01*
X223400Y937600D01*
G01X223733Y938267D02*
X224233Y937600D01*
G01X225708Y938642D02*
X226000Y938933D01*
X226250Y939100D01*
X226583Y939183D01*
X226875Y939100D01*
X227083Y938933D01*
X227250Y938683D01*
X227292Y938392D01*
X227250Y938142D01*
X227083Y937892D01*
X226833Y937683D01*
X226542Y937600D01*
X226208Y937683D01*
X225917Y937933D01*
X225750Y938308D01*
X225708Y938725D01*
X225792Y939267D01*
X225917Y939558D01*
X226125Y939850D01*
X226417Y940058D01*
X226708Y940100D01*
X227000Y940017D01*
X227208Y939808D01*
G01X228683Y937975D02*
X228933Y937767D01*
X229225Y937642D01*
X229600Y937600D01*
X229975Y937683D01*
X230267Y937850D01*
X230475Y938142D01*
X230517Y938475D01*
X230433Y938808D01*
X230225Y939017D01*
X229933Y939183D01*
X229642Y939225D01*
X229350Y939183D01*
X228975Y939017D01*
X229100Y940100D01*
X230225D01*
G01X226000Y941977D02*
Y955977D01*
G01X213000Y941977D02*
X226000D01*
G01X213000Y955977D02*
Y941977D01*
G01X226000Y955977D02*
X213000D01*
G01X200467Y975800D02*
Y978300D01*
X201508D01*
X201842Y978175D01*
X202050Y978008D01*
X202133Y977675D01*
X202050Y977342D01*
X201800Y977133D01*
X201508Y977008D01*
X200467D01*
G01X201508D02*
X202133Y975800D01*
G01X203692Y976092D02*
X203983Y975883D01*
X204317Y975800D01*
X204650Y975883D01*
X204942Y976133D01*
X205150Y976508D01*
X205233Y976883D01*
Y977342D01*
X205150Y977717D01*
X204942Y978050D01*
X204692Y978217D01*
X204400Y978300D01*
X204067Y978217D01*
X203817Y978050D01*
X203650Y977800D01*
X203567Y977467D01*
X203650Y977175D01*
X203858Y976883D01*
X204108Y976717D01*
X204400Y976675D01*
X204733Y976758D01*
X204983Y976967D01*
X205233Y977342D01*
G01X208000Y975800D02*
Y978300D01*
X206458Y976508D01*
X208542D01*
G01X209808Y976842D02*
X210100Y977133D01*
X210350Y977300D01*
X210683Y977383D01*
X210975Y977300D01*
X211183Y977133D01*
X211350Y976883D01*
X211392Y976592D01*
X211350Y976342D01*
X211183Y976092D01*
X210933Y975883D01*
X210642Y975800D01*
X210308Y975883D01*
X210017Y976133D01*
X209850Y976508D01*
X209808Y976925D01*
X209892Y977467D01*
X210017Y977758D01*
X210225Y978050D01*
X210517Y978258D01*
X210808Y978300D01*
X211100Y978217D01*
X211308Y978008D01*
G01X212783Y976300D02*
X213033Y976008D01*
X213367Y975842D01*
X213742Y975800D01*
X214075Y975842D01*
X214408Y976050D01*
X214617Y976300D01*
X214658Y976550D01*
X214575Y976842D01*
X214283Y977050D01*
X213992Y977133D01*
X213617D01*
G01X213992D02*
X214242Y977258D01*
X214450Y977467D01*
X214533Y977717D01*
X214450Y977967D01*
X214242Y978175D01*
X213867Y978300D01*
X213492Y978258D01*
X213117Y978092D01*
G01X197700Y976500D02*
Y980500D01*
X190300D01*
G01X214467Y957300D02*
Y959800D01*
X215508D01*
X215842Y959675D01*
X216050Y959508D01*
X216133Y959175D01*
X216050Y958842D01*
X215800Y958633D01*
X215508Y958508D01*
X214467D01*
G01X215508D02*
X216133Y957300D01*
G01X217692Y957592D02*
X217983Y957383D01*
X218317Y957300D01*
X218650Y957383D01*
X218942Y957633D01*
X219150Y958008D01*
X219233Y958383D01*
Y958842D01*
X219150Y959217D01*
X218942Y959550D01*
X218692Y959717D01*
X218400Y959800D01*
X218067Y959717D01*
X217817Y959550D01*
X217650Y959300D01*
X217567Y958967D01*
X217650Y958675D01*
X217858Y958383D01*
X218108Y958217D01*
X218400Y958175D01*
X218733Y958258D01*
X218983Y958467D01*
X219233Y958842D01*
G01X221500Y957300D02*
X221792Y957342D01*
X222125Y957467D01*
X222333Y957675D01*
X222417Y957967D01*
X222333Y958258D01*
X222083Y958508D01*
X221708Y958633D01*
X221292D01*
X221042Y958717D01*
X220833Y958925D01*
X220750Y959217D01*
X220875Y959508D01*
X221167Y959717D01*
X221500Y959800D01*
X221833Y959717D01*
X222125Y959508D01*
X222250Y959217D01*
X222167Y958925D01*
X221958Y958717D01*
X221708Y958633D01*
X221292D01*
X220917Y958508D01*
X220667Y958258D01*
X220583Y957967D01*
X220667Y957675D01*
X220875Y957467D01*
X221208Y957342D01*
X221500Y957300D01*
G01X223683Y957800D02*
X223933Y957508D01*
X224267Y957342D01*
X224642Y957300D01*
X224975Y957342D01*
X225308Y957550D01*
X225517Y957800D01*
X225558Y958050D01*
X225475Y958342D01*
X225183Y958550D01*
X224892Y958633D01*
X224517D01*
G01X224892D02*
X225142Y958758D01*
X225350Y958967D01*
X225433Y959217D01*
X225350Y959467D01*
X225142Y959675D01*
X224767Y959800D01*
X224392Y959758D01*
X224017Y959592D01*
G01X227700Y959800D02*
X227367Y959717D01*
X227117Y959508D01*
X226950Y959258D01*
X226825Y958925D01*
X226783Y958550D01*
X226825Y958175D01*
X226950Y957842D01*
X227117Y957592D01*
X227367Y957383D01*
X227700Y957300D01*
X228033Y957383D01*
X228283Y957592D01*
X228450Y957842D01*
X228575Y958175D01*
X228617Y958550D01*
X228575Y958925D01*
X228450Y959258D01*
X228283Y959508D01*
X228033Y959717D01*
X227700Y959800D01*
G01X209300Y958977D02*
Y962977D01*
X201900D01*
G01X235167Y938075D02*
X235375Y938408D01*
X235500Y938783D01*
Y939117D01*
X235375Y939450D01*
X235167Y939700D01*
X234875Y939825D01*
X234583Y939742D01*
X234333Y939533D01*
X234167Y939158D01*
X234083Y938658D01*
X233917Y938367D01*
X233625Y938242D01*
X233333Y938325D01*
X233125Y938533D01*
X233000Y938825D01*
Y939117D01*
X233083Y939408D01*
X233292Y939658D01*
G01X235500Y941217D02*
X233000D01*
Y942258D01*
X233125Y942592D01*
X233292Y942800D01*
X233625Y942883D01*
X233958Y942800D01*
X234167Y942550D01*
X234292Y942258D01*
Y941217D01*
G01Y942258D02*
X235500Y942883D01*
G01Y945150D02*
X233000D01*
X233500Y944650D01*
G01X235500D02*
Y945650D01*
G01Y948250D02*
X233000D01*
X233500Y947750D01*
G01X235500D02*
Y948750D01*
G01X235000Y950433D02*
X235292Y950683D01*
X235458Y951017D01*
X235500Y951392D01*
X235458Y951725D01*
X235250Y952058D01*
X235000Y952267D01*
X234750Y952308D01*
X234458Y952225D01*
X234250Y951933D01*
X234167Y951642D01*
Y951267D01*
G01Y951642D02*
X234042Y951892D01*
X233833Y952100D01*
X233583Y952183D01*
X233333Y952100D01*
X233125Y951892D01*
X233000Y951517D01*
X233042Y951142D01*
X233208Y950767D01*
G01X235125Y953533D02*
X235333Y953783D01*
X235458Y954075D01*
X235500Y954450D01*
X235417Y954825D01*
X235250Y955117D01*
X234958Y955325D01*
X234625Y955367D01*
X234292Y955283D01*
X234083Y955075D01*
X233917Y954783D01*
X233875Y954492D01*
X233917Y954200D01*
X234083Y953825D01*
X233000Y953950D01*
Y955075D01*
G01X227500Y947777D02*
X231500D01*
Y955177D01*
G01X201567Y968300D02*
Y970800D01*
X202608D01*
X202942Y970675D01*
X203150Y970508D01*
X203233Y970175D01*
X203150Y969842D01*
X202900Y969633D01*
X202608Y969508D01*
X201567D01*
G01X202608D02*
X203233Y968300D01*
G01X204792Y968592D02*
X205083Y968383D01*
X205417Y968300D01*
X205750Y968383D01*
X206042Y968633D01*
X206250Y969008D01*
X206333Y969383D01*
Y969842D01*
X206250Y970217D01*
X206042Y970550D01*
X205792Y970717D01*
X205500Y970800D01*
X205167Y970717D01*
X204917Y970550D01*
X204750Y970300D01*
X204667Y969967D01*
X204750Y969675D01*
X204958Y969383D01*
X205208Y969217D01*
X205500Y969175D01*
X205833Y969258D01*
X206083Y969467D01*
X206333Y969842D01*
G01X208600Y968300D02*
X208892Y968342D01*
X209225Y968467D01*
X209433Y968675D01*
X209517Y968967D01*
X209433Y969258D01*
X209183Y969508D01*
X208808Y969633D01*
X208392D01*
X208142Y969717D01*
X207933Y969925D01*
X207850Y970217D01*
X207975Y970508D01*
X208267Y970717D01*
X208600Y970800D01*
X208933Y970717D01*
X209225Y970508D01*
X209350Y970217D01*
X209267Y969925D01*
X209058Y969717D01*
X208808Y969633D01*
X208392D01*
X208017Y969508D01*
X207767Y969258D01*
X207683Y968967D01*
X207767Y968675D01*
X207975Y968467D01*
X208308Y968342D01*
X208600Y968300D01*
G01X210992Y968592D02*
X211283Y968383D01*
X211617Y968300D01*
X211950Y968383D01*
X212242Y968633D01*
X212450Y969008D01*
X212533Y969383D01*
Y969842D01*
X212450Y970217D01*
X212242Y970550D01*
X211992Y970717D01*
X211700Y970800D01*
X211367Y970717D01*
X211117Y970550D01*
X210950Y970300D01*
X210867Y969967D01*
X210950Y969675D01*
X211158Y969383D01*
X211408Y969217D01*
X211700Y969175D01*
X212033Y969258D01*
X212283Y969467D01*
X212533Y969842D01*
G01X214092Y968592D02*
X214383Y968383D01*
X214717Y968300D01*
X215050Y968383D01*
X215342Y968633D01*
X215550Y969008D01*
X215633Y969383D01*
Y969842D01*
X215550Y970217D01*
X215342Y970550D01*
X215092Y970717D01*
X214800Y970800D01*
X214467Y970717D01*
X214217Y970550D01*
X214050Y970300D01*
X213967Y969967D01*
X214050Y969675D01*
X214258Y969383D01*
X214508Y969217D01*
X214800Y969175D01*
X215133Y969258D01*
X215383Y969467D01*
X215633Y969842D01*
G01X197700Y967500D02*
Y971500D01*
X190300D01*
G01X214467Y961300D02*
Y963800D01*
X215508D01*
X215842Y963675D01*
X216050Y963508D01*
X216133Y963175D01*
X216050Y962842D01*
X215800Y962633D01*
X215508Y962508D01*
X214467D01*
G01X215508D02*
X216133Y961300D01*
G01X217692Y961592D02*
X217983Y961383D01*
X218317Y961300D01*
X218650Y961383D01*
X218942Y961633D01*
X219150Y962008D01*
X219233Y962383D01*
Y962842D01*
X219150Y963217D01*
X218942Y963550D01*
X218692Y963717D01*
X218400Y963800D01*
X218067Y963717D01*
X217817Y963550D01*
X217650Y963300D01*
X217567Y962967D01*
X217650Y962675D01*
X217858Y962383D01*
X218108Y962217D01*
X218400Y962175D01*
X218733Y962258D01*
X218983Y962467D01*
X219233Y962842D01*
G01X220792Y961592D02*
X221083Y961383D01*
X221417Y961300D01*
X221750Y961383D01*
X222042Y961633D01*
X222250Y962008D01*
X222333Y962383D01*
Y962842D01*
X222250Y963217D01*
X222042Y963550D01*
X221792Y963717D01*
X221500Y963800D01*
X221167Y963717D01*
X220917Y963550D01*
X220750Y963300D01*
X220667Y962967D01*
X220750Y962675D01*
X220958Y962383D01*
X221208Y962217D01*
X221500Y962175D01*
X221833Y962258D01*
X222083Y962467D01*
X222333Y962842D01*
G01X224600Y961300D02*
Y963800D01*
X224100Y963300D01*
G01Y961300D02*
X225100D01*
G01X226992Y961592D02*
X227283Y961383D01*
X227617Y961300D01*
X227950Y961383D01*
X228242Y961633D01*
X228450Y962008D01*
X228533Y962383D01*
Y962842D01*
X228450Y963217D01*
X228242Y963550D01*
X227992Y963717D01*
X227700Y963800D01*
X227367Y963717D01*
X227117Y963550D01*
X226950Y963300D01*
X226867Y962967D01*
X226950Y962675D01*
X227158Y962383D01*
X227408Y962217D01*
X227700Y962175D01*
X228033Y962258D01*
X228283Y962467D01*
X228533Y962842D01*
G01X209300Y963477D02*
Y967477D01*
X201900D01*
G01X201567Y972300D02*
Y974800D01*
X202608D01*
X202942Y974675D01*
X203150Y974508D01*
X203233Y974175D01*
X203150Y973842D01*
X202900Y973633D01*
X202608Y973508D01*
X201567D01*
G01X202608D02*
X203233Y972300D01*
G01X204792Y972592D02*
X205083Y972383D01*
X205417Y972300D01*
X205750Y972383D01*
X206042Y972633D01*
X206250Y973008D01*
X206333Y973383D01*
Y973842D01*
X206250Y974217D01*
X206042Y974550D01*
X205792Y974717D01*
X205500Y974800D01*
X205167Y974717D01*
X204917Y974550D01*
X204750Y974300D01*
X204667Y973967D01*
X204750Y973675D01*
X204958Y973383D01*
X205208Y973217D01*
X205500Y973175D01*
X205833Y973258D01*
X206083Y973467D01*
X206333Y973842D01*
G01X209100Y972300D02*
Y974800D01*
X207558Y973008D01*
X209642D01*
G01X210908Y973342D02*
X211200Y973633D01*
X211450Y973800D01*
X211783Y973883D01*
X212075Y973800D01*
X212283Y973633D01*
X212450Y973383D01*
X212492Y973092D01*
X212450Y972842D01*
X212283Y972592D01*
X212033Y972383D01*
X211742Y972300D01*
X211408Y972383D01*
X211117Y972633D01*
X210950Y973008D01*
X210908Y973425D01*
X210992Y973967D01*
X211117Y974258D01*
X211325Y974550D01*
X211617Y974758D01*
X211908Y974800D01*
X212200Y974717D01*
X212408Y974508D01*
G01X215300Y972300D02*
Y974800D01*
X213758Y973008D01*
X215842D01*
G01X197700Y972000D02*
Y976000D01*
X190300D01*
G01X185433Y939500D02*
Y937708D01*
X185600Y937333D01*
X185933Y937083D01*
X186350Y937000D01*
X186767Y937083D01*
X187100Y937333D01*
X187267Y937708D01*
Y939500D01*
G01X188658Y939083D02*
X188908Y939333D01*
X189200Y939458D01*
X189533Y939500D01*
X189950Y939417D01*
X190242Y939208D01*
X190325Y938958D01*
X190283Y938708D01*
X190117Y938500D01*
X189283Y938083D01*
X188908Y937792D01*
X188658Y937375D01*
X188575Y937000D01*
X190325D01*
G01X192550Y939500D02*
X192217Y939417D01*
X191967Y939208D01*
X191800Y938958D01*
X191675Y938625D01*
X191633Y938250D01*
X191675Y937875D01*
X191800Y937542D01*
X191967Y937292D01*
X192217Y937083D01*
X192550Y937000D01*
X192883Y937083D01*
X193133Y937292D01*
X193300Y937542D01*
X193425Y937875D01*
X193467Y938250D01*
X193425Y938625D01*
X193300Y938958D01*
X193133Y939208D01*
X192883Y939417D01*
X192550Y939500D01*
G01X196150Y937000D02*
Y939500D01*
X194608Y937708D01*
X196692D01*
G01X195000Y959700D02*
Y946300D01*
G01X185000Y959700D02*
X195000D01*
G01X185000Y946300D02*
Y959700D01*
G01X195000Y946300D02*
X185000D01*
G01X203500Y1354400D02*
X203458Y1354067D01*
X203292Y1353775D01*
X203042Y1353525D01*
X202750Y1353358D01*
X202417Y1353275D01*
X202083D01*
X201750Y1353358D01*
X201458Y1353525D01*
X201208Y1353775D01*
X201042Y1354067D01*
X201000Y1354400D01*
X201042Y1354733D01*
X201208Y1355025D01*
X201458Y1355275D01*
X201750Y1355442D01*
X202083Y1355525D01*
X202417D01*
X202750Y1355442D01*
X203042Y1355275D01*
X203292Y1355025D01*
X203458Y1354733D01*
X203500Y1354400D01*
G01X202833Y1354733D02*
X203500Y1355233D01*
G01X203125Y1356583D02*
X203333Y1356833D01*
X203458Y1357125D01*
X203500Y1357500D01*
X203417Y1357875D01*
X203250Y1358167D01*
X202958Y1358375D01*
X202625Y1358417D01*
X202292Y1358333D01*
X202083Y1358125D01*
X201917Y1357833D01*
X201875Y1357542D01*
X201917Y1357250D01*
X202083Y1356875D01*
X201000Y1357000D01*
Y1358125D01*
G01X203500Y1360600D02*
X203458Y1360892D01*
X203333Y1361225D01*
X203125Y1361433D01*
X202833Y1361517D01*
X202542Y1361433D01*
X202292Y1361183D01*
X202167Y1360808D01*
Y1360392D01*
X202083Y1360142D01*
X201875Y1359933D01*
X201583Y1359850D01*
X201292Y1359975D01*
X201083Y1360267D01*
X201000Y1360600D01*
X201083Y1360933D01*
X201292Y1361225D01*
X201583Y1361350D01*
X201875Y1361267D01*
X202083Y1361058D01*
X202167Y1360808D01*
Y1360392D01*
X202292Y1360017D01*
X202542Y1359767D01*
X202833Y1359683D01*
X203125Y1359767D01*
X203333Y1359975D01*
X203458Y1360308D01*
X203500Y1360600D01*
G01X198654Y1350488D02*
Y1364488D01*
G01X185654Y1350488D02*
X198654D01*
G01X185654Y1364488D02*
Y1350488D01*
G01X203467Y1344500D02*
Y1347000D01*
X204508D01*
X204842Y1346875D01*
X205050Y1346708D01*
X205133Y1346375D01*
X205050Y1346042D01*
X204800Y1345833D01*
X204508Y1345708D01*
X203467D01*
G01X204508D02*
X205133Y1344500D01*
G01X206692Y1344792D02*
X206983Y1344583D01*
X207317Y1344500D01*
X207650Y1344583D01*
X207942Y1344833D01*
X208150Y1345208D01*
X208233Y1345583D01*
Y1346042D01*
X208150Y1346417D01*
X207942Y1346750D01*
X207692Y1346917D01*
X207400Y1347000D01*
X207067Y1346917D01*
X206817Y1346750D01*
X206650Y1346500D01*
X206567Y1346167D01*
X206650Y1345875D01*
X206858Y1345583D01*
X207108Y1345417D01*
X207400Y1345375D01*
X207733Y1345458D01*
X207983Y1345667D01*
X208233Y1346042D01*
G01X210500Y1344500D02*
X210792Y1344542D01*
X211125Y1344667D01*
X211333Y1344875D01*
X211417Y1345167D01*
X211333Y1345458D01*
X211083Y1345708D01*
X210708Y1345833D01*
X210292D01*
X210042Y1345917D01*
X209833Y1346125D01*
X209750Y1346417D01*
X209875Y1346708D01*
X210167Y1346917D01*
X210500Y1347000D01*
X210833Y1346917D01*
X211125Y1346708D01*
X211250Y1346417D01*
X211167Y1346125D01*
X210958Y1345917D01*
X210708Y1345833D01*
X210292D01*
X209917Y1345708D01*
X209667Y1345458D01*
X209583Y1345167D01*
X209667Y1344875D01*
X209875Y1344667D01*
X210208Y1344542D01*
X210500Y1344500D01*
G01X212808Y1346583D02*
X213058Y1346833D01*
X213350Y1346958D01*
X213683Y1347000D01*
X214100Y1346917D01*
X214392Y1346708D01*
X214475Y1346458D01*
X214433Y1346208D01*
X214267Y1346000D01*
X213433Y1345583D01*
X213058Y1345292D01*
X212808Y1344875D01*
X212725Y1344500D01*
X214475D01*
G01X216700D02*
Y1347000D01*
X216200Y1346500D01*
G01Y1344500D02*
X217200D01*
G01X189454Y1348488D02*
Y1344488D01*
X196854D01*
G01X198654Y1364488D02*
X185654D01*
G01X195767Y1379200D02*
Y1381700D01*
X196808D01*
X197142Y1381575D01*
X197350Y1381408D01*
X197433Y1381075D01*
X197350Y1380742D01*
X197100Y1380533D01*
X196808Y1380408D01*
X195767D01*
G01X196808D02*
X197433Y1379200D01*
G01X198992Y1379492D02*
X199283Y1379283D01*
X199617Y1379200D01*
X199950Y1379283D01*
X200242Y1379533D01*
X200450Y1379908D01*
X200533Y1380283D01*
Y1380742D01*
X200450Y1381117D01*
X200242Y1381450D01*
X199992Y1381617D01*
X199700Y1381700D01*
X199367Y1381617D01*
X199117Y1381450D01*
X198950Y1381200D01*
X198867Y1380867D01*
X198950Y1380575D01*
X199158Y1380283D01*
X199408Y1380117D01*
X199700Y1380075D01*
X200033Y1380158D01*
X200283Y1380367D01*
X200533Y1380742D01*
G01X203300Y1379200D02*
Y1381700D01*
X201758Y1379908D01*
X203842D01*
G01X205817Y1379200D02*
X205900Y1379742D01*
X206025Y1380200D01*
X206192Y1380617D01*
X206400Y1381075D01*
X206733Y1381700D01*
X205067D01*
G01X209000D02*
X208667Y1381617D01*
X208417Y1381408D01*
X208250Y1381158D01*
X208125Y1380825D01*
X208083Y1380450D01*
X208125Y1380075D01*
X208250Y1379742D01*
X208417Y1379492D01*
X208667Y1379283D01*
X209000Y1379200D01*
X209333Y1379283D01*
X209583Y1379492D01*
X209750Y1379742D01*
X209875Y1380075D01*
X209917Y1380450D01*
X209875Y1380825D01*
X209750Y1381158D01*
X209583Y1381408D01*
X209333Y1381617D01*
X209000Y1381700D01*
G01X192200Y1380000D02*
Y1384000D01*
X184800D01*
G01X254275Y1405724D02*
X254608Y1405516D01*
X254983Y1405391D01*
X255317D01*
X255650Y1405516D01*
X255900Y1405724D01*
X256025Y1406016D01*
X255942Y1406308D01*
X255733Y1406558D01*
X255358Y1406724D01*
X254858Y1406808D01*
X254567Y1406974D01*
X254442Y1407266D01*
X254525Y1407558D01*
X254733Y1407766D01*
X255025Y1407891D01*
X255317D01*
X255608Y1407808D01*
X255858Y1407599D01*
G01X257417Y1405391D02*
Y1407891D01*
X258458D01*
X258792Y1407766D01*
X259000Y1407599D01*
X259083Y1407266D01*
X259000Y1406933D01*
X258750Y1406724D01*
X258458Y1406599D01*
X257417D01*
G01X258458D02*
X259083Y1405391D01*
G01X261350D02*
Y1407891D01*
X260850Y1407391D01*
G01Y1405391D02*
X261850D01*
G01X264450Y1407891D02*
X264117Y1407808D01*
X263867Y1407599D01*
X263700Y1407349D01*
X263575Y1407016D01*
X263533Y1406641D01*
X263575Y1406266D01*
X263700Y1405933D01*
X263867Y1405683D01*
X264117Y1405474D01*
X264450Y1405391D01*
X264783Y1405474D01*
X265033Y1405683D01*
X265200Y1405933D01*
X265325Y1406266D01*
X265367Y1406641D01*
X265325Y1407016D01*
X265200Y1407349D01*
X265033Y1407599D01*
X264783Y1407808D01*
X264450Y1407891D01*
G01X266633Y1405766D02*
X266883Y1405558D01*
X267175Y1405433D01*
X267550Y1405391D01*
X267925Y1405474D01*
X268217Y1405641D01*
X268425Y1405933D01*
X268467Y1406266D01*
X268383Y1406599D01*
X268175Y1406808D01*
X267883Y1406974D01*
X267592Y1407016D01*
X267300Y1406974D01*
X266925Y1406808D01*
X267050Y1407891D01*
X268175D01*
G01X270650Y1405391D02*
Y1407891D01*
X270150Y1407391D01*
G01Y1405391D02*
X271150D01*
G01X253925Y1416333D02*
X254258Y1416125D01*
X254633Y1416000D01*
X254967D01*
X255300Y1416125D01*
X255550Y1416333D01*
X255675Y1416625D01*
X255592Y1416917D01*
X255383Y1417167D01*
X255008Y1417333D01*
X254508Y1417417D01*
X254217Y1417583D01*
X254092Y1417875D01*
X254175Y1418167D01*
X254383Y1418375D01*
X254675Y1418500D01*
X254967D01*
X255258Y1418417D01*
X255508Y1418208D01*
G01X257067Y1416000D02*
Y1418500D01*
X258108D01*
X258442Y1418375D01*
X258650Y1418208D01*
X258733Y1417875D01*
X258650Y1417542D01*
X258400Y1417333D01*
X258108Y1417208D01*
X257067D01*
G01X258108D02*
X258733Y1416000D01*
G01X260292Y1416292D02*
X260583Y1416083D01*
X260917Y1416000D01*
X261250Y1416083D01*
X261542Y1416333D01*
X261750Y1416708D01*
X261833Y1417083D01*
Y1417542D01*
X261750Y1417917D01*
X261542Y1418250D01*
X261292Y1418417D01*
X261000Y1418500D01*
X260667Y1418417D01*
X260417Y1418250D01*
X260250Y1418000D01*
X260167Y1417667D01*
X260250Y1417375D01*
X260458Y1417083D01*
X260708Y1416917D01*
X261000Y1416875D01*
X261333Y1416958D01*
X261583Y1417167D01*
X261833Y1417542D01*
G01X264017Y1416000D02*
X264100Y1416542D01*
X264225Y1417000D01*
X264392Y1417417D01*
X264600Y1417875D01*
X264933Y1418500D01*
X263267D01*
G01X267200Y1416000D02*
X267492Y1416042D01*
X267825Y1416167D01*
X268033Y1416375D01*
X268117Y1416667D01*
X268033Y1416958D01*
X267783Y1417208D01*
X267408Y1417333D01*
X266992D01*
X266742Y1417417D01*
X266533Y1417625D01*
X266450Y1417917D01*
X266575Y1418208D01*
X266867Y1418417D01*
X267200Y1418500D01*
X267533Y1418417D01*
X267825Y1418208D01*
X267950Y1417917D01*
X267867Y1417625D01*
X267658Y1417417D01*
X267408Y1417333D01*
X266992D01*
X266617Y1417208D01*
X266367Y1416958D01*
X266283Y1416667D01*
X266367Y1416375D01*
X266575Y1416167D01*
X266908Y1416042D01*
X267200Y1416000D01*
G01X255825Y1409724D02*
X256158Y1409516D01*
X256533Y1409391D01*
X256867D01*
X257200Y1409516D01*
X257450Y1409724D01*
X257575Y1410016D01*
X257492Y1410308D01*
X257283Y1410558D01*
X256908Y1410724D01*
X256408Y1410808D01*
X256117Y1410974D01*
X255992Y1411266D01*
X256075Y1411558D01*
X256283Y1411766D01*
X256575Y1411891D01*
X256867D01*
X257158Y1411808D01*
X257408Y1411599D01*
G01X258967Y1409391D02*
Y1411891D01*
X260008D01*
X260342Y1411766D01*
X260550Y1411599D01*
X260633Y1411266D01*
X260550Y1410933D01*
X260300Y1410724D01*
X260008Y1410599D01*
X258967D01*
G01X260008D02*
X260633Y1409391D01*
G01X262192Y1409683D02*
X262483Y1409474D01*
X262817Y1409391D01*
X263150Y1409474D01*
X263442Y1409724D01*
X263650Y1410099D01*
X263733Y1410474D01*
Y1410933D01*
X263650Y1411308D01*
X263442Y1411641D01*
X263192Y1411808D01*
X262900Y1411891D01*
X262567Y1411808D01*
X262317Y1411641D01*
X262150Y1411391D01*
X262067Y1411058D01*
X262150Y1410766D01*
X262358Y1410474D01*
X262608Y1410308D01*
X262900Y1410266D01*
X263233Y1410349D01*
X263483Y1410558D01*
X263733Y1410933D01*
G01X266000Y1409391D02*
X266292Y1409433D01*
X266625Y1409558D01*
X266833Y1409766D01*
X266917Y1410058D01*
X266833Y1410349D01*
X266583Y1410599D01*
X266208Y1410724D01*
X265792D01*
X265542Y1410808D01*
X265333Y1411016D01*
X265250Y1411308D01*
X265375Y1411599D01*
X265667Y1411808D01*
X266000Y1411891D01*
X266333Y1411808D01*
X266625Y1411599D01*
X266750Y1411308D01*
X266667Y1411016D01*
X266458Y1410808D01*
X266208Y1410724D01*
X265792D01*
X265417Y1410599D01*
X265167Y1410349D01*
X265083Y1410058D01*
X265167Y1409766D01*
X265375Y1409558D01*
X265708Y1409433D01*
X266000Y1409391D01*
G01X269100Y1411891D02*
X268767Y1411808D01*
X268517Y1411599D01*
X268350Y1411349D01*
X268225Y1411016D01*
X268183Y1410641D01*
X268225Y1410266D01*
X268350Y1409933D01*
X268517Y1409683D01*
X268767Y1409474D01*
X269100Y1409391D01*
X269433Y1409474D01*
X269683Y1409683D01*
X269850Y1409933D01*
X269975Y1410266D01*
X270017Y1410641D01*
X269975Y1411016D01*
X269850Y1411349D01*
X269683Y1411599D01*
X269433Y1411808D01*
X269100Y1411891D01*
G01X254425Y1422833D02*
X254758Y1422625D01*
X255133Y1422500D01*
X255467D01*
X255800Y1422625D01*
X256050Y1422833D01*
X256175Y1423125D01*
X256092Y1423417D01*
X255883Y1423667D01*
X255508Y1423833D01*
X255008Y1423917D01*
X254717Y1424083D01*
X254592Y1424375D01*
X254675Y1424667D01*
X254883Y1424875D01*
X255175Y1425000D01*
X255467D01*
X255758Y1424917D01*
X256008Y1424708D01*
G01X257567Y1422500D02*
Y1425000D01*
X258608D01*
X258942Y1424875D01*
X259150Y1424708D01*
X259233Y1424375D01*
X259150Y1424042D01*
X258900Y1423833D01*
X258608Y1423708D01*
X257567D01*
G01X258608D02*
X259233Y1422500D01*
G01X260792Y1422792D02*
X261083Y1422583D01*
X261417Y1422500D01*
X261750Y1422583D01*
X262042Y1422833D01*
X262250Y1423208D01*
X262333Y1423583D01*
Y1424042D01*
X262250Y1424417D01*
X262042Y1424750D01*
X261792Y1424917D01*
X261500Y1425000D01*
X261167Y1424917D01*
X260917Y1424750D01*
X260750Y1424500D01*
X260667Y1424167D01*
X260750Y1423875D01*
X260958Y1423583D01*
X261208Y1423417D01*
X261500Y1423375D01*
X261833Y1423458D01*
X262083Y1423667D01*
X262333Y1424042D01*
G01X264600Y1422500D02*
X264892Y1422542D01*
X265225Y1422667D01*
X265433Y1422875D01*
X265517Y1423167D01*
X265433Y1423458D01*
X265183Y1423708D01*
X264808Y1423833D01*
X264392D01*
X264142Y1423917D01*
X263933Y1424125D01*
X263850Y1424417D01*
X263975Y1424708D01*
X264267Y1424917D01*
X264600Y1425000D01*
X264933Y1424917D01*
X265225Y1424708D01*
X265350Y1424417D01*
X265267Y1424125D01*
X265058Y1423917D01*
X264808Y1423833D01*
X264392D01*
X264017Y1423708D01*
X263767Y1423458D01*
X263683Y1423167D01*
X263767Y1422875D01*
X263975Y1422667D01*
X264308Y1422542D01*
X264600Y1422500D01*
G01X267700D02*
Y1425000D01*
X267200Y1424500D01*
G01Y1422500D02*
X268200D01*
G01X195767Y1371200D02*
Y1373700D01*
X196808D01*
X197142Y1373575D01*
X197350Y1373408D01*
X197433Y1373075D01*
X197350Y1372742D01*
X197100Y1372533D01*
X196808Y1372408D01*
X195767D01*
G01X196808D02*
X197433Y1371200D01*
G01X198992Y1371492D02*
X199283Y1371283D01*
X199617Y1371200D01*
X199950Y1371283D01*
X200242Y1371533D01*
X200450Y1371908D01*
X200533Y1372283D01*
Y1372742D01*
X200450Y1373117D01*
X200242Y1373450D01*
X199992Y1373617D01*
X199700Y1373700D01*
X199367Y1373617D01*
X199117Y1373450D01*
X198950Y1373200D01*
X198867Y1372867D01*
X198950Y1372575D01*
X199158Y1372283D01*
X199408Y1372117D01*
X199700Y1372075D01*
X200033Y1372158D01*
X200283Y1372367D01*
X200533Y1372742D01*
G01X202800Y1371200D02*
X203092Y1371242D01*
X203425Y1371367D01*
X203633Y1371575D01*
X203717Y1371867D01*
X203633Y1372158D01*
X203383Y1372408D01*
X203008Y1372533D01*
X202592D01*
X202342Y1372617D01*
X202133Y1372825D01*
X202050Y1373117D01*
X202175Y1373408D01*
X202467Y1373617D01*
X202800Y1373700D01*
X203133Y1373617D01*
X203425Y1373408D01*
X203550Y1373117D01*
X203467Y1372825D01*
X203258Y1372617D01*
X203008Y1372533D01*
X202592D01*
X202217Y1372408D01*
X201967Y1372158D01*
X201883Y1371867D01*
X201967Y1371575D01*
X202175Y1371367D01*
X202508Y1371242D01*
X202800Y1371200D01*
G01X205192Y1371492D02*
X205483Y1371283D01*
X205817Y1371200D01*
X206150Y1371283D01*
X206442Y1371533D01*
X206650Y1371908D01*
X206733Y1372283D01*
Y1372742D01*
X206650Y1373117D01*
X206442Y1373450D01*
X206192Y1373617D01*
X205900Y1373700D01*
X205567Y1373617D01*
X205317Y1373450D01*
X205150Y1373200D01*
X205067Y1372867D01*
X205150Y1372575D01*
X205358Y1372283D01*
X205608Y1372117D01*
X205900Y1372075D01*
X206233Y1372158D01*
X206483Y1372367D01*
X206733Y1372742D01*
G01X209000Y1371200D02*
X209292Y1371242D01*
X209625Y1371367D01*
X209833Y1371575D01*
X209917Y1371867D01*
X209833Y1372158D01*
X209583Y1372408D01*
X209208Y1372533D01*
X208792D01*
X208542Y1372617D01*
X208333Y1372825D01*
X208250Y1373117D01*
X208375Y1373408D01*
X208667Y1373617D01*
X209000Y1373700D01*
X209333Y1373617D01*
X209625Y1373408D01*
X209750Y1373117D01*
X209667Y1372825D01*
X209458Y1372617D01*
X209208Y1372533D01*
X208792D01*
X208417Y1372408D01*
X208167Y1372158D01*
X208083Y1371867D01*
X208167Y1371575D01*
X208375Y1371367D01*
X208708Y1371242D01*
X209000Y1371200D01*
G01X192200Y1371000D02*
Y1375000D01*
X184800D01*
G01X253875Y1401833D02*
X254208Y1401625D01*
X254583Y1401500D01*
X254917D01*
X255250Y1401625D01*
X255500Y1401833D01*
X255625Y1402125D01*
X255542Y1402417D01*
X255333Y1402667D01*
X254958Y1402833D01*
X254458Y1402917D01*
X254167Y1403083D01*
X254042Y1403375D01*
X254125Y1403667D01*
X254333Y1403875D01*
X254625Y1404000D01*
X254917D01*
X255208Y1403917D01*
X255458Y1403708D01*
G01X257017Y1401500D02*
Y1404000D01*
X258058D01*
X258392Y1403875D01*
X258600Y1403708D01*
X258683Y1403375D01*
X258600Y1403042D01*
X258350Y1402833D01*
X258058Y1402708D01*
X257017D01*
G01X258058D02*
X258683Y1401500D01*
G01X260950D02*
Y1404000D01*
X260450Y1403500D01*
G01Y1401500D02*
X261450D01*
G01X264050D02*
Y1404000D01*
X263550Y1403500D01*
G01Y1401500D02*
X264550D01*
G01X266233Y1401875D02*
X266483Y1401667D01*
X266775Y1401542D01*
X267150Y1401500D01*
X267525Y1401583D01*
X267817Y1401750D01*
X268025Y1402042D01*
X268067Y1402375D01*
X267983Y1402708D01*
X267775Y1402917D01*
X267483Y1403083D01*
X267192Y1403125D01*
X266900Y1403083D01*
X266525Y1402917D01*
X266650Y1404000D01*
X267775D01*
G01X269333Y1401875D02*
X269583Y1401667D01*
X269875Y1401542D01*
X270250Y1401500D01*
X270625Y1401583D01*
X270917Y1401750D01*
X271125Y1402042D01*
X271167Y1402375D01*
X271083Y1402708D01*
X270875Y1402917D01*
X270583Y1403083D01*
X270292Y1403125D01*
X270000Y1403083D01*
X269625Y1402917D01*
X269750Y1404000D01*
X270875D01*
G01X195767Y1375200D02*
Y1377700D01*
X196808D01*
X197142Y1377575D01*
X197350Y1377408D01*
X197433Y1377075D01*
X197350Y1376742D01*
X197100Y1376533D01*
X196808Y1376408D01*
X195767D01*
G01X196808D02*
X197433Y1375200D01*
G01X198992Y1375492D02*
X199283Y1375283D01*
X199617Y1375200D01*
X199950Y1375283D01*
X200242Y1375533D01*
X200450Y1375908D01*
X200533Y1376283D01*
Y1376742D01*
X200450Y1377117D01*
X200242Y1377450D01*
X199992Y1377617D01*
X199700Y1377700D01*
X199367Y1377617D01*
X199117Y1377450D01*
X198950Y1377200D01*
X198867Y1376867D01*
X198950Y1376575D01*
X199158Y1376283D01*
X199408Y1376117D01*
X199700Y1376075D01*
X200033Y1376158D01*
X200283Y1376367D01*
X200533Y1376742D01*
G01X203300Y1375200D02*
Y1377700D01*
X201758Y1375908D01*
X203842D01*
G01X205817Y1375200D02*
X205900Y1375742D01*
X206025Y1376200D01*
X206192Y1376617D01*
X206400Y1377075D01*
X206733Y1377700D01*
X205067D01*
G01X209000Y1375200D02*
Y1377700D01*
X208500Y1377200D01*
G01Y1375200D02*
X209500D01*
G01X192200Y1375500D02*
Y1379500D01*
X184800D01*
G01X252407Y1721420D02*
Y1723920D01*
X253448D01*
X253782Y1723795D01*
X253990Y1723628D01*
X254073Y1723295D01*
X253990Y1722962D01*
X253740Y1722753D01*
X253448Y1722628D01*
X252407D01*
G01X253448D02*
X254073Y1721420D01*
G01X255423Y1721920D02*
X255673Y1721628D01*
X256007Y1721462D01*
X256382Y1721420D01*
X256715Y1721462D01*
X257048Y1721670D01*
X257257Y1721920D01*
X257298Y1722170D01*
X257215Y1722462D01*
X256923Y1722670D01*
X256632Y1722753D01*
X256257D01*
G01X256632D02*
X256882Y1722878D01*
X257090Y1723087D01*
X257173Y1723337D01*
X257090Y1723587D01*
X256882Y1723795D01*
X256507Y1723920D01*
X256132Y1723878D01*
X255757Y1723712D01*
G01X258648Y1722462D02*
X258940Y1722753D01*
X259190Y1722920D01*
X259523Y1723003D01*
X259815Y1722920D01*
X260023Y1722753D01*
X260190Y1722503D01*
X260232Y1722212D01*
X260190Y1721962D01*
X260023Y1721712D01*
X259773Y1721503D01*
X259482Y1721420D01*
X259148Y1721503D01*
X258857Y1721753D01*
X258690Y1722128D01*
X258648Y1722545D01*
X258732Y1723087D01*
X258857Y1723378D01*
X259065Y1723670D01*
X259357Y1723878D01*
X259648Y1723920D01*
X259940Y1723837D01*
X260148Y1723628D01*
G01X262540Y1721420D02*
X262832Y1721462D01*
X263165Y1721587D01*
X263373Y1721795D01*
X263457Y1722087D01*
X263373Y1722378D01*
X263123Y1722628D01*
X262748Y1722753D01*
X262332D01*
X262082Y1722837D01*
X261873Y1723045D01*
X261790Y1723337D01*
X261915Y1723628D01*
X262207Y1723837D01*
X262540Y1723920D01*
X262873Y1723837D01*
X263165Y1723628D01*
X263290Y1723337D01*
X263207Y1723045D01*
X262998Y1722837D01*
X262748Y1722753D01*
X262332D01*
X261957Y1722628D01*
X261707Y1722378D01*
X261623Y1722087D01*
X261707Y1721795D01*
X261915Y1721587D01*
X262248Y1721462D01*
X262540Y1721420D01*
G01X188208Y1742217D02*
X188083Y1741967D01*
X188000Y1741675D01*
Y1741342D01*
X188125Y1740967D01*
X188333Y1740675D01*
X188583Y1740467D01*
X189000Y1740300D01*
X189375Y1740258D01*
X189750Y1740342D01*
X190000Y1740467D01*
X190250Y1740717D01*
X190417Y1741008D01*
X190500Y1741300D01*
Y1741592D01*
X190417Y1741883D01*
X190292Y1742133D01*
X190125Y1742342D01*
G01X190208Y1743692D02*
X190417Y1743983D01*
X190500Y1744317D01*
X190417Y1744650D01*
X190167Y1744942D01*
X189792Y1745150D01*
X189417Y1745233D01*
X188958D01*
X188583Y1745150D01*
X188250Y1744942D01*
X188083Y1744692D01*
X188000Y1744400D01*
X188083Y1744067D01*
X188250Y1743817D01*
X188500Y1743650D01*
X188833Y1743567D01*
X189125Y1743650D01*
X189417Y1743858D01*
X189583Y1744108D01*
X189625Y1744400D01*
X189542Y1744733D01*
X189333Y1744983D01*
X188958Y1745233D01*
G01X190125Y1746583D02*
X190333Y1746833D01*
X190458Y1747125D01*
X190500Y1747500D01*
X190417Y1747875D01*
X190250Y1748167D01*
X189958Y1748375D01*
X189625Y1748417D01*
X189292Y1748333D01*
X189083Y1748125D01*
X188917Y1747833D01*
X188875Y1747542D01*
X188917Y1747250D01*
X189083Y1746875D01*
X188000Y1747000D01*
Y1748125D01*
G01X188417Y1749808D02*
X188167Y1750058D01*
X188042Y1750350D01*
X188000Y1750683D01*
X188083Y1751100D01*
X188292Y1751392D01*
X188542Y1751475D01*
X188792Y1751433D01*
X189000Y1751267D01*
X189417Y1750433D01*
X189708Y1750058D01*
X190125Y1749808D01*
X190500Y1749725D01*
Y1751475D01*
G01X190000Y1752783D02*
X190292Y1753033D01*
X190458Y1753367D01*
X190500Y1753742D01*
X190458Y1754075D01*
X190250Y1754408D01*
X190000Y1754617D01*
X189750Y1754658D01*
X189458Y1754575D01*
X189250Y1754283D01*
X189167Y1753992D01*
Y1753617D01*
G01Y1753992D02*
X189042Y1754242D01*
X188833Y1754450D01*
X188583Y1754533D01*
X188333Y1754450D01*
X188125Y1754242D01*
X188000Y1753867D01*
X188042Y1753492D01*
X188208Y1753117D01*
G01X191346Y1757000D02*
Y1770000D01*
G01X218800Y1748000D02*
X218467Y1748042D01*
X218175Y1748208D01*
X217925Y1748458D01*
X217758Y1748750D01*
X217675Y1749083D01*
Y1749417D01*
X217758Y1749750D01*
X217925Y1750042D01*
X218175Y1750292D01*
X218467Y1750458D01*
X218800Y1750500D01*
X219133Y1750458D01*
X219425Y1750292D01*
X219675Y1750042D01*
X219842Y1749750D01*
X219925Y1749417D01*
Y1749083D01*
X219842Y1748750D01*
X219675Y1748458D01*
X219425Y1748208D01*
X219133Y1748042D01*
X218800Y1748000D01*
G01X219133Y1748667D02*
X219633Y1748000D01*
G01X220983Y1748375D02*
X221233Y1748167D01*
X221525Y1748042D01*
X221900Y1748000D01*
X222275Y1748083D01*
X222567Y1748250D01*
X222775Y1748542D01*
X222817Y1748875D01*
X222733Y1749208D01*
X222525Y1749417D01*
X222233Y1749583D01*
X221942Y1749625D01*
X221650Y1749583D01*
X221275Y1749417D01*
X221400Y1750500D01*
X222525D01*
G01X225500Y1748000D02*
Y1750500D01*
X223958Y1748708D01*
X226042D01*
G01X227500Y1753000D02*
Y1767000D01*
G01X214500Y1753000D02*
X227500D01*
G01X214500Y1767000D02*
Y1753000D01*
G01X227500Y1767000D02*
X214500D01*
G01X232400Y1747700D02*
X232067Y1747742D01*
X231775Y1747908D01*
X231525Y1748158D01*
X231358Y1748450D01*
X231275Y1748783D01*
Y1749117D01*
X231358Y1749450D01*
X231525Y1749742D01*
X231775Y1749992D01*
X232067Y1750158D01*
X232400Y1750200D01*
X232733Y1750158D01*
X233025Y1749992D01*
X233275Y1749742D01*
X233442Y1749450D01*
X233525Y1749117D01*
Y1748783D01*
X233442Y1748450D01*
X233275Y1748158D01*
X233025Y1747908D01*
X232733Y1747742D01*
X232400Y1747700D01*
G01X232733Y1748367D02*
X233233Y1747700D01*
G01X234583Y1748075D02*
X234833Y1747867D01*
X235125Y1747742D01*
X235500Y1747700D01*
X235875Y1747783D01*
X236167Y1747950D01*
X236375Y1748242D01*
X236417Y1748575D01*
X236333Y1748908D01*
X236125Y1749117D01*
X235833Y1749283D01*
X235542Y1749325D01*
X235250Y1749283D01*
X234875Y1749117D01*
X235000Y1750200D01*
X236125D01*
G01X237683Y1748075D02*
X237933Y1747867D01*
X238225Y1747742D01*
X238600Y1747700D01*
X238975Y1747783D01*
X239267Y1747950D01*
X239475Y1748242D01*
X239517Y1748575D01*
X239433Y1748908D01*
X239225Y1749117D01*
X238933Y1749283D01*
X238642Y1749325D01*
X238350Y1749283D01*
X237975Y1749117D01*
X238100Y1750200D01*
X239225D01*
G01X242000Y1753000D02*
Y1767000D01*
G01X229000Y1753000D02*
X242000D01*
G01X229000Y1767000D02*
Y1753000D01*
G01X242000Y1767000D02*
X229000D01*
G01X199767Y1791300D02*
Y1793800D01*
X200808D01*
X201142Y1793675D01*
X201350Y1793508D01*
X201433Y1793175D01*
X201350Y1792842D01*
X201100Y1792633D01*
X200808Y1792508D01*
X199767D01*
G01X200808D02*
X201433Y1791300D01*
G01X202992Y1791592D02*
X203283Y1791383D01*
X203617Y1791300D01*
X203950Y1791383D01*
X204242Y1791633D01*
X204450Y1792008D01*
X204533Y1792383D01*
Y1792842D01*
X204450Y1793217D01*
X204242Y1793550D01*
X203992Y1793717D01*
X203700Y1793800D01*
X203367Y1793717D01*
X203117Y1793550D01*
X202950Y1793300D01*
X202867Y1792967D01*
X202950Y1792675D01*
X203158Y1792383D01*
X203408Y1792217D01*
X203700Y1792175D01*
X204033Y1792258D01*
X204283Y1792467D01*
X204533Y1792842D01*
G01X207300Y1791300D02*
Y1793800D01*
X205758Y1792008D01*
X207842D01*
G01X209900Y1791300D02*
Y1793800D01*
X209400Y1793300D01*
G01Y1791300D02*
X210400D01*
G01X213500D02*
Y1793800D01*
X211958Y1792008D01*
X214042D01*
G01X196700Y1788500D02*
Y1792500D01*
X189300D01*
G01X217167Y1779600D02*
Y1782100D01*
X218208D01*
X218542Y1781975D01*
X218750Y1781808D01*
X218833Y1781475D01*
X218750Y1781142D01*
X218500Y1780933D01*
X218208Y1780808D01*
X217167D01*
G01X218208D02*
X218833Y1779600D01*
G01X220392Y1779892D02*
X220683Y1779683D01*
X221017Y1779600D01*
X221350Y1779683D01*
X221642Y1779933D01*
X221850Y1780308D01*
X221933Y1780683D01*
Y1781142D01*
X221850Y1781517D01*
X221642Y1781850D01*
X221392Y1782017D01*
X221100Y1782100D01*
X220767Y1782017D01*
X220517Y1781850D01*
X220350Y1781600D01*
X220267Y1781267D01*
X220350Y1780975D01*
X220558Y1780683D01*
X220808Y1780517D01*
X221100Y1780475D01*
X221433Y1780558D01*
X221683Y1780767D01*
X221933Y1781142D01*
G01X224200Y1779600D02*
X224492Y1779642D01*
X224825Y1779767D01*
X225033Y1779975D01*
X225117Y1780267D01*
X225033Y1780558D01*
X224783Y1780808D01*
X224408Y1780933D01*
X223992D01*
X223742Y1781017D01*
X223533Y1781225D01*
X223450Y1781517D01*
X223575Y1781808D01*
X223867Y1782017D01*
X224200Y1782100D01*
X224533Y1782017D01*
X224825Y1781808D01*
X224950Y1781517D01*
X224867Y1781225D01*
X224658Y1781017D01*
X224408Y1780933D01*
X223992D01*
X223617Y1780808D01*
X223367Y1780558D01*
X223283Y1780267D01*
X223367Y1779975D01*
X223575Y1779767D01*
X223908Y1779642D01*
X224200Y1779600D01*
G01X227300D02*
Y1782100D01*
X226800Y1781600D01*
G01Y1779600D02*
X227800D01*
G01X229608Y1780642D02*
X229900Y1780933D01*
X230150Y1781100D01*
X230483Y1781183D01*
X230775Y1781100D01*
X230983Y1780933D01*
X231150Y1780683D01*
X231192Y1780392D01*
X231150Y1780142D01*
X230983Y1779892D01*
X230733Y1779683D01*
X230442Y1779600D01*
X230108Y1779683D01*
X229817Y1779933D01*
X229650Y1780308D01*
X229608Y1780725D01*
X229692Y1781267D01*
X229817Y1781558D01*
X230025Y1781850D01*
X230317Y1782058D01*
X230608Y1782100D01*
X230900Y1782017D01*
X231108Y1781808D01*
G01X221400Y1770100D02*
Y1774100D01*
X214000D01*
G01X195500Y1734967D02*
X193000D01*
Y1736008D01*
X193125Y1736342D01*
X193292Y1736550D01*
X193625Y1736633D01*
X193958Y1736550D01*
X194167Y1736300D01*
X194292Y1736008D01*
Y1734967D01*
G01Y1736008D02*
X195500Y1736633D01*
G01X195208Y1738192D02*
X195417Y1738483D01*
X195500Y1738817D01*
X195417Y1739150D01*
X195167Y1739442D01*
X194792Y1739650D01*
X194417Y1739733D01*
X193958D01*
X193583Y1739650D01*
X193250Y1739442D01*
X193083Y1739192D01*
X193000Y1738900D01*
X193083Y1738567D01*
X193250Y1738317D01*
X193500Y1738150D01*
X193833Y1738067D01*
X194125Y1738150D01*
X194417Y1738358D01*
X194583Y1738608D01*
X194625Y1738900D01*
X194542Y1739233D01*
X194333Y1739483D01*
X193958Y1739733D01*
G01X195500Y1742000D02*
X195458Y1742292D01*
X195333Y1742625D01*
X195125Y1742833D01*
X194833Y1742917D01*
X194542Y1742833D01*
X194292Y1742583D01*
X194167Y1742208D01*
Y1741792D01*
X194083Y1741542D01*
X193875Y1741333D01*
X193583Y1741250D01*
X193292Y1741375D01*
X193083Y1741667D01*
X193000Y1742000D01*
X193083Y1742333D01*
X193292Y1742625D01*
X193583Y1742750D01*
X193875Y1742667D01*
X194083Y1742458D01*
X194167Y1742208D01*
Y1741792D01*
X194292Y1741417D01*
X194542Y1741167D01*
X194833Y1741083D01*
X195125Y1741167D01*
X195333Y1741375D01*
X195458Y1741708D01*
X195500Y1742000D01*
G01Y1745100D02*
X193000D01*
X193500Y1744600D01*
G01X195500D02*
Y1745600D01*
G01Y1748117D02*
X194958Y1748200D01*
X194500Y1748325D01*
X194083Y1748492D01*
X193625Y1748700D01*
X193000Y1749033D01*
Y1747367D01*
G01X196750Y1758450D02*
X192750D01*
Y1751050D01*
G01X237875Y1774833D02*
X238208Y1774625D01*
X238583Y1774500D01*
X238917D01*
X239250Y1774625D01*
X239500Y1774833D01*
X239625Y1775125D01*
X239542Y1775417D01*
X239333Y1775667D01*
X238958Y1775833D01*
X238458Y1775917D01*
X238167Y1776083D01*
X238042Y1776375D01*
X238125Y1776667D01*
X238333Y1776875D01*
X238625Y1777000D01*
X238917D01*
X239208Y1776917D01*
X239458Y1776708D01*
G01X241017Y1774500D02*
Y1777000D01*
X242058D01*
X242392Y1776875D01*
X242600Y1776708D01*
X242683Y1776375D01*
X242600Y1776042D01*
X242350Y1775833D01*
X242058Y1775708D01*
X241017D01*
G01X242058D02*
X242683Y1774500D01*
G01X244950D02*
Y1777000D01*
X244450Y1776500D01*
G01Y1774500D02*
X245450D01*
G01X248050D02*
Y1777000D01*
X247550Y1776500D01*
G01Y1774500D02*
X248550D01*
G01X250233Y1775000D02*
X250483Y1774708D01*
X250817Y1774542D01*
X251192Y1774500D01*
X251525Y1774542D01*
X251858Y1774750D01*
X252067Y1775000D01*
X252108Y1775250D01*
X252025Y1775542D01*
X251733Y1775750D01*
X251442Y1775833D01*
X251067D01*
G01X251442D02*
X251692Y1775958D01*
X251900Y1776167D01*
X251983Y1776417D01*
X251900Y1776667D01*
X251692Y1776875D01*
X251317Y1777000D01*
X250942Y1776958D01*
X250567Y1776792D01*
G01X254250Y1774500D02*
Y1777000D01*
X253750Y1776500D01*
G01Y1774500D02*
X254750D01*
G01X250300Y1767900D02*
Y1771900D01*
X242900D01*
G01X201167Y1730375D02*
X201375Y1730708D01*
X201500Y1731083D01*
Y1731417D01*
X201375Y1731750D01*
X201167Y1732000D01*
X200875Y1732125D01*
X200583Y1732042D01*
X200333Y1731833D01*
X200167Y1731458D01*
X200083Y1730958D01*
X199917Y1730667D01*
X199625Y1730542D01*
X199333Y1730625D01*
X199125Y1730833D01*
X199000Y1731125D01*
Y1731417D01*
X199083Y1731708D01*
X199292Y1731958D01*
G01X201500Y1733517D02*
X199000D01*
Y1734558D01*
X199125Y1734892D01*
X199292Y1735100D01*
X199625Y1735183D01*
X199958Y1735100D01*
X200167Y1734850D01*
X200292Y1734558D01*
Y1733517D01*
G01Y1734558D02*
X201500Y1735183D01*
G01Y1737450D02*
X199000D01*
X199500Y1736950D01*
G01X201500D02*
Y1737950D01*
G01Y1740550D02*
X199000D01*
X199500Y1740050D01*
G01X201500D02*
Y1741050D01*
G01X201000Y1742733D02*
X201292Y1742983D01*
X201458Y1743317D01*
X201500Y1743692D01*
X201458Y1744025D01*
X201250Y1744358D01*
X201000Y1744567D01*
X200750Y1744608D01*
X200458Y1744525D01*
X200250Y1744233D01*
X200167Y1743942D01*
Y1743567D01*
G01Y1743942D02*
X200042Y1744192D01*
X199833Y1744400D01*
X199583Y1744483D01*
X199333Y1744400D01*
X199125Y1744192D01*
X199000Y1743817D01*
X199042Y1743442D01*
X199208Y1743067D01*
G01X199417Y1745958D02*
X199167Y1746208D01*
X199042Y1746500D01*
X199000Y1746833D01*
X199083Y1747250D01*
X199292Y1747542D01*
X199542Y1747625D01*
X199792Y1747583D01*
X200000Y1747417D01*
X200417Y1746583D01*
X200708Y1746208D01*
X201125Y1745958D01*
X201500Y1745875D01*
Y1747625D01*
G01X202198Y1764200D02*
X198198D01*
Y1756800D01*
G01X199767Y1783300D02*
Y1785800D01*
X200808D01*
X201142Y1785675D01*
X201350Y1785508D01*
X201433Y1785175D01*
X201350Y1784842D01*
X201100Y1784633D01*
X200808Y1784508D01*
X199767D01*
G01X200808D02*
X201433Y1783300D01*
G01X202992Y1783592D02*
X203283Y1783383D01*
X203617Y1783300D01*
X203950Y1783383D01*
X204242Y1783633D01*
X204450Y1784008D01*
X204533Y1784383D01*
Y1784842D01*
X204450Y1785217D01*
X204242Y1785550D01*
X203992Y1785717D01*
X203700Y1785800D01*
X203367Y1785717D01*
X203117Y1785550D01*
X202950Y1785300D01*
X202867Y1784967D01*
X202950Y1784675D01*
X203158Y1784383D01*
X203408Y1784217D01*
X203700Y1784175D01*
X204033Y1784258D01*
X204283Y1784467D01*
X204533Y1784842D01*
G01X206800Y1783300D02*
X207092Y1783342D01*
X207425Y1783467D01*
X207633Y1783675D01*
X207717Y1783967D01*
X207633Y1784258D01*
X207383Y1784508D01*
X207008Y1784633D01*
X206592D01*
X206342Y1784717D01*
X206133Y1784925D01*
X206050Y1785217D01*
X206175Y1785508D01*
X206467Y1785717D01*
X206800Y1785800D01*
X207133Y1785717D01*
X207425Y1785508D01*
X207550Y1785217D01*
X207467Y1784925D01*
X207258Y1784717D01*
X207008Y1784633D01*
X206592D01*
X206217Y1784508D01*
X205967Y1784258D01*
X205883Y1783967D01*
X205967Y1783675D01*
X206175Y1783467D01*
X206508Y1783342D01*
X206800Y1783300D01*
G01X209192Y1783592D02*
X209483Y1783383D01*
X209817Y1783300D01*
X210150Y1783383D01*
X210442Y1783633D01*
X210650Y1784008D01*
X210733Y1784383D01*
Y1784842D01*
X210650Y1785217D01*
X210442Y1785550D01*
X210192Y1785717D01*
X209900Y1785800D01*
X209567Y1785717D01*
X209317Y1785550D01*
X209150Y1785300D01*
X209067Y1784967D01*
X209150Y1784675D01*
X209358Y1784383D01*
X209608Y1784217D01*
X209900Y1784175D01*
X210233Y1784258D01*
X210483Y1784467D01*
X210733Y1784842D01*
G01X212917Y1783300D02*
X213000Y1783842D01*
X213125Y1784300D01*
X213292Y1784717D01*
X213500Y1785175D01*
X213833Y1785800D01*
X212167D01*
G01X196700Y1779500D02*
Y1783500D01*
X189300D01*
G01X217167Y1783600D02*
Y1786100D01*
X218208D01*
X218542Y1785975D01*
X218750Y1785808D01*
X218833Y1785475D01*
X218750Y1785142D01*
X218500Y1784933D01*
X218208Y1784808D01*
X217167D01*
G01X218208D02*
X218833Y1783600D01*
G01X220392Y1783892D02*
X220683Y1783683D01*
X221017Y1783600D01*
X221350Y1783683D01*
X221642Y1783933D01*
X221850Y1784308D01*
X221933Y1784683D01*
Y1785142D01*
X221850Y1785517D01*
X221642Y1785850D01*
X221392Y1786017D01*
X221100Y1786100D01*
X220767Y1786017D01*
X220517Y1785850D01*
X220350Y1785600D01*
X220267Y1785267D01*
X220350Y1784975D01*
X220558Y1784683D01*
X220808Y1784517D01*
X221100Y1784475D01*
X221433Y1784558D01*
X221683Y1784767D01*
X221933Y1785142D01*
G01X223492Y1783892D02*
X223783Y1783683D01*
X224117Y1783600D01*
X224450Y1783683D01*
X224742Y1783933D01*
X224950Y1784308D01*
X225033Y1784683D01*
Y1785142D01*
X224950Y1785517D01*
X224742Y1785850D01*
X224492Y1786017D01*
X224200Y1786100D01*
X223867Y1786017D01*
X223617Y1785850D01*
X223450Y1785600D01*
X223367Y1785267D01*
X223450Y1784975D01*
X223658Y1784683D01*
X223908Y1784517D01*
X224200Y1784475D01*
X224533Y1784558D01*
X224783Y1784767D01*
X225033Y1785142D01*
G01X227300Y1783600D02*
Y1786100D01*
X226800Y1785600D01*
G01Y1783600D02*
X227800D01*
G01X230317D02*
X230400Y1784142D01*
X230525Y1784600D01*
X230692Y1785017D01*
X230900Y1785475D01*
X231233Y1786100D01*
X229567D01*
G01X221400Y1774200D02*
Y1778200D01*
X214000D01*
G01X199767Y1787300D02*
Y1789800D01*
X200808D01*
X201142Y1789675D01*
X201350Y1789508D01*
X201433Y1789175D01*
X201350Y1788842D01*
X201100Y1788633D01*
X200808Y1788508D01*
X199767D01*
G01X200808D02*
X201433Y1787300D01*
G01X202992Y1787592D02*
X203283Y1787383D01*
X203617Y1787300D01*
X203950Y1787383D01*
X204242Y1787633D01*
X204450Y1788008D01*
X204533Y1788383D01*
Y1788842D01*
X204450Y1789217D01*
X204242Y1789550D01*
X203992Y1789717D01*
X203700Y1789800D01*
X203367Y1789717D01*
X203117Y1789550D01*
X202950Y1789300D01*
X202867Y1788967D01*
X202950Y1788675D01*
X203158Y1788383D01*
X203408Y1788217D01*
X203700Y1788175D01*
X204033Y1788258D01*
X204283Y1788467D01*
X204533Y1788842D01*
G01X207300Y1787300D02*
Y1789800D01*
X205758Y1788008D01*
X207842D01*
G01X209900Y1787300D02*
Y1789800D01*
X209400Y1789300D01*
G01Y1787300D02*
X210400D01*
G01X212083Y1787675D02*
X212333Y1787467D01*
X212625Y1787342D01*
X213000Y1787300D01*
X213375Y1787383D01*
X213667Y1787550D01*
X213875Y1787842D01*
X213917Y1788175D01*
X213833Y1788508D01*
X213625Y1788717D01*
X213333Y1788883D01*
X213042Y1788925D01*
X212750Y1788883D01*
X212375Y1788717D01*
X212500Y1789800D01*
X213625D01*
G01X196700Y1784000D02*
Y1788000D01*
X189300D01*
G01X201933Y1781500D02*
Y1779708D01*
X202100Y1779333D01*
X202433Y1779083D01*
X202850Y1779000D01*
X203267Y1779083D01*
X203600Y1779333D01*
X203767Y1779708D01*
Y1781500D01*
G01X205158Y1781083D02*
X205408Y1781333D01*
X205700Y1781458D01*
X206033Y1781500D01*
X206450Y1781417D01*
X206742Y1781208D01*
X206825Y1780958D01*
X206783Y1780708D01*
X206617Y1780500D01*
X205783Y1780083D01*
X205408Y1779792D01*
X205158Y1779375D01*
X205075Y1779000D01*
X206825D01*
G01X209050Y1781500D02*
X208717Y1781417D01*
X208467Y1781208D01*
X208300Y1780958D01*
X208175Y1780625D01*
X208133Y1780250D01*
X208175Y1779875D01*
X208300Y1779542D01*
X208467Y1779292D01*
X208717Y1779083D01*
X209050Y1779000D01*
X209383Y1779083D01*
X209633Y1779292D01*
X209800Y1779542D01*
X209925Y1779875D01*
X209967Y1780250D01*
X209925Y1780625D01*
X209800Y1780958D01*
X209633Y1781208D01*
X209383Y1781417D01*
X209050Y1781500D01*
G01X211358Y1781083D02*
X211608Y1781333D01*
X211900Y1781458D01*
X212233Y1781500D01*
X212650Y1781417D01*
X212942Y1781208D01*
X213025Y1780958D01*
X212983Y1780708D01*
X212817Y1780500D01*
X211983Y1780083D01*
X211608Y1779792D01*
X211358Y1779375D01*
X211275Y1779000D01*
X213025D01*
G01X197646Y1777000D02*
X211046D01*
G01X197646Y1767000D02*
Y1777000D01*
G01X211046Y1767000D02*
X197646D01*
G01X211046Y1777000D02*
Y1767000D01*
G01X324737Y331812D02*
X324487Y331937D01*
X324195Y332020D01*
X323862D01*
X323487Y331895D01*
X323195Y331687D01*
X322987Y331437D01*
X322820Y331020D01*
X322778Y330645D01*
X322862Y330270D01*
X322987Y330020D01*
X323237Y329770D01*
X323528Y329603D01*
X323820Y329520D01*
X324112D01*
X324403Y329603D01*
X324653Y329728D01*
X324862Y329895D01*
G01X326212Y329812D02*
X326503Y329603D01*
X326837Y329520D01*
X327170Y329603D01*
X327462Y329853D01*
X327670Y330228D01*
X327753Y330603D01*
Y331062D01*
X327670Y331437D01*
X327462Y331770D01*
X327212Y331937D01*
X326920Y332020D01*
X326587Y331937D01*
X326337Y331770D01*
X326170Y331520D01*
X326087Y331187D01*
X326170Y330895D01*
X326378Y330603D01*
X326628Y330437D01*
X326920Y330395D01*
X327253Y330478D01*
X327503Y330687D01*
X327753Y331062D01*
G01X329103Y330020D02*
X329353Y329728D01*
X329687Y329562D01*
X330062Y329520D01*
X330395Y329562D01*
X330728Y329770D01*
X330937Y330020D01*
X330978Y330270D01*
X330895Y330562D01*
X330603Y330770D01*
X330312Y330853D01*
X329937D01*
G01X330312D02*
X330562Y330978D01*
X330770Y331187D01*
X330853Y331437D01*
X330770Y331687D01*
X330562Y331895D01*
X330187Y332020D01*
X329812Y331978D01*
X329437Y331812D01*
G01X332203Y330020D02*
X332453Y329728D01*
X332787Y329562D01*
X333162Y329520D01*
X333495Y329562D01*
X333828Y329770D01*
X334037Y330020D01*
X334078Y330270D01*
X333995Y330562D01*
X333703Y330770D01*
X333412Y330853D01*
X333037D01*
G01X333412D02*
X333662Y330978D01*
X333870Y331187D01*
X333953Y331437D01*
X333870Y331687D01*
X333662Y331895D01*
X333287Y332020D01*
X332912Y331978D01*
X332537Y331812D01*
G01X336137Y329520D02*
X336220Y330062D01*
X336345Y330520D01*
X336512Y330937D01*
X336720Y331395D01*
X337053Y332020D01*
X335387D01*
G01X322617Y307790D02*
Y310290D01*
X323658D01*
X323992Y310165D01*
X324200Y309998D01*
X324283Y309665D01*
X324200Y309332D01*
X323950Y309123D01*
X323658Y308998D01*
X322617D01*
G01X323658D02*
X324283Y307790D01*
G01X325842Y308082D02*
X326133Y307873D01*
X326467Y307790D01*
X326800Y307873D01*
X327092Y308123D01*
X327300Y308498D01*
X327383Y308873D01*
Y309332D01*
X327300Y309707D01*
X327092Y310040D01*
X326842Y310207D01*
X326550Y310290D01*
X326217Y310207D01*
X325967Y310040D01*
X325800Y309790D01*
X325717Y309457D01*
X325800Y309165D01*
X326008Y308873D01*
X326258Y308707D01*
X326550Y308665D01*
X326883Y308748D01*
X327133Y308957D01*
X327383Y309332D01*
G01X328733Y308290D02*
X328983Y307998D01*
X329317Y307832D01*
X329692Y307790D01*
X330025Y307832D01*
X330358Y308040D01*
X330567Y308290D01*
X330608Y308540D01*
X330525Y308832D01*
X330233Y309040D01*
X329942Y309123D01*
X329567D01*
G01X329942D02*
X330192Y309248D01*
X330400Y309457D01*
X330483Y309707D01*
X330400Y309957D01*
X330192Y310165D01*
X329817Y310290D01*
X329442Y310248D01*
X329067Y310082D01*
G01X332042Y308082D02*
X332333Y307873D01*
X332667Y307790D01*
X333000Y307873D01*
X333292Y308123D01*
X333500Y308498D01*
X333583Y308873D01*
Y309332D01*
X333500Y309707D01*
X333292Y310040D01*
X333042Y310207D01*
X332750Y310290D01*
X332417Y310207D01*
X332167Y310040D01*
X332000Y309790D01*
X331917Y309457D01*
X332000Y309165D01*
X332208Y308873D01*
X332458Y308707D01*
X332750Y308665D01*
X333083Y308748D01*
X333333Y308957D01*
X333583Y309332D01*
G01X334933Y308165D02*
X335183Y307957D01*
X335475Y307832D01*
X335850Y307790D01*
X336225Y307873D01*
X336517Y308040D01*
X336725Y308332D01*
X336767Y308665D01*
X336683Y308998D01*
X336475Y309207D01*
X336183Y309373D01*
X335892Y309415D01*
X335600Y309373D01*
X335225Y309207D01*
X335350Y310290D01*
X336475D01*
G01X272125Y302267D02*
Y304767D01*
G01X273875D02*
Y302267D01*
G01Y303517D02*
X272125D01*
G01X276100Y302267D02*
Y304767D01*
X275600Y304267D01*
G01Y302267D02*
X276600D01*
G01X279200Y304767D02*
X278867Y304684D01*
X278617Y304475D01*
X278450Y304225D01*
X278325Y303892D01*
X278283Y303517D01*
X278325Y303142D01*
X278450Y302809D01*
X278617Y302559D01*
X278867Y302350D01*
X279200Y302267D01*
X279533Y302350D01*
X279783Y302559D01*
X279950Y302809D01*
X280075Y303142D01*
X280117Y303517D01*
X280075Y303892D01*
X279950Y304225D01*
X279783Y304475D01*
X279533Y304684D01*
X279200Y304767D01*
G01X296797Y402517D02*
X296672Y402267D01*
X296589Y401975D01*
Y401642D01*
X296714Y401267D01*
X296922Y400975D01*
X297172Y400767D01*
X297589Y400600D01*
X297964Y400558D01*
X298339Y400642D01*
X298589Y400767D01*
X298839Y401017D01*
X299006Y401308D01*
X299089Y401600D01*
Y401892D01*
X299006Y402183D01*
X298881Y402433D01*
X298714Y402642D01*
G01X299089Y404700D02*
X299047Y404992D01*
X298922Y405325D01*
X298714Y405533D01*
X298422Y405617D01*
X298131Y405533D01*
X297881Y405283D01*
X297756Y404908D01*
Y404492D01*
X297672Y404242D01*
X297464Y404033D01*
X297172Y403950D01*
X296881Y404075D01*
X296672Y404367D01*
X296589Y404700D01*
X296672Y405033D01*
X296881Y405325D01*
X297172Y405450D01*
X297464Y405367D01*
X297672Y405158D01*
X297756Y404908D01*
Y404492D01*
X297881Y404117D01*
X298131Y403867D01*
X298422Y403783D01*
X298714Y403867D01*
X298922Y404075D01*
X299047Y404408D01*
X299089Y404700D01*
G01X298797Y407092D02*
X299006Y407383D01*
X299089Y407717D01*
X299006Y408050D01*
X298756Y408342D01*
X298381Y408550D01*
X298006Y408633D01*
X297547D01*
X297172Y408550D01*
X296839Y408342D01*
X296672Y408092D01*
X296589Y407800D01*
X296672Y407467D01*
X296839Y407217D01*
X297089Y407050D01*
X297422Y406967D01*
X297714Y407050D01*
X298006Y407258D01*
X298172Y407508D01*
X298214Y407800D01*
X298131Y408133D01*
X297922Y408383D01*
X297547Y408633D01*
G01X298589Y409983D02*
X298881Y410233D01*
X299047Y410567D01*
X299089Y410942D01*
X299047Y411275D01*
X298839Y411608D01*
X298589Y411817D01*
X298339Y411858D01*
X298047Y411775D01*
X297839Y411483D01*
X297756Y411192D01*
Y410817D01*
G01Y411192D02*
X297631Y411442D01*
X297422Y411650D01*
X297172Y411733D01*
X296922Y411650D01*
X296714Y411442D01*
X296589Y411067D01*
X296631Y410692D01*
X296797Y410317D01*
G01X298589Y413083D02*
X298881Y413333D01*
X299047Y413667D01*
X299089Y414042D01*
X299047Y414375D01*
X298839Y414708D01*
X298589Y414917D01*
X298339Y414958D01*
X298047Y414875D01*
X297839Y414583D01*
X297756Y414292D01*
Y413917D01*
G01Y414292D02*
X297631Y414542D01*
X297422Y414750D01*
X297172Y414833D01*
X296922Y414750D01*
X296714Y414542D01*
X296589Y414167D01*
X296631Y413792D01*
X296797Y413417D01*
G01X300308Y402217D02*
X300183Y401967D01*
X300100Y401675D01*
Y401342D01*
X300225Y400967D01*
X300433Y400675D01*
X300683Y400467D01*
X301100Y400300D01*
X301475Y400258D01*
X301850Y400342D01*
X302100Y400467D01*
X302350Y400717D01*
X302517Y401008D01*
X302600Y401300D01*
Y401592D01*
X302517Y401883D01*
X302392Y402133D01*
X302225Y402342D01*
G01X302600Y404400D02*
X302558Y404692D01*
X302433Y405025D01*
X302225Y405233D01*
X301933Y405317D01*
X301642Y405233D01*
X301392Y404983D01*
X301267Y404608D01*
Y404192D01*
X301183Y403942D01*
X300975Y403733D01*
X300683Y403650D01*
X300392Y403775D01*
X300183Y404067D01*
X300100Y404400D01*
X300183Y404733D01*
X300392Y405025D01*
X300683Y405150D01*
X300975Y405067D01*
X301183Y404858D01*
X301267Y404608D01*
Y404192D01*
X301392Y403817D01*
X301642Y403567D01*
X301933Y403483D01*
X302225Y403567D01*
X302433Y403775D01*
X302558Y404108D01*
X302600Y404400D01*
G01X302308Y406792D02*
X302517Y407083D01*
X302600Y407417D01*
X302517Y407750D01*
X302267Y408042D01*
X301892Y408250D01*
X301517Y408333D01*
X301058D01*
X300683Y408250D01*
X300350Y408042D01*
X300183Y407792D01*
X300100Y407500D01*
X300183Y407167D01*
X300350Y406917D01*
X300600Y406750D01*
X300933Y406667D01*
X301225Y406750D01*
X301517Y406958D01*
X301683Y407208D01*
X301725Y407500D01*
X301642Y407833D01*
X301433Y408083D01*
X301058Y408333D01*
G01X302100Y409683D02*
X302392Y409933D01*
X302558Y410267D01*
X302600Y410642D01*
X302558Y410975D01*
X302350Y411308D01*
X302100Y411517D01*
X301850Y411558D01*
X301558Y411475D01*
X301350Y411183D01*
X301267Y410892D01*
Y410517D01*
G01Y410892D02*
X301142Y411142D01*
X300933Y411350D01*
X300683Y411433D01*
X300433Y411350D01*
X300225Y411142D01*
X300100Y410767D01*
X300142Y410392D01*
X300308Y410017D01*
G01X302600Y414200D02*
X300100D01*
X301892Y412658D01*
Y414742D01*
G01X307077Y350180D02*
Y352680D01*
X308077D01*
X308410Y352555D01*
X308660Y352263D01*
X308743Y351930D01*
X308660Y351597D01*
X308452Y351347D01*
X308077Y351222D01*
X307077D01*
G01X310177Y350180D02*
Y352680D01*
X311218D01*
X311552Y352555D01*
X311760Y352388D01*
X311843Y352055D01*
X311760Y351722D01*
X311510Y351513D01*
X311218Y351388D01*
X310177D01*
G01X311218D02*
X311843Y350180D01*
G01X313402Y350472D02*
X313693Y350263D01*
X314027Y350180D01*
X314360Y350263D01*
X314652Y350513D01*
X314860Y350888D01*
X314943Y351263D01*
Y351722D01*
X314860Y352097D01*
X314652Y352430D01*
X314402Y352597D01*
X314110Y352680D01*
X313777Y352597D01*
X313527Y352430D01*
X313360Y352180D01*
X313277Y351847D01*
X313360Y351555D01*
X313568Y351263D01*
X313818Y351097D01*
X314110Y351055D01*
X314443Y351138D01*
X314693Y351347D01*
X314943Y351722D01*
G01X317210Y352680D02*
X316877Y352597D01*
X316627Y352388D01*
X316460Y352138D01*
X316335Y351805D01*
X316293Y351430D01*
X316335Y351055D01*
X316460Y350722D01*
X316627Y350472D01*
X316877Y350263D01*
X317210Y350180D01*
X317543Y350263D01*
X317793Y350472D01*
X317960Y350722D01*
X318085Y351055D01*
X318127Y351430D01*
X318085Y351805D01*
X317960Y352138D01*
X317793Y352388D01*
X317543Y352597D01*
X317210Y352680D01*
G01X320810Y350180D02*
Y352680D01*
X319268Y350888D01*
X321352D01*
G01X323410Y350180D02*
Y352680D01*
X322910Y352180D01*
G01Y350180D02*
X323910D01*
G01X328800Y379000D02*
Y375000D01*
X336200D01*
G01X308077Y370180D02*
Y372680D01*
X309077D01*
X309410Y372555D01*
X309660Y372263D01*
X309743Y371930D01*
X309660Y371597D01*
X309452Y371347D01*
X309077Y371222D01*
X308077D01*
G01X311177Y370180D02*
Y372680D01*
X312218D01*
X312552Y372555D01*
X312760Y372388D01*
X312843Y372055D01*
X312760Y371722D01*
X312510Y371513D01*
X312218Y371388D01*
X311177D01*
G01X312218D02*
X312843Y370180D01*
G01X314402Y370472D02*
X314693Y370263D01*
X315027Y370180D01*
X315360Y370263D01*
X315652Y370513D01*
X315860Y370888D01*
X315943Y371263D01*
Y371722D01*
X315860Y372097D01*
X315652Y372430D01*
X315402Y372597D01*
X315110Y372680D01*
X314777Y372597D01*
X314527Y372430D01*
X314360Y372180D01*
X314277Y371847D01*
X314360Y371555D01*
X314568Y371263D01*
X314818Y371097D01*
X315110Y371055D01*
X315443Y371138D01*
X315693Y371347D01*
X315943Y371722D01*
G01X318210Y372680D02*
X317877Y372597D01*
X317627Y372388D01*
X317460Y372138D01*
X317335Y371805D01*
X317293Y371430D01*
X317335Y371055D01*
X317460Y370722D01*
X317627Y370472D01*
X317877Y370263D01*
X318210Y370180D01*
X318543Y370263D01*
X318793Y370472D01*
X318960Y370722D01*
X319085Y371055D01*
X319127Y371430D01*
X319085Y371805D01*
X318960Y372138D01*
X318793Y372388D01*
X318543Y372597D01*
X318210Y372680D01*
G01X321810Y370180D02*
Y372680D01*
X320268Y370888D01*
X322352D01*
G01X323618Y372263D02*
X323868Y372513D01*
X324160Y372638D01*
X324493Y372680D01*
X324910Y372597D01*
X325202Y372388D01*
X325285Y372138D01*
X325243Y371888D01*
X325077Y371680D01*
X324243Y371263D01*
X323868Y370972D01*
X323618Y370555D01*
X323535Y370180D01*
X325285D01*
G01X308077Y366180D02*
Y368680D01*
X309118D01*
X309452Y368555D01*
X309660Y368388D01*
X309743Y368055D01*
X309660Y367722D01*
X309410Y367513D01*
X309118Y367388D01*
X308077D01*
G01X309118D02*
X309743Y366180D01*
G01X311302Y366472D02*
X311593Y366263D01*
X311927Y366180D01*
X312260Y366263D01*
X312552Y366513D01*
X312760Y366888D01*
X312843Y367263D01*
Y367722D01*
X312760Y368097D01*
X312552Y368430D01*
X312302Y368597D01*
X312010Y368680D01*
X311677Y368597D01*
X311427Y368430D01*
X311260Y368180D01*
X311177Y367847D01*
X311260Y367555D01*
X311468Y367263D01*
X311718Y367097D01*
X312010Y367055D01*
X312343Y367138D01*
X312593Y367347D01*
X312843Y367722D01*
G01X315110Y366180D02*
Y368680D01*
X314610Y368180D01*
G01Y366180D02*
X315610D01*
G01X317418Y368263D02*
X317668Y368513D01*
X317960Y368638D01*
X318293Y368680D01*
X318710Y368597D01*
X319002Y368388D01*
X319085Y368138D01*
X319043Y367888D01*
X318877Y367680D01*
X318043Y367263D01*
X317668Y366972D01*
X317418Y366555D01*
X317335Y366180D01*
X319085D01*
G01X321310D02*
Y368680D01*
X320810Y368180D01*
G01Y366180D02*
X321810D01*
G01X307077Y346180D02*
Y348680D01*
X308118D01*
X308452Y348555D01*
X308660Y348388D01*
X308743Y348055D01*
X308660Y347722D01*
X308410Y347513D01*
X308118Y347388D01*
X307077D01*
G01X308118D02*
X308743Y346180D01*
G01X310302Y346472D02*
X310593Y346263D01*
X310927Y346180D01*
X311260Y346263D01*
X311552Y346513D01*
X311760Y346888D01*
X311843Y347263D01*
Y347722D01*
X311760Y348097D01*
X311552Y348430D01*
X311302Y348597D01*
X311010Y348680D01*
X310677Y348597D01*
X310427Y348430D01*
X310260Y348180D01*
X310177Y347847D01*
X310260Y347555D01*
X310468Y347263D01*
X310718Y347097D01*
X311010Y347055D01*
X311343Y347138D01*
X311593Y347347D01*
X311843Y347722D01*
G01X314110Y346180D02*
Y348680D01*
X313610Y348180D01*
G01Y346180D02*
X314610D01*
G01X316418Y348263D02*
X316668Y348513D01*
X316960Y348638D01*
X317293Y348680D01*
X317710Y348597D01*
X318002Y348388D01*
X318085Y348138D01*
X318043Y347888D01*
X317877Y347680D01*
X317043Y347263D01*
X316668Y346972D01*
X316418Y346555D01*
X316335Y346180D01*
X318085D01*
G01X319518Y348263D02*
X319768Y348513D01*
X320060Y348638D01*
X320393Y348680D01*
X320810Y348597D01*
X321102Y348388D01*
X321185Y348138D01*
X321143Y347888D01*
X320977Y347680D01*
X320143Y347263D01*
X319768Y346972D01*
X319518Y346555D01*
X319435Y346180D01*
X321185D01*
G01X336200Y371000D02*
Y375000D01*
X328800D01*
G01X322800Y410500D02*
Y406500D01*
X330200D01*
G01X281067Y409900D02*
Y412400D01*
X282108D01*
X282442Y412275D01*
X282650Y412108D01*
X282733Y411775D01*
X282650Y411442D01*
X282400Y411233D01*
X282108Y411108D01*
X281067D01*
G01X282108D02*
X282733Y409900D01*
G01X284292Y410192D02*
X284583Y409983D01*
X284917Y409900D01*
X285250Y409983D01*
X285542Y410233D01*
X285750Y410608D01*
X285833Y410983D01*
Y411442D01*
X285750Y411817D01*
X285542Y412150D01*
X285292Y412317D01*
X285000Y412400D01*
X284667Y412317D01*
X284417Y412150D01*
X284250Y411900D01*
X284167Y411567D01*
X284250Y411275D01*
X284458Y410983D01*
X284708Y410817D01*
X285000Y410775D01*
X285333Y410858D01*
X285583Y411067D01*
X285833Y411442D01*
G01X287183Y410400D02*
X287433Y410108D01*
X287767Y409942D01*
X288142Y409900D01*
X288475Y409942D01*
X288808Y410150D01*
X289017Y410400D01*
X289058Y410650D01*
X288975Y410942D01*
X288683Y411150D01*
X288392Y411233D01*
X288017D01*
G01X288392D02*
X288642Y411358D01*
X288850Y411567D01*
X288933Y411817D01*
X288850Y412067D01*
X288642Y412275D01*
X288267Y412400D01*
X287892Y412358D01*
X287517Y412192D01*
G01X290283Y410275D02*
X290533Y410067D01*
X290825Y409942D01*
X291200Y409900D01*
X291575Y409983D01*
X291867Y410150D01*
X292075Y410442D01*
X292117Y410775D01*
X292033Y411108D01*
X291825Y411317D01*
X291533Y411483D01*
X291242Y411525D01*
X290950Y411483D01*
X290575Y411317D01*
X290700Y412400D01*
X291825D01*
G01X294217Y409900D02*
X294300Y410442D01*
X294425Y410900D01*
X294592Y411317D01*
X294800Y411775D01*
X295133Y412400D01*
X293467D01*
G01X322800Y406400D02*
Y402400D01*
X330200D01*
G01X307077Y354180D02*
Y356680D01*
X308118D01*
X308452Y356555D01*
X308660Y356388D01*
X308743Y356055D01*
X308660Y355722D01*
X308410Y355513D01*
X308118Y355388D01*
X307077D01*
G01X308118D02*
X308743Y354180D01*
G01X311510D02*
Y356680D01*
X309968Y354888D01*
X312052D01*
G01X313318Y356263D02*
X313568Y356513D01*
X313860Y356638D01*
X314193Y356680D01*
X314610Y356597D01*
X314902Y356388D01*
X314985Y356138D01*
X314943Y355888D01*
X314777Y355680D01*
X313943Y355263D01*
X313568Y354972D01*
X313318Y354555D01*
X313235Y354180D01*
X314985D01*
G01X316293Y354555D02*
X316543Y354347D01*
X316835Y354222D01*
X317210Y354180D01*
X317585Y354263D01*
X317877Y354430D01*
X318085Y354722D01*
X318127Y355055D01*
X318043Y355388D01*
X317835Y355597D01*
X317543Y355763D01*
X317252Y355805D01*
X316960Y355763D01*
X316585Y355597D01*
X316710Y356680D01*
X317835D01*
G01X328800Y383000D02*
Y379000D01*
X336200D01*
G01X307077Y358180D02*
Y360680D01*
X308118D01*
X308452Y360555D01*
X308660Y360388D01*
X308743Y360055D01*
X308660Y359722D01*
X308410Y359513D01*
X308118Y359388D01*
X307077D01*
G01X308118D02*
X308743Y358180D01*
G01X311510D02*
Y360680D01*
X309968Y358888D01*
X312052D01*
G01X313318Y360263D02*
X313568Y360513D01*
X313860Y360638D01*
X314193Y360680D01*
X314610Y360597D01*
X314902Y360388D01*
X314985Y360138D01*
X314943Y359888D01*
X314777Y359680D01*
X313943Y359263D01*
X313568Y358972D01*
X313318Y358555D01*
X313235Y358180D01*
X314985D01*
G01X316418Y359222D02*
X316710Y359513D01*
X316960Y359680D01*
X317293Y359763D01*
X317585Y359680D01*
X317793Y359513D01*
X317960Y359263D01*
X318002Y358972D01*
X317960Y358722D01*
X317793Y358472D01*
X317543Y358263D01*
X317252Y358180D01*
X316918Y358263D01*
X316627Y358513D01*
X316460Y358888D01*
X316418Y359305D01*
X316502Y359847D01*
X316627Y360138D01*
X316835Y360430D01*
X317127Y360638D01*
X317418Y360680D01*
X317710Y360597D01*
X317918Y360388D01*
G01X328800Y387000D02*
Y383000D01*
X336200D01*
G01X298676Y358519D02*
X296176D01*
Y359560D01*
X296301Y359894D01*
X296468Y360102D01*
X296801Y360185D01*
X297134Y360102D01*
X297343Y359852D01*
X297468Y359560D01*
Y358519D01*
G01Y359560D02*
X298676Y360185D01*
G01X298384Y361744D02*
X298593Y362035D01*
X298676Y362369D01*
X298593Y362702D01*
X298343Y362994D01*
X297968Y363202D01*
X297593Y363285D01*
X297134D01*
X296759Y363202D01*
X296426Y362994D01*
X296259Y362744D01*
X296176Y362452D01*
X296259Y362119D01*
X296426Y361869D01*
X296676Y361702D01*
X297009Y361619D01*
X297301Y361702D01*
X297593Y361910D01*
X297759Y362160D01*
X297801Y362452D01*
X297718Y362785D01*
X297509Y363035D01*
X297134Y363285D01*
G01X298384Y364844D02*
X298593Y365135D01*
X298676Y365469D01*
X298593Y365802D01*
X298343Y366094D01*
X297968Y366302D01*
X297593Y366385D01*
X297134D01*
X296759Y366302D01*
X296426Y366094D01*
X296259Y365844D01*
X296176Y365552D01*
X296259Y365219D01*
X296426Y364969D01*
X296676Y364802D01*
X297009Y364719D01*
X297301Y364802D01*
X297593Y365010D01*
X297759Y365260D01*
X297801Y365552D01*
X297718Y365885D01*
X297509Y366135D01*
X297134Y366385D01*
G01X298676Y368569D02*
X298134Y368652D01*
X297676Y368777D01*
X297259Y368944D01*
X296801Y369152D01*
X296176Y369485D01*
Y367819D01*
G01X297634Y370960D02*
X297343Y371252D01*
X297176Y371502D01*
X297093Y371835D01*
X297176Y372127D01*
X297343Y372335D01*
X297593Y372502D01*
X297884Y372544D01*
X298134Y372502D01*
X298384Y372335D01*
X298593Y372085D01*
X298676Y371794D01*
X298593Y371460D01*
X298343Y371169D01*
X297968Y371002D01*
X297551Y370960D01*
X297009Y371044D01*
X296718Y371169D01*
X296426Y371377D01*
X296218Y371669D01*
X296176Y371960D01*
X296259Y372252D01*
X296468Y372460D01*
G01X307100Y398500D02*
X303100D01*
Y391100D01*
G01X298676Y374919D02*
X296176D01*
Y375960D01*
X296301Y376294D01*
X296468Y376502D01*
X296801Y376585D01*
X297134Y376502D01*
X297343Y376252D01*
X297468Y375960D01*
Y374919D01*
G01Y375960D02*
X298676Y376585D01*
G01X298384Y378144D02*
X298593Y378435D01*
X298676Y378769D01*
X298593Y379102D01*
X298343Y379394D01*
X297968Y379602D01*
X297593Y379685D01*
X297134D01*
X296759Y379602D01*
X296426Y379394D01*
X296259Y379144D01*
X296176Y378852D01*
X296259Y378519D01*
X296426Y378269D01*
X296676Y378102D01*
X297009Y378019D01*
X297301Y378102D01*
X297593Y378310D01*
X297759Y378560D01*
X297801Y378852D01*
X297718Y379185D01*
X297509Y379435D01*
X297134Y379685D01*
G01X298384Y381244D02*
X298593Y381535D01*
X298676Y381869D01*
X298593Y382202D01*
X298343Y382494D01*
X297968Y382702D01*
X297593Y382785D01*
X297134D01*
X296759Y382702D01*
X296426Y382494D01*
X296259Y382244D01*
X296176Y381952D01*
X296259Y381619D01*
X296426Y381369D01*
X296676Y381202D01*
X297009Y381119D01*
X297301Y381202D01*
X297593Y381410D01*
X297759Y381660D01*
X297801Y381952D01*
X297718Y382285D01*
X297509Y382535D01*
X297134Y382785D01*
G01X298676Y384969D02*
X298134Y385052D01*
X297676Y385177D01*
X297259Y385344D01*
X296801Y385552D01*
X296176Y385885D01*
Y384219D01*
G01X298301Y387235D02*
X298509Y387485D01*
X298634Y387777D01*
X298676Y388152D01*
X298593Y388527D01*
X298426Y388819D01*
X298134Y389027D01*
X297801Y389069D01*
X297468Y388985D01*
X297259Y388777D01*
X297093Y388485D01*
X297051Y388194D01*
X297093Y387902D01*
X297259Y387527D01*
X296176Y387652D01*
Y388777D01*
G01X303100Y398600D02*
X307100D01*
Y406000D01*
G01X303176Y375019D02*
X300676D01*
Y376060D01*
X300801Y376394D01*
X300968Y376602D01*
X301301Y376685D01*
X301634Y376602D01*
X301843Y376352D01*
X301968Y376060D01*
Y375019D01*
G01Y376060D02*
X303176Y376685D01*
G01X302884Y378244D02*
X303093Y378535D01*
X303176Y378869D01*
X303093Y379202D01*
X302843Y379494D01*
X302468Y379702D01*
X302093Y379785D01*
X301634D01*
X301259Y379702D01*
X300926Y379494D01*
X300759Y379244D01*
X300676Y378952D01*
X300759Y378619D01*
X300926Y378369D01*
X301176Y378202D01*
X301509Y378119D01*
X301801Y378202D01*
X302093Y378410D01*
X302259Y378660D01*
X302301Y378952D01*
X302218Y379285D01*
X302009Y379535D01*
X301634Y379785D01*
G01X302884Y381344D02*
X303093Y381635D01*
X303176Y381969D01*
X303093Y382302D01*
X302843Y382594D01*
X302468Y382802D01*
X302093Y382885D01*
X301634D01*
X301259Y382802D01*
X300926Y382594D01*
X300759Y382344D01*
X300676Y382052D01*
X300759Y381719D01*
X300926Y381469D01*
X301176Y381302D01*
X301509Y381219D01*
X301801Y381302D01*
X302093Y381510D01*
X302259Y381760D01*
X302301Y382052D01*
X302218Y382385D01*
X302009Y382635D01*
X301634Y382885D01*
G01X303176Y385069D02*
X302634Y385152D01*
X302176Y385277D01*
X301759Y385444D01*
X301301Y385652D01*
X300676Y385985D01*
Y384319D01*
G01X302676Y387335D02*
X302968Y387585D01*
X303134Y387919D01*
X303176Y388294D01*
X303134Y388627D01*
X302926Y388960D01*
X302676Y389169D01*
X302426Y389210D01*
X302134Y389127D01*
X301926Y388835D01*
X301843Y388544D01*
Y388169D01*
G01Y388544D02*
X301718Y388794D01*
X301509Y389002D01*
X301259Y389085D01*
X301009Y389002D01*
X300801Y388794D01*
X300676Y388419D01*
X300718Y388044D01*
X300884Y387669D01*
G01X311300Y406000D02*
X307300D01*
Y398600D01*
G01X303276Y358419D02*
X300776D01*
Y359460D01*
X300901Y359794D01*
X301068Y360002D01*
X301401Y360085D01*
X301734Y360002D01*
X301943Y359752D01*
X302068Y359460D01*
Y358419D01*
G01Y359460D02*
X303276Y360085D01*
G01X302984Y361644D02*
X303193Y361935D01*
X303276Y362269D01*
X303193Y362602D01*
X302943Y362894D01*
X302568Y363102D01*
X302193Y363185D01*
X301734D01*
X301359Y363102D01*
X301026Y362894D01*
X300859Y362644D01*
X300776Y362352D01*
X300859Y362019D01*
X301026Y361769D01*
X301276Y361602D01*
X301609Y361519D01*
X301901Y361602D01*
X302193Y361810D01*
X302359Y362060D01*
X302401Y362352D01*
X302318Y362685D01*
X302109Y362935D01*
X301734Y363185D01*
G01X302984Y364744D02*
X303193Y365035D01*
X303276Y365369D01*
X303193Y365702D01*
X302943Y365994D01*
X302568Y366202D01*
X302193Y366285D01*
X301734D01*
X301359Y366202D01*
X301026Y365994D01*
X300859Y365744D01*
X300776Y365452D01*
X300859Y365119D01*
X301026Y364869D01*
X301276Y364702D01*
X301609Y364619D01*
X301901Y364702D01*
X302193Y364910D01*
X302359Y365160D01*
X302401Y365452D01*
X302318Y365785D01*
X302109Y366035D01*
X301734Y366285D01*
G01X303276Y368469D02*
X302734Y368552D01*
X302276Y368677D01*
X301859Y368844D01*
X301401Y369052D01*
X300776Y369385D01*
Y367719D01*
G01X301193Y370860D02*
X300943Y371110D01*
X300818Y371402D01*
X300776Y371735D01*
X300859Y372152D01*
X301068Y372444D01*
X301318Y372527D01*
X301568Y372485D01*
X301776Y372319D01*
X302193Y371485D01*
X302484Y371110D01*
X302901Y370860D01*
X303276Y370777D01*
Y372527D01*
G01X307300Y391100D02*
X311300D01*
Y398500D01*
G01X317950Y374967D02*
X315450D01*
Y376008D01*
X315575Y376342D01*
X315742Y376550D01*
X316075Y376633D01*
X316408Y376550D01*
X316617Y376300D01*
X316742Y376008D01*
Y374967D01*
G01Y376008D02*
X317950Y376633D01*
G01X317658Y378192D02*
X317867Y378483D01*
X317950Y378817D01*
X317867Y379150D01*
X317617Y379442D01*
X317242Y379650D01*
X316867Y379733D01*
X316408D01*
X316033Y379650D01*
X315700Y379442D01*
X315533Y379192D01*
X315450Y378900D01*
X315533Y378567D01*
X315700Y378317D01*
X315950Y378150D01*
X316283Y378067D01*
X316575Y378150D01*
X316867Y378358D01*
X317033Y378608D01*
X317075Y378900D01*
X316992Y379233D01*
X316783Y379483D01*
X316408Y379733D01*
G01X317658Y381292D02*
X317867Y381583D01*
X317950Y381917D01*
X317867Y382250D01*
X317617Y382542D01*
X317242Y382750D01*
X316867Y382833D01*
X316408D01*
X316033Y382750D01*
X315700Y382542D01*
X315533Y382292D01*
X315450Y382000D01*
X315533Y381667D01*
X315700Y381417D01*
X315950Y381250D01*
X316283Y381167D01*
X316575Y381250D01*
X316867Y381458D01*
X317033Y381708D01*
X317075Y382000D01*
X316992Y382333D01*
X316783Y382583D01*
X316408Y382833D01*
G01X317950Y385017D02*
X317408Y385100D01*
X316950Y385225D01*
X316533Y385392D01*
X316075Y385600D01*
X315450Y385933D01*
Y384267D01*
G01X317950Y388700D02*
X315450D01*
X317242Y387158D01*
Y389242D01*
G01X323317Y456692D02*
X323067Y456817D01*
X322775Y456900D01*
X322442D01*
X322067Y456775D01*
X321775Y456567D01*
X321567Y456317D01*
X321400Y455900D01*
X321358Y455525D01*
X321442Y455150D01*
X321567Y454900D01*
X321817Y454650D01*
X322108Y454483D01*
X322400Y454400D01*
X322692D01*
X322983Y454483D01*
X323233Y454608D01*
X323442Y454775D01*
G01X324792Y454692D02*
X325083Y454483D01*
X325417Y454400D01*
X325750Y454483D01*
X326042Y454733D01*
X326250Y455108D01*
X326333Y455483D01*
Y455942D01*
X326250Y456317D01*
X326042Y456650D01*
X325792Y456817D01*
X325500Y456900D01*
X325167Y456817D01*
X324917Y456650D01*
X324750Y456400D01*
X324667Y456067D01*
X324750Y455775D01*
X324958Y455483D01*
X325208Y455317D01*
X325500Y455275D01*
X325833Y455358D01*
X326083Y455567D01*
X326333Y455942D01*
G01X327683Y454900D02*
X327933Y454608D01*
X328267Y454442D01*
X328642Y454400D01*
X328975Y454442D01*
X329308Y454650D01*
X329517Y454900D01*
X329558Y455150D01*
X329475Y455442D01*
X329183Y455650D01*
X328892Y455733D01*
X328517D01*
G01X328892D02*
X329142Y455858D01*
X329350Y456067D01*
X329433Y456317D01*
X329350Y456567D01*
X329142Y456775D01*
X328767Y456900D01*
X328392Y456858D01*
X328017Y456692D01*
G01X332200Y454400D02*
Y456900D01*
X330658Y455108D01*
X332742D01*
G01X333883Y454775D02*
X334133Y454567D01*
X334425Y454442D01*
X334800Y454400D01*
X335175Y454483D01*
X335467Y454650D01*
X335675Y454942D01*
X335717Y455275D01*
X335633Y455608D01*
X335425Y455817D01*
X335133Y455983D01*
X334842Y456025D01*
X334550Y455983D01*
X334175Y455817D01*
X334300Y456900D01*
X335425D01*
G01X307117Y456692D02*
X306867Y456817D01*
X306575Y456900D01*
X306242D01*
X305867Y456775D01*
X305575Y456567D01*
X305367Y456317D01*
X305200Y455900D01*
X305158Y455525D01*
X305242Y455150D01*
X305367Y454900D01*
X305617Y454650D01*
X305908Y454483D01*
X306200Y454400D01*
X306492D01*
X306783Y454483D01*
X307033Y454608D01*
X307242Y454775D01*
G01X308592Y454692D02*
X308883Y454483D01*
X309217Y454400D01*
X309550Y454483D01*
X309842Y454733D01*
X310050Y455108D01*
X310133Y455483D01*
Y455942D01*
X310050Y456317D01*
X309842Y456650D01*
X309592Y456817D01*
X309300Y456900D01*
X308967Y456817D01*
X308717Y456650D01*
X308550Y456400D01*
X308467Y456067D01*
X308550Y455775D01*
X308758Y455483D01*
X309008Y455317D01*
X309300Y455275D01*
X309633Y455358D01*
X309883Y455567D01*
X310133Y455942D01*
G01X311483Y454900D02*
X311733Y454608D01*
X312067Y454442D01*
X312442Y454400D01*
X312775Y454442D01*
X313108Y454650D01*
X313317Y454900D01*
X313358Y455150D01*
X313275Y455442D01*
X312983Y455650D01*
X312692Y455733D01*
X312317D01*
G01X312692D02*
X312942Y455858D01*
X313150Y456067D01*
X313233Y456317D01*
X313150Y456567D01*
X312942Y456775D01*
X312567Y456900D01*
X312192Y456858D01*
X311817Y456692D01*
G01X315417Y454400D02*
X315500Y454942D01*
X315625Y455400D01*
X315792Y455817D01*
X316000Y456275D01*
X316333Y456900D01*
X314667D01*
G01X317683Y454900D02*
X317933Y454608D01*
X318267Y454442D01*
X318642Y454400D01*
X318975Y454442D01*
X319308Y454650D01*
X319517Y454900D01*
X319558Y455150D01*
X319475Y455442D01*
X319183Y455650D01*
X318892Y455733D01*
X318517D01*
G01X318892D02*
X319142Y455858D01*
X319350Y456067D01*
X319433Y456317D01*
X319350Y456567D01*
X319142Y456775D01*
X318767Y456900D01*
X318392Y456858D01*
X318017Y456692D01*
G01X301808Y430397D02*
X301683Y430147D01*
X301600Y429855D01*
Y429522D01*
X301725Y429147D01*
X301933Y428855D01*
X302183Y428647D01*
X302600Y428480D01*
X302975Y428438D01*
X303350Y428522D01*
X303600Y428647D01*
X303850Y428897D01*
X304017Y429188D01*
X304100Y429480D01*
Y429772D01*
X304017Y430063D01*
X303892Y430313D01*
X303725Y430522D01*
G01X304100Y432580D02*
X304058Y432872D01*
X303933Y433205D01*
X303725Y433413D01*
X303433Y433497D01*
X303142Y433413D01*
X302892Y433163D01*
X302767Y432788D01*
Y432372D01*
X302683Y432122D01*
X302475Y431913D01*
X302183Y431830D01*
X301892Y431955D01*
X301683Y432247D01*
X301600Y432580D01*
X301683Y432913D01*
X301892Y433205D01*
X302183Y433330D01*
X302475Y433247D01*
X302683Y433038D01*
X302767Y432788D01*
Y432372D01*
X302892Y431997D01*
X303142Y431747D01*
X303433Y431663D01*
X303725Y431747D01*
X303933Y431955D01*
X304058Y432288D01*
X304100Y432580D01*
G01X303808Y434972D02*
X304017Y435263D01*
X304100Y435597D01*
X304017Y435930D01*
X303767Y436222D01*
X303392Y436430D01*
X303017Y436513D01*
X302558D01*
X302183Y436430D01*
X301850Y436222D01*
X301683Y435972D01*
X301600Y435680D01*
X301683Y435347D01*
X301850Y435097D01*
X302100Y434930D01*
X302433Y434847D01*
X302725Y434930D01*
X303017Y435138D01*
X303183Y435388D01*
X303225Y435680D01*
X303142Y436013D01*
X302933Y436263D01*
X302558Y436513D01*
G01X303600Y437863D02*
X303892Y438113D01*
X304058Y438447D01*
X304100Y438822D01*
X304058Y439155D01*
X303850Y439488D01*
X303600Y439697D01*
X303350Y439738D01*
X303058Y439655D01*
X302850Y439363D01*
X302767Y439072D01*
Y438697D01*
G01Y439072D02*
X302642Y439322D01*
X302433Y439530D01*
X302183Y439613D01*
X301933Y439530D01*
X301725Y439322D01*
X301600Y438947D01*
X301642Y438572D01*
X301808Y438197D01*
G01X304100Y441880D02*
X301600D01*
X302100Y441380D01*
G01X304100D02*
Y442380D01*
G01X305808Y430217D02*
X305683Y429967D01*
X305600Y429675D01*
Y429342D01*
X305725Y428967D01*
X305933Y428675D01*
X306183Y428467D01*
X306600Y428300D01*
X306975Y428258D01*
X307350Y428342D01*
X307600Y428467D01*
X307850Y428717D01*
X308017Y429008D01*
X308100Y429300D01*
Y429592D01*
X308017Y429883D01*
X307892Y430133D01*
X307725Y430342D01*
G01X308100Y432400D02*
X308058Y432692D01*
X307933Y433025D01*
X307725Y433233D01*
X307433Y433317D01*
X307142Y433233D01*
X306892Y432983D01*
X306767Y432608D01*
Y432192D01*
X306683Y431942D01*
X306475Y431733D01*
X306183Y431650D01*
X305892Y431775D01*
X305683Y432067D01*
X305600Y432400D01*
X305683Y432733D01*
X305892Y433025D01*
X306183Y433150D01*
X306475Y433067D01*
X306683Y432858D01*
X306767Y432608D01*
Y432192D01*
X306892Y431817D01*
X307142Y431567D01*
X307433Y431483D01*
X307725Y431567D01*
X307933Y431775D01*
X308058Y432108D01*
X308100Y432400D01*
G01X307808Y434792D02*
X308017Y435083D01*
X308100Y435417D01*
X308017Y435750D01*
X307767Y436042D01*
X307392Y436250D01*
X307017Y436333D01*
X306558D01*
X306183Y436250D01*
X305850Y436042D01*
X305683Y435792D01*
X305600Y435500D01*
X305683Y435167D01*
X305850Y434917D01*
X306100Y434750D01*
X306433Y434667D01*
X306725Y434750D01*
X307017Y434958D01*
X307183Y435208D01*
X307225Y435500D01*
X307142Y435833D01*
X306933Y436083D01*
X306558Y436333D01*
G01X307600Y437683D02*
X307892Y437933D01*
X308058Y438267D01*
X308100Y438642D01*
X308058Y438975D01*
X307850Y439308D01*
X307600Y439517D01*
X307350Y439558D01*
X307058Y439475D01*
X306850Y439183D01*
X306767Y438892D01*
Y438517D01*
G01Y438892D02*
X306642Y439142D01*
X306433Y439350D01*
X306183Y439433D01*
X305933Y439350D01*
X305725Y439142D01*
X305600Y438767D01*
X305642Y438392D01*
X305808Y438017D01*
G01X306017Y440908D02*
X305767Y441158D01*
X305642Y441450D01*
X305600Y441783D01*
X305683Y442200D01*
X305892Y442492D01*
X306142Y442575D01*
X306392Y442533D01*
X306600Y442367D01*
X307017Y441533D01*
X307308Y441158D01*
X307725Y440908D01*
X308100Y440825D01*
Y442575D01*
G01X321567Y462400D02*
Y464900D01*
X322608D01*
X322942Y464775D01*
X323150Y464608D01*
X323233Y464275D01*
X323150Y463942D01*
X322900Y463733D01*
X322608Y463608D01*
X321567D01*
G01X322608D02*
X323233Y462400D01*
G01X324792Y462692D02*
X325083Y462483D01*
X325417Y462400D01*
X325750Y462483D01*
X326042Y462733D01*
X326250Y463108D01*
X326333Y463483D01*
Y463942D01*
X326250Y464317D01*
X326042Y464650D01*
X325792Y464817D01*
X325500Y464900D01*
X325167Y464817D01*
X324917Y464650D01*
X324750Y464400D01*
X324667Y464067D01*
X324750Y463775D01*
X324958Y463483D01*
X325208Y463317D01*
X325500Y463275D01*
X325833Y463358D01*
X326083Y463567D01*
X326333Y463942D01*
G01X329100Y462400D02*
Y464900D01*
X327558Y463108D01*
X329642D01*
G01X330908Y464483D02*
X331158Y464733D01*
X331450Y464858D01*
X331783Y464900D01*
X332200Y464817D01*
X332492Y464608D01*
X332575Y464358D01*
X332533Y464108D01*
X332367Y463900D01*
X331533Y463483D01*
X331158Y463192D01*
X330908Y462775D01*
X330825Y462400D01*
X332575D01*
G01X333883Y462900D02*
X334133Y462608D01*
X334467Y462442D01*
X334842Y462400D01*
X335175Y462442D01*
X335508Y462650D01*
X335717Y462900D01*
X335758Y463150D01*
X335675Y463442D01*
X335383Y463650D01*
X335092Y463733D01*
X334717D01*
G01X335092D02*
X335342Y463858D01*
X335550Y464067D01*
X335633Y464317D01*
X335550Y464567D01*
X335342Y464775D01*
X334967Y464900D01*
X334592Y464858D01*
X334217Y464692D01*
G01X326670Y435777D02*
X324170D01*
Y436818D01*
X324295Y437152D01*
X324462Y437360D01*
X324795Y437443D01*
X325128Y437360D01*
X325337Y437110D01*
X325462Y436818D01*
Y435777D01*
G01Y436818D02*
X326670Y437443D01*
G01X326378Y439002D02*
X326587Y439293D01*
X326670Y439627D01*
X326587Y439960D01*
X326337Y440252D01*
X325962Y440460D01*
X325587Y440543D01*
X325128D01*
X324753Y440460D01*
X324420Y440252D01*
X324253Y440002D01*
X324170Y439710D01*
X324253Y439377D01*
X324420Y439127D01*
X324670Y438960D01*
X325003Y438877D01*
X325295Y438960D01*
X325587Y439168D01*
X325753Y439418D01*
X325795Y439710D01*
X325712Y440043D01*
X325503Y440293D01*
X325128Y440543D01*
G01X324170Y442810D02*
X324253Y442477D01*
X324462Y442227D01*
X324712Y442060D01*
X325045Y441935D01*
X325420Y441893D01*
X325795Y441935D01*
X326128Y442060D01*
X326378Y442227D01*
X326587Y442477D01*
X326670Y442810D01*
X326587Y443143D01*
X326378Y443393D01*
X326128Y443560D01*
X325795Y443685D01*
X325420Y443727D01*
X325045Y443685D01*
X324712Y443560D01*
X324462Y443393D01*
X324253Y443143D01*
X324170Y442810D01*
G01X326295Y444993D02*
X326503Y445243D01*
X326628Y445535D01*
X326670Y445910D01*
X326587Y446285D01*
X326420Y446577D01*
X326128Y446785D01*
X325795Y446827D01*
X325462Y446743D01*
X325253Y446535D01*
X325087Y446243D01*
X325045Y445952D01*
X325087Y445660D01*
X325253Y445285D01*
X324170Y445410D01*
Y446535D01*
G01X326378Y448302D02*
X326587Y448593D01*
X326670Y448927D01*
X326587Y449260D01*
X326337Y449552D01*
X325962Y449760D01*
X325587Y449843D01*
X325128D01*
X324753Y449760D01*
X324420Y449552D01*
X324253Y449302D01*
X324170Y449010D01*
X324253Y448677D01*
X324420Y448427D01*
X324670Y448260D01*
X325003Y448177D01*
X325295Y448260D01*
X325587Y448468D01*
X325753Y448718D01*
X325795Y449010D01*
X325712Y449343D01*
X325503Y449593D01*
X325128Y449843D01*
G01X322670Y435777D02*
X320170D01*
Y436818D01*
X320295Y437152D01*
X320462Y437360D01*
X320795Y437443D01*
X321128Y437360D01*
X321337Y437110D01*
X321462Y436818D01*
Y435777D01*
G01Y436818D02*
X322670Y437443D01*
G01X322378Y439002D02*
X322587Y439293D01*
X322670Y439627D01*
X322587Y439960D01*
X322337Y440252D01*
X321962Y440460D01*
X321587Y440543D01*
X321128D01*
X320753Y440460D01*
X320420Y440252D01*
X320253Y440002D01*
X320170Y439710D01*
X320253Y439377D01*
X320420Y439127D01*
X320670Y438960D01*
X321003Y438877D01*
X321295Y438960D01*
X321587Y439168D01*
X321753Y439418D01*
X321795Y439710D01*
X321712Y440043D01*
X321503Y440293D01*
X321128Y440543D01*
G01X320170Y442810D02*
X320253Y442477D01*
X320462Y442227D01*
X320712Y442060D01*
X321045Y441935D01*
X321420Y441893D01*
X321795Y441935D01*
X322128Y442060D01*
X322378Y442227D01*
X322587Y442477D01*
X322670Y442810D01*
X322587Y443143D01*
X322378Y443393D01*
X322128Y443560D01*
X321795Y443685D01*
X321420Y443727D01*
X321045Y443685D01*
X320712Y443560D01*
X320462Y443393D01*
X320253Y443143D01*
X320170Y442810D01*
G01X321628Y445118D02*
X321337Y445410D01*
X321170Y445660D01*
X321087Y445993D01*
X321170Y446285D01*
X321337Y446493D01*
X321587Y446660D01*
X321878Y446702D01*
X322128Y446660D01*
X322378Y446493D01*
X322587Y446243D01*
X322670Y445952D01*
X322587Y445618D01*
X322337Y445327D01*
X321962Y445160D01*
X321545Y445118D01*
X321003Y445202D01*
X320712Y445327D01*
X320420Y445535D01*
X320212Y445827D01*
X320170Y446118D01*
X320253Y446410D01*
X320462Y446618D01*
G01X320170Y449010D02*
X320253Y448677D01*
X320462Y448427D01*
X320712Y448260D01*
X321045Y448135D01*
X321420Y448093D01*
X321795Y448135D01*
X322128Y448260D01*
X322378Y448427D01*
X322587Y448677D01*
X322670Y449010D01*
X322587Y449343D01*
X322378Y449593D01*
X322128Y449760D01*
X321795Y449885D01*
X321420Y449927D01*
X321045Y449885D01*
X320712Y449760D01*
X320462Y449593D01*
X320253Y449343D01*
X320170Y449010D01*
G01X331470Y435977D02*
X328970D01*
Y437018D01*
X329095Y437352D01*
X329262Y437560D01*
X329595Y437643D01*
X329928Y437560D01*
X330137Y437310D01*
X330262Y437018D01*
Y435977D01*
G01Y437018D02*
X331470Y437643D01*
G01X331178Y439202D02*
X331387Y439493D01*
X331470Y439827D01*
X331387Y440160D01*
X331137Y440452D01*
X330762Y440660D01*
X330387Y440743D01*
X329928D01*
X329553Y440660D01*
X329220Y440452D01*
X329053Y440202D01*
X328970Y439910D01*
X329053Y439577D01*
X329220Y439327D01*
X329470Y439160D01*
X329803Y439077D01*
X330095Y439160D01*
X330387Y439368D01*
X330553Y439618D01*
X330595Y439910D01*
X330512Y440243D01*
X330303Y440493D01*
X329928Y440743D01*
G01X328970Y443010D02*
X329053Y442677D01*
X329262Y442427D01*
X329512Y442260D01*
X329845Y442135D01*
X330220Y442093D01*
X330595Y442135D01*
X330928Y442260D01*
X331178Y442427D01*
X331387Y442677D01*
X331470Y443010D01*
X331387Y443343D01*
X331178Y443593D01*
X330928Y443760D01*
X330595Y443885D01*
X330220Y443927D01*
X329845Y443885D01*
X329512Y443760D01*
X329262Y443593D01*
X329053Y443343D01*
X328970Y443010D01*
G01X330428Y445318D02*
X330137Y445610D01*
X329970Y445860D01*
X329887Y446193D01*
X329970Y446485D01*
X330137Y446693D01*
X330387Y446860D01*
X330678Y446902D01*
X330928Y446860D01*
X331178Y446693D01*
X331387Y446443D01*
X331470Y446152D01*
X331387Y445818D01*
X331137Y445527D01*
X330762Y445360D01*
X330345Y445318D01*
X329803Y445402D01*
X329512Y445527D01*
X329220Y445735D01*
X329012Y446027D01*
X328970Y446318D01*
X329053Y446610D01*
X329262Y446818D01*
G01X329387Y448418D02*
X329137Y448668D01*
X329012Y448960D01*
X328970Y449293D01*
X329053Y449710D01*
X329262Y450002D01*
X329512Y450085D01*
X329762Y450043D01*
X329970Y449877D01*
X330387Y449043D01*
X330678Y448668D01*
X331095Y448418D01*
X331470Y448335D01*
Y450085D01*
G01X281067Y417900D02*
Y420400D01*
X282067D01*
X282400Y420275D01*
X282650Y419983D01*
X282733Y419650D01*
X282650Y419317D01*
X282442Y419067D01*
X282067Y418942D01*
X281067D01*
G01X284167Y417900D02*
Y420400D01*
X285208D01*
X285542Y420275D01*
X285750Y420108D01*
X285833Y419775D01*
X285750Y419442D01*
X285500Y419233D01*
X285208Y419108D01*
X284167D01*
G01X285208D02*
X285833Y417900D01*
G01X287392Y418192D02*
X287683Y417983D01*
X288017Y417900D01*
X288350Y417983D01*
X288642Y418233D01*
X288850Y418608D01*
X288933Y418983D01*
Y419442D01*
X288850Y419817D01*
X288642Y420150D01*
X288392Y420317D01*
X288100Y420400D01*
X287767Y420317D01*
X287517Y420150D01*
X287350Y419900D01*
X287267Y419567D01*
X287350Y419275D01*
X287558Y418983D01*
X287808Y418817D01*
X288100Y418775D01*
X288433Y418858D01*
X288683Y419067D01*
X288933Y419442D01*
G01X291200Y420400D02*
X290867Y420317D01*
X290617Y420108D01*
X290450Y419858D01*
X290325Y419525D01*
X290283Y419150D01*
X290325Y418775D01*
X290450Y418442D01*
X290617Y418192D01*
X290867Y417983D01*
X291200Y417900D01*
X291533Y417983D01*
X291783Y418192D01*
X291950Y418442D01*
X292075Y418775D01*
X292117Y419150D01*
X292075Y419525D01*
X291950Y419858D01*
X291783Y420108D01*
X291533Y420317D01*
X291200Y420400D01*
G01X293508Y418942D02*
X293800Y419233D01*
X294050Y419400D01*
X294383Y419483D01*
X294675Y419400D01*
X294883Y419233D01*
X295050Y418983D01*
X295092Y418692D01*
X295050Y418442D01*
X294883Y418192D01*
X294633Y417983D01*
X294342Y417900D01*
X294008Y417983D01*
X293717Y418233D01*
X293550Y418608D01*
X293508Y419025D01*
X293592Y419567D01*
X293717Y419858D01*
X293925Y420150D01*
X294217Y420358D01*
X294508Y420400D01*
X294800Y420317D01*
X295008Y420108D01*
G01X297900Y417900D02*
Y420400D01*
X296358Y418608D01*
X298442D01*
G01X330200Y411000D02*
Y415000D01*
X322800D01*
G01X281025Y426233D02*
X281358Y426025D01*
X281733Y425900D01*
X282067D01*
X282400Y426025D01*
X282650Y426233D01*
X282775Y426525D01*
X282692Y426817D01*
X282483Y427067D01*
X282108Y427233D01*
X281608Y427317D01*
X281317Y427483D01*
X281192Y427775D01*
X281275Y428067D01*
X281483Y428275D01*
X281775Y428400D01*
X282067D01*
X282358Y428317D01*
X282608Y428108D01*
G01X284167Y425900D02*
Y428400D01*
X285208D01*
X285542Y428275D01*
X285750Y428108D01*
X285833Y427775D01*
X285750Y427442D01*
X285500Y427233D01*
X285208Y427108D01*
X284167D01*
G01X285208D02*
X285833Y425900D01*
G01X287392Y426192D02*
X287683Y425983D01*
X288017Y425900D01*
X288350Y425983D01*
X288642Y426233D01*
X288850Y426608D01*
X288933Y426983D01*
Y427442D01*
X288850Y427817D01*
X288642Y428150D01*
X288392Y428317D01*
X288100Y428400D01*
X287767Y428317D01*
X287517Y428150D01*
X287350Y427900D01*
X287267Y427567D01*
X287350Y427275D01*
X287558Y426983D01*
X287808Y426817D01*
X288100Y426775D01*
X288433Y426858D01*
X288683Y427067D01*
X288933Y427442D01*
G01X290283Y426275D02*
X290533Y426067D01*
X290825Y425942D01*
X291200Y425900D01*
X291575Y425983D01*
X291867Y426150D01*
X292075Y426442D01*
X292117Y426775D01*
X292033Y427108D01*
X291825Y427317D01*
X291533Y427483D01*
X291242Y427525D01*
X290950Y427483D01*
X290575Y427317D01*
X290700Y428400D01*
X291825D01*
G01X294800Y425900D02*
Y428400D01*
X293258Y426608D01*
X295342D01*
G01X322800Y423000D02*
Y419000D01*
X330200D01*
G01X281025Y422233D02*
X281358Y422025D01*
X281733Y421900D01*
X282067D01*
X282400Y422025D01*
X282650Y422233D01*
X282775Y422525D01*
X282692Y422817D01*
X282483Y423067D01*
X282108Y423233D01*
X281608Y423317D01*
X281317Y423483D01*
X281192Y423775D01*
X281275Y424067D01*
X281483Y424275D01*
X281775Y424400D01*
X282067D01*
X282358Y424317D01*
X282608Y424108D01*
G01X284167Y421900D02*
Y424400D01*
X285208D01*
X285542Y424275D01*
X285750Y424108D01*
X285833Y423775D01*
X285750Y423442D01*
X285500Y423233D01*
X285208Y423108D01*
X284167D01*
G01X285208D02*
X285833Y421900D01*
G01X287392Y422192D02*
X287683Y421983D01*
X288017Y421900D01*
X288350Y421983D01*
X288642Y422233D01*
X288850Y422608D01*
X288933Y422983D01*
Y423442D01*
X288850Y423817D01*
X288642Y424150D01*
X288392Y424317D01*
X288100Y424400D01*
X287767Y424317D01*
X287517Y424150D01*
X287350Y423900D01*
X287267Y423567D01*
X287350Y423275D01*
X287558Y422983D01*
X287808Y422817D01*
X288100Y422775D01*
X288433Y422858D01*
X288683Y423067D01*
X288933Y423442D01*
G01X290283Y422275D02*
X290533Y422067D01*
X290825Y421942D01*
X291200Y421900D01*
X291575Y421983D01*
X291867Y422150D01*
X292075Y422442D01*
X292117Y422775D01*
X292033Y423108D01*
X291825Y423317D01*
X291533Y423483D01*
X291242Y423525D01*
X290950Y423483D01*
X290575Y423317D01*
X290700Y424400D01*
X291825D01*
G01X293383Y422275D02*
X293633Y422067D01*
X293925Y421942D01*
X294300Y421900D01*
X294675Y421983D01*
X294967Y422150D01*
X295175Y422442D01*
X295217Y422775D01*
X295133Y423108D01*
X294925Y423317D01*
X294633Y423483D01*
X294342Y423525D01*
X294050Y423483D01*
X293675Y423317D01*
X293800Y424400D01*
X294925D01*
G01X322800Y419000D02*
Y415000D01*
X330200D01*
G01X281025Y414233D02*
X281358Y414025D01*
X281733Y413900D01*
X282067D01*
X282400Y414025D01*
X282650Y414233D01*
X282775Y414525D01*
X282692Y414817D01*
X282483Y415067D01*
X282108Y415233D01*
X281608Y415317D01*
X281317Y415483D01*
X281192Y415775D01*
X281275Y416067D01*
X281483Y416275D01*
X281775Y416400D01*
X282067D01*
X282358Y416317D01*
X282608Y416108D01*
G01X284167Y413900D02*
Y416400D01*
X285208D01*
X285542Y416275D01*
X285750Y416108D01*
X285833Y415775D01*
X285750Y415442D01*
X285500Y415233D01*
X285208Y415108D01*
X284167D01*
G01X285208D02*
X285833Y413900D01*
G01X287392Y414192D02*
X287683Y413983D01*
X288017Y413900D01*
X288350Y413983D01*
X288642Y414233D01*
X288850Y414608D01*
X288933Y414983D01*
Y415442D01*
X288850Y415817D01*
X288642Y416150D01*
X288392Y416317D01*
X288100Y416400D01*
X287767Y416317D01*
X287517Y416150D01*
X287350Y415900D01*
X287267Y415567D01*
X287350Y415275D01*
X287558Y414983D01*
X287808Y414817D01*
X288100Y414775D01*
X288433Y414858D01*
X288683Y415067D01*
X288933Y415442D01*
G01X290283Y414275D02*
X290533Y414067D01*
X290825Y413942D01*
X291200Y413900D01*
X291575Y413983D01*
X291867Y414150D01*
X292075Y414442D01*
X292117Y414775D01*
X292033Y415108D01*
X291825Y415317D01*
X291533Y415483D01*
X291242Y415525D01*
X290950Y415483D01*
X290575Y415317D01*
X290700Y416400D01*
X291825D01*
G01X293508Y414942D02*
X293800Y415233D01*
X294050Y415400D01*
X294383Y415483D01*
X294675Y415400D01*
X294883Y415233D01*
X295050Y414983D01*
X295092Y414692D01*
X295050Y414442D01*
X294883Y414192D01*
X294633Y413983D01*
X294342Y413900D01*
X294008Y413983D01*
X293717Y414233D01*
X293550Y414608D01*
X293508Y415025D01*
X293592Y415567D01*
X293717Y415858D01*
X293925Y416150D01*
X294217Y416358D01*
X294508Y416400D01*
X294800Y416317D01*
X295008Y416108D01*
G01X305367Y462400D02*
Y464900D01*
X306408D01*
X306742Y464775D01*
X306950Y464608D01*
X307033Y464275D01*
X306950Y463942D01*
X306700Y463733D01*
X306408Y463608D01*
X305367D01*
G01X306408D02*
X307033Y462400D01*
G01X308592Y462692D02*
X308883Y462483D01*
X309217Y462400D01*
X309550Y462483D01*
X309842Y462733D01*
X310050Y463108D01*
X310133Y463483D01*
Y463942D01*
X310050Y464317D01*
X309842Y464650D01*
X309592Y464817D01*
X309300Y464900D01*
X308967Y464817D01*
X308717Y464650D01*
X308550Y464400D01*
X308467Y464067D01*
X308550Y463775D01*
X308758Y463483D01*
X309008Y463317D01*
X309300Y463275D01*
X309633Y463358D01*
X309883Y463567D01*
X310133Y463942D01*
G01X311483Y462775D02*
X311733Y462567D01*
X312025Y462442D01*
X312400Y462400D01*
X312775Y462483D01*
X313067Y462650D01*
X313275Y462942D01*
X313317Y463275D01*
X313233Y463608D01*
X313025Y463817D01*
X312733Y463983D01*
X312442Y464025D01*
X312150Y463983D01*
X311775Y463817D01*
X311900Y464900D01*
X313025D01*
G01X315500Y462400D02*
X315792Y462442D01*
X316125Y462567D01*
X316333Y462775D01*
X316417Y463067D01*
X316333Y463358D01*
X316083Y463608D01*
X315708Y463733D01*
X315292D01*
X315042Y463817D01*
X314833Y464025D01*
X314750Y464317D01*
X314875Y464608D01*
X315167Y464817D01*
X315500Y464900D01*
X315833Y464817D01*
X316125Y464608D01*
X316250Y464317D01*
X316167Y464025D01*
X315958Y463817D01*
X315708Y463733D01*
X315292D01*
X314917Y463608D01*
X314667Y463358D01*
X314583Y463067D01*
X314667Y462775D01*
X314875Y462567D01*
X315208Y462442D01*
X315500Y462400D01*
G01X318517D02*
X318600Y462942D01*
X318725Y463400D01*
X318892Y463817D01*
X319100Y464275D01*
X319433Y464900D01*
X317767D01*
G01X281067Y429900D02*
Y432400D01*
X282108D01*
X282442Y432275D01*
X282650Y432108D01*
X282733Y431775D01*
X282650Y431442D01*
X282400Y431233D01*
X282108Y431108D01*
X281067D01*
G01X282108D02*
X282733Y429900D01*
G01X284292Y430192D02*
X284583Y429983D01*
X284917Y429900D01*
X285250Y429983D01*
X285542Y430233D01*
X285750Y430608D01*
X285833Y430983D01*
Y431442D01*
X285750Y431817D01*
X285542Y432150D01*
X285292Y432317D01*
X285000Y432400D01*
X284667Y432317D01*
X284417Y432150D01*
X284250Y431900D01*
X284167Y431567D01*
X284250Y431275D01*
X284458Y430983D01*
X284708Y430817D01*
X285000Y430775D01*
X285333Y430858D01*
X285583Y431067D01*
X285833Y431442D01*
G01X287183Y430400D02*
X287433Y430108D01*
X287767Y429942D01*
X288142Y429900D01*
X288475Y429942D01*
X288808Y430150D01*
X289017Y430400D01*
X289058Y430650D01*
X288975Y430942D01*
X288683Y431150D01*
X288392Y431233D01*
X288017D01*
G01X288392D02*
X288642Y431358D01*
X288850Y431567D01*
X288933Y431817D01*
X288850Y432067D01*
X288642Y432275D01*
X288267Y432400D01*
X287892Y432358D01*
X287517Y432192D01*
G01X290283Y430275D02*
X290533Y430067D01*
X290825Y429942D01*
X291200Y429900D01*
X291575Y429983D01*
X291867Y430150D01*
X292075Y430442D01*
X292117Y430775D01*
X292033Y431108D01*
X291825Y431317D01*
X291533Y431483D01*
X291242Y431525D01*
X290950Y431483D01*
X290575Y431317D01*
X290700Y432400D01*
X291825D01*
G01X294300Y429900D02*
X294592Y429942D01*
X294925Y430067D01*
X295133Y430275D01*
X295217Y430567D01*
X295133Y430858D01*
X294883Y431108D01*
X294508Y431233D01*
X294092D01*
X293842Y431317D01*
X293633Y431525D01*
X293550Y431817D01*
X293675Y432108D01*
X293967Y432317D01*
X294300Y432400D01*
X294633Y432317D01*
X294925Y432108D01*
X295050Y431817D01*
X294967Y431525D01*
X294758Y431317D01*
X294508Y431233D01*
X294092D01*
X293717Y431108D01*
X293467Y430858D01*
X293383Y430567D01*
X293467Y430275D01*
X293675Y430067D01*
X294008Y429942D01*
X294300Y429900D01*
G01X322800Y427000D02*
Y423000D01*
X330200D01*
G01X304967Y458167D02*
Y460667D01*
X306008D01*
X306342Y460542D01*
X306550Y460375D01*
X306633Y460042D01*
X306550Y459709D01*
X306300Y459500D01*
X306008Y459375D01*
X304967D01*
G01X306008D02*
X306633Y458167D01*
G01X308192Y458459D02*
X308483Y458250D01*
X308817Y458167D01*
X309150Y458250D01*
X309442Y458500D01*
X309650Y458875D01*
X309733Y459250D01*
Y459709D01*
X309650Y460084D01*
X309442Y460417D01*
X309192Y460584D01*
X308900Y460667D01*
X308567Y460584D01*
X308317Y460417D01*
X308150Y460167D01*
X308067Y459834D01*
X308150Y459542D01*
X308358Y459250D01*
X308608Y459084D01*
X308900Y459042D01*
X309233Y459125D01*
X309483Y459334D01*
X309733Y459709D01*
G01X311208Y459209D02*
X311500Y459500D01*
X311750Y459667D01*
X312083Y459750D01*
X312375Y459667D01*
X312583Y459500D01*
X312750Y459250D01*
X312792Y458959D01*
X312750Y458709D01*
X312583Y458459D01*
X312333Y458250D01*
X312042Y458167D01*
X311708Y458250D01*
X311417Y458500D01*
X311250Y458875D01*
X311208Y459292D01*
X311292Y459834D01*
X311417Y460125D01*
X311625Y460417D01*
X311917Y460625D01*
X312208Y460667D01*
X312500Y460584D01*
X312708Y460375D01*
G01X315100Y458167D02*
Y460667D01*
X314600Y460167D01*
G01Y458167D02*
X315600D01*
G01X317283Y458542D02*
X317533Y458334D01*
X317825Y458209D01*
X318200Y458167D01*
X318575Y458250D01*
X318867Y458417D01*
X319075Y458709D01*
X319117Y459042D01*
X319033Y459375D01*
X318825Y459584D01*
X318533Y459750D01*
X318242Y459792D01*
X317950Y459750D01*
X317575Y459584D01*
X317700Y460667D01*
X318825D01*
G01X321619Y458224D02*
Y460724D01*
X322660D01*
X322994Y460599D01*
X323202Y460432D01*
X323285Y460099D01*
X323202Y459766D01*
X322952Y459557D01*
X322660Y459432D01*
X321619D01*
G01X322660D02*
X323285Y458224D01*
G01X324844Y458516D02*
X325135Y458307D01*
X325469Y458224D01*
X325802Y458307D01*
X326094Y458557D01*
X326302Y458932D01*
X326385Y459307D01*
Y459766D01*
X326302Y460141D01*
X326094Y460474D01*
X325844Y460641D01*
X325552Y460724D01*
X325219Y460641D01*
X324969Y460474D01*
X324802Y460224D01*
X324719Y459891D01*
X324802Y459599D01*
X325010Y459307D01*
X325260Y459141D01*
X325552Y459099D01*
X325885Y459182D01*
X326135Y459391D01*
X326385Y459766D01*
G01X327860Y459266D02*
X328152Y459557D01*
X328402Y459724D01*
X328735Y459807D01*
X329027Y459724D01*
X329235Y459557D01*
X329402Y459307D01*
X329444Y459016D01*
X329402Y458766D01*
X329235Y458516D01*
X328985Y458307D01*
X328694Y458224D01*
X328360Y458307D01*
X328069Y458557D01*
X327902Y458932D01*
X327860Y459349D01*
X327944Y459891D01*
X328069Y460182D01*
X328277Y460474D01*
X328569Y460682D01*
X328860Y460724D01*
X329152Y460641D01*
X329360Y460432D01*
G01X331752Y458224D02*
Y460724D01*
X331252Y460224D01*
G01Y458224D02*
X332252D01*
G01X335352D02*
Y460724D01*
X333810Y458932D01*
X335894D01*
G01X265058Y429900D02*
Y432400D01*
X266642D01*
G01X266058Y431192D02*
X265058D01*
G01X269283Y431233D02*
X269450Y431358D01*
X269575Y431567D01*
X269658Y431858D01*
X269575Y432108D01*
X269408Y432275D01*
X269117Y432400D01*
X267992D01*
Y429900D01*
X269367D01*
X269658Y430067D01*
X269825Y430317D01*
X269908Y430608D01*
X269825Y430900D01*
X269575Y431150D01*
X269283Y431233D01*
X267992D01*
G01X272050Y429900D02*
Y432400D01*
X271550Y431900D01*
G01Y429900D02*
X272550D01*
G01X275150Y432400D02*
X274817Y432317D01*
X274567Y432108D01*
X274400Y431858D01*
X274275Y431525D01*
X274233Y431150D01*
X274275Y430775D01*
X274400Y430442D01*
X274567Y430192D01*
X274817Y429983D01*
X275150Y429900D01*
X275483Y429983D01*
X275733Y430192D01*
X275900Y430442D01*
X276025Y430775D01*
X276067Y431150D01*
X276025Y431525D01*
X275900Y431858D01*
X275733Y432108D01*
X275483Y432317D01*
X275150Y432400D01*
G01X304700Y419100D02*
Y426100D01*
X318100D01*
Y419100D01*
X304700D01*
G01X266767Y428192D02*
X266517Y428317D01*
X266225Y428400D01*
X265892D01*
X265517Y428275D01*
X265225Y428067D01*
X265017Y427817D01*
X264850Y427400D01*
X264808Y427025D01*
X264892Y426650D01*
X265017Y426400D01*
X265267Y426150D01*
X265558Y425983D01*
X265850Y425900D01*
X266142D01*
X266433Y425983D01*
X266683Y426108D01*
X266892Y426275D01*
G01X268950Y425900D02*
X269242Y425942D01*
X269575Y426067D01*
X269783Y426275D01*
X269867Y426567D01*
X269783Y426858D01*
X269533Y427108D01*
X269158Y427233D01*
X268742D01*
X268492Y427317D01*
X268283Y427525D01*
X268200Y427817D01*
X268325Y428108D01*
X268617Y428317D01*
X268950Y428400D01*
X269283Y428317D01*
X269575Y428108D01*
X269700Y427817D01*
X269617Y427525D01*
X269408Y427317D01*
X269158Y427233D01*
X268742D01*
X268367Y427108D01*
X268117Y426858D01*
X268033Y426567D01*
X268117Y426275D01*
X268325Y426067D01*
X268658Y425942D01*
X268950Y425900D01*
G01X271342Y426192D02*
X271633Y425983D01*
X271967Y425900D01*
X272300Y425983D01*
X272592Y426233D01*
X272800Y426608D01*
X272883Y426983D01*
Y427442D01*
X272800Y427817D01*
X272592Y428150D01*
X272342Y428317D01*
X272050Y428400D01*
X271717Y428317D01*
X271467Y428150D01*
X271300Y427900D01*
X271217Y427567D01*
X271300Y427275D01*
X271508Y426983D01*
X271758Y426817D01*
X272050Y426775D01*
X272383Y426858D01*
X272633Y427067D01*
X272883Y427442D01*
G01X274233Y426400D02*
X274483Y426108D01*
X274817Y425942D01*
X275192Y425900D01*
X275525Y425942D01*
X275858Y426150D01*
X276067Y426400D01*
X276108Y426650D01*
X276025Y426942D01*
X275733Y427150D01*
X275442Y427233D01*
X275067D01*
G01X275442D02*
X275692Y427358D01*
X275900Y427567D01*
X275983Y427817D01*
X275900Y428067D01*
X275692Y428275D01*
X275317Y428400D01*
X274942Y428358D01*
X274567Y428192D01*
G01X277333Y426275D02*
X277583Y426067D01*
X277875Y425942D01*
X278250Y425900D01*
X278625Y425983D01*
X278917Y426150D01*
X279125Y426442D01*
X279167Y426775D01*
X279083Y427108D01*
X278875Y427317D01*
X278583Y427483D01*
X278292Y427525D01*
X278000Y427483D01*
X277625Y427317D01*
X277750Y428400D01*
X278875D01*
G01X324400Y550375D02*
X324608Y550708D01*
X324733Y551083D01*
Y551417D01*
X324608Y551750D01*
X324400Y552000D01*
X324108Y552125D01*
X323816Y552042D01*
X323566Y551833D01*
X323400Y551458D01*
X323316Y550958D01*
X323150Y550667D01*
X322858Y550542D01*
X322566Y550625D01*
X322358Y550833D01*
X322233Y551125D01*
Y551417D01*
X322316Y551708D01*
X322525Y551958D01*
G01X324733Y553517D02*
X322233D01*
Y554558D01*
X322358Y554892D01*
X322525Y555100D01*
X322858Y555183D01*
X323191Y555100D01*
X323400Y554850D01*
X323525Y554558D01*
Y553517D01*
G01Y554558D02*
X324733Y555183D01*
G01Y557450D02*
X322233D01*
X322733Y556950D01*
G01X324733D02*
Y557950D01*
G01X322233Y560550D02*
X322316Y560217D01*
X322525Y559967D01*
X322775Y559800D01*
X323108Y559675D01*
X323483Y559633D01*
X323858Y559675D01*
X324191Y559800D01*
X324441Y559967D01*
X324650Y560217D01*
X324733Y560550D01*
X324650Y560883D01*
X324441Y561133D01*
X324191Y561300D01*
X323858Y561425D01*
X323483Y561467D01*
X323108Y561425D01*
X322775Y561300D01*
X322525Y561133D01*
X322316Y560883D01*
X322233Y560550D01*
G01X324733Y564150D02*
X322233D01*
X324025Y562608D01*
Y564692D01*
G01X323691Y565958D02*
X323400Y566250D01*
X323233Y566500D01*
X323150Y566833D01*
X323233Y567125D01*
X323400Y567333D01*
X323650Y567500D01*
X323941Y567542D01*
X324191Y567500D01*
X324441Y567333D01*
X324650Y567083D01*
X324733Y566792D01*
X324650Y566458D01*
X324400Y566167D01*
X324025Y566000D01*
X323608Y565958D01*
X323066Y566042D01*
X322775Y566167D01*
X322483Y566375D01*
X322275Y566667D01*
X322233Y566958D01*
X322316Y567250D01*
X322525Y567458D01*
G01X287667Y551925D02*
X287875Y552258D01*
X288000Y552633D01*
Y552967D01*
X287875Y553300D01*
X287667Y553550D01*
X287375Y553675D01*
X287083Y553592D01*
X286833Y553383D01*
X286667Y553008D01*
X286583Y552508D01*
X286417Y552217D01*
X286125Y552092D01*
X285833Y552175D01*
X285625Y552383D01*
X285500Y552675D01*
Y552967D01*
X285583Y553258D01*
X285792Y553508D01*
G01X288000Y555067D02*
X285500D01*
Y556108D01*
X285625Y556442D01*
X285792Y556650D01*
X286125Y556733D01*
X286458Y556650D01*
X286667Y556400D01*
X286792Y556108D01*
Y555067D01*
G01Y556108D02*
X288000Y556733D01*
G01X287708Y558292D02*
X287917Y558583D01*
X288000Y558917D01*
X287917Y559250D01*
X287667Y559542D01*
X287292Y559750D01*
X286917Y559833D01*
X286458D01*
X286083Y559750D01*
X285750Y559542D01*
X285583Y559292D01*
X285500Y559000D01*
X285583Y558667D01*
X285750Y558417D01*
X286000Y558250D01*
X286333Y558167D01*
X286625Y558250D01*
X286917Y558458D01*
X287083Y558708D01*
X287125Y559000D01*
X287042Y559333D01*
X286833Y559583D01*
X286458Y559833D01*
G01X286958Y561308D02*
X286667Y561600D01*
X286500Y561850D01*
X286417Y562183D01*
X286500Y562475D01*
X286667Y562683D01*
X286917Y562850D01*
X287208Y562892D01*
X287458Y562850D01*
X287708Y562683D01*
X287917Y562433D01*
X288000Y562142D01*
X287917Y561808D01*
X287667Y561517D01*
X287292Y561350D01*
X286875Y561308D01*
X286333Y561392D01*
X286042Y561517D01*
X285750Y561725D01*
X285542Y562017D01*
X285500Y562308D01*
X285583Y562600D01*
X285792Y562808D01*
G01X288000Y565700D02*
X285500D01*
X287292Y564158D01*
Y566242D01*
G01X303667Y552425D02*
X303875Y552758D01*
X304000Y553133D01*
Y553467D01*
X303875Y553800D01*
X303667Y554050D01*
X303375Y554175D01*
X303083Y554092D01*
X302833Y553883D01*
X302667Y553508D01*
X302583Y553008D01*
X302417Y552717D01*
X302125Y552592D01*
X301833Y552675D01*
X301625Y552883D01*
X301500Y553175D01*
Y553467D01*
X301583Y553758D01*
X301792Y554008D01*
G01X304000Y555567D02*
X301500D01*
Y556608D01*
X301625Y556942D01*
X301792Y557150D01*
X302125Y557233D01*
X302458Y557150D01*
X302667Y556900D01*
X302792Y556608D01*
Y555567D01*
G01Y556608D02*
X304000Y557233D01*
G01X303708Y558792D02*
X303917Y559083D01*
X304000Y559417D01*
X303917Y559750D01*
X303667Y560042D01*
X303292Y560250D01*
X302917Y560333D01*
X302458D01*
X302083Y560250D01*
X301750Y560042D01*
X301583Y559792D01*
X301500Y559500D01*
X301583Y559167D01*
X301750Y558917D01*
X302000Y558750D01*
X302333Y558667D01*
X302625Y558750D01*
X302917Y558958D01*
X303083Y559208D01*
X303125Y559500D01*
X303042Y559833D01*
X302833Y560083D01*
X302458Y560333D01*
G01X302958Y561808D02*
X302667Y562100D01*
X302500Y562350D01*
X302417Y562683D01*
X302500Y562975D01*
X302667Y563183D01*
X302917Y563350D01*
X303208Y563392D01*
X303458Y563350D01*
X303708Y563183D01*
X303917Y562933D01*
X304000Y562642D01*
X303917Y562308D01*
X303667Y562017D01*
X303292Y561850D01*
X302875Y561808D01*
X302333Y561892D01*
X302042Y562017D01*
X301750Y562225D01*
X301542Y562517D01*
X301500Y562808D01*
X301583Y563100D01*
X301792Y563308D01*
G01X303625Y564783D02*
X303833Y565033D01*
X303958Y565325D01*
X304000Y565700D01*
X303917Y566075D01*
X303750Y566367D01*
X303458Y566575D01*
X303125Y566617D01*
X302792Y566533D01*
X302583Y566325D01*
X302417Y566033D01*
X302375Y565742D01*
X302417Y565450D01*
X302583Y565075D01*
X301500Y565200D01*
Y566325D01*
G01X328601Y550575D02*
X328809Y550908D01*
X328934Y551283D01*
Y551617D01*
X328809Y551950D01*
X328601Y552200D01*
X328309Y552325D01*
X328017Y552242D01*
X327767Y552033D01*
X327601Y551658D01*
X327517Y551158D01*
X327351Y550867D01*
X327059Y550742D01*
X326767Y550825D01*
X326559Y551033D01*
X326434Y551325D01*
Y551617D01*
X326517Y551908D01*
X326726Y552158D01*
G01X328934Y553717D02*
X326434D01*
Y554758D01*
X326559Y555092D01*
X326726Y555300D01*
X327059Y555383D01*
X327392Y555300D01*
X327601Y555050D01*
X327726Y554758D01*
Y553717D01*
G01Y554758D02*
X328934Y555383D01*
G01Y557650D02*
X326434D01*
X326934Y557150D01*
G01X328934D02*
Y558150D01*
G01Y560750D02*
X326434D01*
X326934Y560250D01*
G01X328934D02*
Y561250D01*
G01X328559Y562933D02*
X328767Y563183D01*
X328892Y563475D01*
X328934Y563850D01*
X328851Y564225D01*
X328684Y564517D01*
X328392Y564725D01*
X328059Y564767D01*
X327726Y564683D01*
X327517Y564475D01*
X327351Y564183D01*
X327309Y563892D01*
X327351Y563600D01*
X327517Y563225D01*
X326434Y563350D01*
Y564475D01*
G01X326851Y566158D02*
X326601Y566408D01*
X326476Y566700D01*
X326434Y567033D01*
X326517Y567450D01*
X326726Y567742D01*
X326976Y567825D01*
X327226Y567783D01*
X327434Y567617D01*
X327851Y566783D01*
X328142Y566408D01*
X328559Y566158D01*
X328934Y566075D01*
Y567825D01*
G01X323800Y611000D02*
Y607000D01*
X331200D01*
G01X334700Y568580D02*
Y572580D01*
X327300D01*
G01X334700Y576600D02*
Y580600D01*
X327300D01*
G01X331200Y603000D02*
Y607000D01*
X323800D01*
G01X315000Y567700D02*
X311000D01*
Y560300D01*
G01X323800Y599000D02*
Y595000D01*
X331200D01*
G01Y591000D02*
Y595000D01*
X323800D01*
G01X288580Y560300D02*
X292580D01*
Y567700D01*
G01X296450Y560300D02*
X300450D01*
Y567700D01*
G01X274800Y575000D02*
Y571000D01*
X282200D01*
G01X274800Y567000D02*
Y563000D01*
X282200D01*
G01X274800Y587000D02*
Y583000D01*
X282200D01*
G01X274800Y579000D02*
Y575000D01*
X282200D01*
G01X274800Y599000D02*
Y595000D01*
X282200D01*
G01X291477Y618055D02*
X291685Y618388D01*
X291810Y618763D01*
Y619097D01*
X291685Y619430D01*
X291477Y619680D01*
X291185Y619805D01*
X290893Y619722D01*
X290643Y619513D01*
X290477Y619138D01*
X290393Y618638D01*
X290227Y618347D01*
X289935Y618222D01*
X289643Y618305D01*
X289435Y618513D01*
X289310Y618805D01*
Y619097D01*
X289393Y619388D01*
X289602Y619638D01*
G01X291810Y621197D02*
X289310D01*
Y622238D01*
X289435Y622572D01*
X289602Y622780D01*
X289935Y622863D01*
X290268Y622780D01*
X290477Y622530D01*
X290602Y622238D01*
Y621197D01*
G01Y622238D02*
X291810Y622863D01*
G01X291518Y624422D02*
X291727Y624713D01*
X291810Y625047D01*
X291727Y625380D01*
X291477Y625672D01*
X291102Y625880D01*
X290727Y625963D01*
X290268D01*
X289893Y625880D01*
X289560Y625672D01*
X289393Y625422D01*
X289310Y625130D01*
X289393Y624797D01*
X289560Y624547D01*
X289810Y624380D01*
X290143Y624297D01*
X290435Y624380D01*
X290727Y624588D01*
X290893Y624838D01*
X290935Y625130D01*
X290852Y625463D01*
X290643Y625713D01*
X290268Y625963D01*
G01X291810Y628147D02*
X291268Y628230D01*
X290810Y628355D01*
X290393Y628522D01*
X289935Y628730D01*
X289310Y629063D01*
Y627397D01*
G01X291810Y631330D02*
X289310D01*
X289810Y630830D01*
G01X291810D02*
Y631830D01*
G01X294000Y610700D02*
X290000D01*
Y603300D01*
G01X274800Y591000D02*
Y587000D01*
X282200D01*
G01X279667Y601925D02*
X279875Y602258D01*
X280000Y602633D01*
Y602967D01*
X279875Y603300D01*
X279667Y603550D01*
X279375Y603675D01*
X279083Y603592D01*
X278833Y603383D01*
X278667Y603008D01*
X278583Y602508D01*
X278417Y602217D01*
X278125Y602092D01*
X277833Y602175D01*
X277625Y602383D01*
X277500Y602675D01*
Y602967D01*
X277583Y603258D01*
X277792Y603508D01*
G01X280000Y605067D02*
X277500D01*
Y606108D01*
X277625Y606442D01*
X277792Y606650D01*
X278125Y606733D01*
X278458Y606650D01*
X278667Y606400D01*
X278792Y606108D01*
Y605067D01*
G01Y606108D02*
X280000Y606733D01*
G01X279708Y608292D02*
X279917Y608583D01*
X280000Y608917D01*
X279917Y609250D01*
X279667Y609542D01*
X279292Y609750D01*
X278917Y609833D01*
X278458D01*
X278083Y609750D01*
X277750Y609542D01*
X277583Y609292D01*
X277500Y609000D01*
X277583Y608667D01*
X277750Y608417D01*
X278000Y608250D01*
X278333Y608167D01*
X278625Y608250D01*
X278917Y608458D01*
X279083Y608708D01*
X279125Y609000D01*
X279042Y609333D01*
X278833Y609583D01*
X278458Y609833D01*
G01X280000Y612017D02*
X279458Y612100D01*
X279000Y612225D01*
X278583Y612392D01*
X278125Y612600D01*
X277500Y612933D01*
Y611267D01*
G01X279500Y614283D02*
X279792Y614533D01*
X279958Y614867D01*
X280000Y615242D01*
X279958Y615575D01*
X279750Y615908D01*
X279500Y616117D01*
X279250Y616158D01*
X278958Y616075D01*
X278750Y615783D01*
X278667Y615492D01*
Y615117D01*
G01Y615492D02*
X278542Y615742D01*
X278333Y615950D01*
X278083Y616033D01*
X277833Y615950D01*
X277625Y615742D01*
X277500Y615367D01*
X277542Y614992D01*
X277708Y614617D01*
G01X286000Y610700D02*
X282000D01*
Y603300D01*
G01X305977Y617555D02*
X306185Y617888D01*
X306310Y618263D01*
Y618597D01*
X306185Y618930D01*
X305977Y619180D01*
X305685Y619305D01*
X305393Y619222D01*
X305143Y619013D01*
X304977Y618638D01*
X304893Y618138D01*
X304727Y617847D01*
X304435Y617722D01*
X304143Y617805D01*
X303935Y618013D01*
X303810Y618305D01*
Y618597D01*
X303893Y618888D01*
X304102Y619138D01*
G01X306310Y620697D02*
X303810D01*
Y621738D01*
X303935Y622072D01*
X304102Y622280D01*
X304435Y622363D01*
X304768Y622280D01*
X304977Y622030D01*
X305102Y621738D01*
Y620697D01*
G01Y621738D02*
X306310Y622363D01*
G01X306018Y623922D02*
X306227Y624213D01*
X306310Y624547D01*
X306227Y624880D01*
X305977Y625172D01*
X305602Y625380D01*
X305227Y625463D01*
X304768D01*
X304393Y625380D01*
X304060Y625172D01*
X303893Y624922D01*
X303810Y624630D01*
X303893Y624297D01*
X304060Y624047D01*
X304310Y623880D01*
X304643Y623797D01*
X304935Y623880D01*
X305227Y624088D01*
X305393Y624338D01*
X305435Y624630D01*
X305352Y624963D01*
X305143Y625213D01*
X304768Y625463D01*
G01X306310Y627647D02*
X305768Y627730D01*
X305310Y627855D01*
X304893Y628022D01*
X304435Y628230D01*
X303810Y628563D01*
Y626897D01*
G01X306310Y631330D02*
X303810D01*
X305602Y629788D01*
Y631872D01*
G01X306000Y610700D02*
X302000D01*
Y603300D01*
G01X295477Y618055D02*
X295685Y618388D01*
X295810Y618763D01*
Y619097D01*
X295685Y619430D01*
X295477Y619680D01*
X295185Y619805D01*
X294893Y619722D01*
X294643Y619513D01*
X294477Y619138D01*
X294393Y618638D01*
X294227Y618347D01*
X293935Y618222D01*
X293643Y618305D01*
X293435Y618513D01*
X293310Y618805D01*
Y619097D01*
X293393Y619388D01*
X293602Y619638D01*
G01X295810Y621197D02*
X293310D01*
Y622238D01*
X293435Y622572D01*
X293602Y622780D01*
X293935Y622863D01*
X294268Y622780D01*
X294477Y622530D01*
X294602Y622238D01*
Y621197D01*
G01Y622238D02*
X295810Y622863D01*
G01X295518Y624422D02*
X295727Y624713D01*
X295810Y625047D01*
X295727Y625380D01*
X295477Y625672D01*
X295102Y625880D01*
X294727Y625963D01*
X294268D01*
X293893Y625880D01*
X293560Y625672D01*
X293393Y625422D01*
X293310Y625130D01*
X293393Y624797D01*
X293560Y624547D01*
X293810Y624380D01*
X294143Y624297D01*
X294435Y624380D01*
X294727Y624588D01*
X294893Y624838D01*
X294935Y625130D01*
X294852Y625463D01*
X294643Y625713D01*
X294268Y625963D01*
G01X295810Y628147D02*
X295268Y628230D01*
X294810Y628355D01*
X294393Y628522D01*
X293935Y628730D01*
X293310Y629063D01*
Y627397D01*
G01X295435Y630413D02*
X295643Y630663D01*
X295768Y630955D01*
X295810Y631330D01*
X295727Y631705D01*
X295560Y631997D01*
X295268Y632205D01*
X294935Y632247D01*
X294602Y632163D01*
X294393Y631955D01*
X294227Y631663D01*
X294185Y631372D01*
X294227Y631080D01*
X294393Y630705D01*
X293310Y630830D01*
Y631955D01*
G01X298000Y610700D02*
X294000D01*
Y603300D01*
G01X318167Y614425D02*
X318375Y614758D01*
X318500Y615133D01*
Y615467D01*
X318375Y615800D01*
X318167Y616050D01*
X317875Y616175D01*
X317583Y616092D01*
X317333Y615883D01*
X317167Y615508D01*
X317083Y615008D01*
X316917Y614717D01*
X316625Y614592D01*
X316333Y614675D01*
X316125Y614883D01*
X316000Y615175D01*
Y615467D01*
X316083Y615758D01*
X316292Y616008D01*
G01X318500Y617567D02*
X316000D01*
Y618608D01*
X316125Y618942D01*
X316292Y619150D01*
X316625Y619233D01*
X316958Y619150D01*
X317167Y618900D01*
X317292Y618608D01*
Y617567D01*
G01Y618608D02*
X318500Y619233D01*
G01X318208Y620792D02*
X318417Y621083D01*
X318500Y621417D01*
X318417Y621750D01*
X318167Y622042D01*
X317792Y622250D01*
X317417Y622333D01*
X316958D01*
X316583Y622250D01*
X316250Y622042D01*
X316083Y621792D01*
X316000Y621500D01*
X316083Y621167D01*
X316250Y620917D01*
X316500Y620750D01*
X316833Y620667D01*
X317125Y620750D01*
X317417Y620958D01*
X317583Y621208D01*
X317625Y621500D01*
X317542Y621833D01*
X317333Y622083D01*
X316958Y622333D01*
G01X318500Y624517D02*
X317958Y624600D01*
X317500Y624725D01*
X317083Y624892D01*
X316625Y625100D01*
X316000Y625433D01*
Y623767D01*
G01X317458Y626908D02*
X317167Y627200D01*
X317000Y627450D01*
X316917Y627783D01*
X317000Y628075D01*
X317167Y628283D01*
X317417Y628450D01*
X317708Y628492D01*
X317958Y628450D01*
X318208Y628283D01*
X318417Y628033D01*
X318500Y627742D01*
X318417Y627408D01*
X318167Y627117D01*
X317792Y626950D01*
X317375Y626908D01*
X316833Y626992D01*
X316542Y627117D01*
X316250Y627325D01*
X316042Y627617D01*
X316000Y627908D01*
X316083Y628200D01*
X316292Y628408D01*
G01X318000Y610700D02*
X314000D01*
Y603300D01*
G01X309977Y617555D02*
X310185Y617888D01*
X310310Y618263D01*
Y618597D01*
X310185Y618930D01*
X309977Y619180D01*
X309685Y619305D01*
X309393Y619222D01*
X309143Y619013D01*
X308977Y618638D01*
X308893Y618138D01*
X308727Y617847D01*
X308435Y617722D01*
X308143Y617805D01*
X307935Y618013D01*
X307810Y618305D01*
Y618597D01*
X307893Y618888D01*
X308102Y619138D01*
G01X310310Y620697D02*
X307810D01*
Y621738D01*
X307935Y622072D01*
X308102Y622280D01*
X308435Y622363D01*
X308768Y622280D01*
X308977Y622030D01*
X309102Y621738D01*
Y620697D01*
G01Y621738D02*
X310310Y622363D01*
G01X310018Y623922D02*
X310227Y624213D01*
X310310Y624547D01*
X310227Y624880D01*
X309977Y625172D01*
X309602Y625380D01*
X309227Y625463D01*
X308768D01*
X308393Y625380D01*
X308060Y625172D01*
X307893Y624922D01*
X307810Y624630D01*
X307893Y624297D01*
X308060Y624047D01*
X308310Y623880D01*
X308643Y623797D01*
X308935Y623880D01*
X309227Y624088D01*
X309393Y624338D01*
X309435Y624630D01*
X309352Y624963D01*
X309143Y625213D01*
X308768Y625463D01*
G01X310310Y627647D02*
X309768Y627730D01*
X309310Y627855D01*
X308893Y628022D01*
X308435Y628230D01*
X307810Y628563D01*
Y626897D01*
G01X310310Y630747D02*
X309768Y630830D01*
X309310Y630955D01*
X308893Y631122D01*
X308435Y631330D01*
X307810Y631663D01*
Y629997D01*
G01X310000Y610700D02*
X306000D01*
Y603300D01*
G01X325700Y570500D02*
Y574500D01*
X318300D01*
G01X325700D02*
Y578500D01*
X318300D01*
G01X323800Y591000D02*
Y587000D01*
X331200D01*
G01X315500Y560300D02*
X319500D01*
Y567700D01*
G01X331200Y599000D02*
Y603000D01*
X323800D01*
G01X286683Y569500D02*
X285017D01*
Y572000D01*
X286683D01*
G01X286017Y570792D02*
X285017D01*
G01X288033Y572000D02*
Y570208D01*
X288200Y569833D01*
X288533Y569583D01*
X288950Y569500D01*
X289367Y569583D01*
X289700Y569833D01*
X289867Y570208D01*
Y572000D01*
G01X292050Y569500D02*
Y572000D01*
X291550Y571500D01*
G01Y569500D02*
X292550D01*
G01X294358Y570542D02*
X294650Y570833D01*
X294900Y571000D01*
X295233Y571083D01*
X295525Y571000D01*
X295733Y570833D01*
X295900Y570583D01*
X295942Y570292D01*
X295900Y570042D01*
X295733Y569792D01*
X295483Y569583D01*
X295192Y569500D01*
X294858Y569583D01*
X294567Y569833D01*
X294400Y570208D01*
X294358Y570625D01*
X294442Y571167D01*
X294567Y571458D01*
X294775Y571750D01*
X295067Y571958D01*
X295358Y572000D01*
X295650Y571917D01*
X295858Y571708D01*
G01X311100Y582500D02*
X314100D01*
G01X286100Y584500D02*
X289100D01*
G01X299000Y572500D02*
Y574500D01*
G01X297100Y596500D02*
Y598500D01*
G01X306900Y573600D02*
X311900D01*
Y578600D01*
G01X288100D02*
Y573600D01*
X293100D01*
G01X288100Y592400D02*
Y597400D01*
X293100D01*
G01X316407Y773691D02*
Y776191D01*
X317448D01*
X317782Y776066D01*
X317990Y775899D01*
X318073Y775566D01*
X317990Y775233D01*
X317740Y775024D01*
X317448Y774899D01*
X316407D01*
G01X317448D02*
X318073Y773691D01*
G01X319632Y773983D02*
X319923Y773774D01*
X320257Y773691D01*
X320590Y773774D01*
X320882Y774024D01*
X321090Y774399D01*
X321173Y774774D01*
Y775233D01*
X321090Y775608D01*
X320882Y775941D01*
X320632Y776108D01*
X320340Y776191D01*
X320007Y776108D01*
X319757Y775941D01*
X319590Y775691D01*
X319507Y775358D01*
X319590Y775066D01*
X319798Y774774D01*
X320048Y774608D01*
X320340Y774566D01*
X320673Y774649D01*
X320923Y774858D01*
X321173Y775233D01*
G01X323440Y773691D02*
Y776191D01*
X322940Y775691D01*
G01Y773691D02*
X323940D01*
G01X326540D02*
Y776191D01*
X326040Y775691D01*
G01Y773691D02*
X327040D01*
G01X329640D02*
X329932Y773733D01*
X330265Y773858D01*
X330473Y774066D01*
X330557Y774358D01*
X330473Y774649D01*
X330223Y774899D01*
X329848Y775024D01*
X329432D01*
X329182Y775108D01*
X328973Y775316D01*
X328890Y775608D01*
X329015Y775899D01*
X329307Y776108D01*
X329640Y776191D01*
X329973Y776108D01*
X330265Y775899D01*
X330390Y775608D01*
X330307Y775316D01*
X330098Y775108D01*
X329848Y775024D01*
X329432D01*
X329057Y774899D01*
X328807Y774649D01*
X328723Y774358D01*
X328807Y774066D01*
X329015Y773858D01*
X329348Y773733D01*
X329640Y773691D01*
G01X273975Y707967D02*
Y710467D01*
G01X275725D02*
Y707967D01*
G01Y709217D02*
X273975D01*
G01X277867Y707967D02*
X277950Y708509D01*
X278075Y708967D01*
X278242Y709384D01*
X278450Y709842D01*
X278783Y710467D01*
X277117D01*
G01X295948Y831927D02*
X295823Y831677D01*
X295740Y831385D01*
Y831052D01*
X295865Y830677D01*
X296073Y830385D01*
X296323Y830177D01*
X296740Y830010D01*
X297115Y829968D01*
X297490Y830052D01*
X297740Y830177D01*
X297990Y830427D01*
X298157Y830718D01*
X298240Y831010D01*
Y831302D01*
X298157Y831593D01*
X298032Y831843D01*
X297865Y832052D01*
G01X298240Y834110D02*
X298198Y834402D01*
X298073Y834735D01*
X297865Y834943D01*
X297573Y835027D01*
X297282Y834943D01*
X297032Y834693D01*
X296907Y834318D01*
Y833902D01*
X296823Y833652D01*
X296615Y833443D01*
X296323Y833360D01*
X296032Y833485D01*
X295823Y833777D01*
X295740Y834110D01*
X295823Y834443D01*
X296032Y834735D01*
X296323Y834860D01*
X296615Y834777D01*
X296823Y834568D01*
X296907Y834318D01*
Y833902D01*
X297032Y833527D01*
X297282Y833277D01*
X297573Y833193D01*
X297865Y833277D01*
X298073Y833485D01*
X298198Y833818D01*
X298240Y834110D01*
G01X297948Y836502D02*
X298157Y836793D01*
X298240Y837127D01*
X298157Y837460D01*
X297907Y837752D01*
X297532Y837960D01*
X297157Y838043D01*
X296698D01*
X296323Y837960D01*
X295990Y837752D01*
X295823Y837502D01*
X295740Y837210D01*
X295823Y836877D01*
X295990Y836627D01*
X296240Y836460D01*
X296573Y836377D01*
X296865Y836460D01*
X297157Y836668D01*
X297323Y836918D01*
X297365Y837210D01*
X297282Y837543D01*
X297073Y837793D01*
X296698Y838043D01*
G01X298240Y840310D02*
X295740D01*
X296240Y839810D01*
G01X298240D02*
Y840810D01*
G01X297198Y842618D02*
X296907Y842910D01*
X296740Y843160D01*
X296657Y843493D01*
X296740Y843785D01*
X296907Y843993D01*
X297157Y844160D01*
X297448Y844202D01*
X297698Y844160D01*
X297948Y843993D01*
X298157Y843743D01*
X298240Y843452D01*
X298157Y843118D01*
X297907Y842827D01*
X297532Y842660D01*
X297115Y842618D01*
X296573Y842702D01*
X296282Y842827D01*
X295990Y843035D01*
X295782Y843327D01*
X295740Y843618D01*
X295823Y843910D01*
X296032Y844118D01*
G01X299837Y832107D02*
X299712Y831857D01*
X299629Y831565D01*
Y831232D01*
X299754Y830857D01*
X299962Y830565D01*
X300212Y830357D01*
X300629Y830190D01*
X301004Y830148D01*
X301379Y830232D01*
X301629Y830357D01*
X301879Y830607D01*
X302046Y830898D01*
X302129Y831190D01*
Y831482D01*
X302046Y831773D01*
X301921Y832023D01*
X301754Y832232D01*
G01X302129Y834290D02*
X302087Y834582D01*
X301962Y834915D01*
X301754Y835123D01*
X301462Y835207D01*
X301171Y835123D01*
X300921Y834873D01*
X300796Y834498D01*
Y834082D01*
X300712Y833832D01*
X300504Y833623D01*
X300212Y833540D01*
X299921Y833665D01*
X299712Y833957D01*
X299629Y834290D01*
X299712Y834623D01*
X299921Y834915D01*
X300212Y835040D01*
X300504Y834957D01*
X300712Y834748D01*
X300796Y834498D01*
Y834082D01*
X300921Y833707D01*
X301171Y833457D01*
X301462Y833373D01*
X301754Y833457D01*
X301962Y833665D01*
X302087Y833998D01*
X302129Y834290D01*
G01X301837Y836682D02*
X302046Y836973D01*
X302129Y837307D01*
X302046Y837640D01*
X301796Y837932D01*
X301421Y838140D01*
X301046Y838223D01*
X300587D01*
X300212Y838140D01*
X299879Y837932D01*
X299712Y837682D01*
X299629Y837390D01*
X299712Y837057D01*
X299879Y836807D01*
X300129Y836640D01*
X300462Y836557D01*
X300754Y836640D01*
X301046Y836848D01*
X301212Y837098D01*
X301254Y837390D01*
X301171Y837723D01*
X300962Y837973D01*
X300587Y838223D01*
G01X300046Y839698D02*
X299796Y839948D01*
X299671Y840240D01*
X299629Y840573D01*
X299712Y840990D01*
X299921Y841282D01*
X300171Y841365D01*
X300421Y841323D01*
X300629Y841157D01*
X301046Y840323D01*
X301337Y839948D01*
X301754Y839698D01*
X302129Y839615D01*
Y841365D01*
G01X301837Y842882D02*
X302046Y843173D01*
X302129Y843507D01*
X302046Y843840D01*
X301796Y844132D01*
X301421Y844340D01*
X301046Y844423D01*
X300587D01*
X300212Y844340D01*
X299879Y844132D01*
X299712Y843882D01*
X299629Y843590D01*
X299712Y843257D01*
X299879Y843007D01*
X300129Y842840D01*
X300462Y842757D01*
X300754Y842840D01*
X301046Y843048D01*
X301212Y843298D01*
X301254Y843590D01*
X301171Y843923D01*
X300962Y844173D01*
X300587Y844423D01*
G01X316417Y777500D02*
Y780000D01*
X317417D01*
X317750Y779875D01*
X318000Y779583D01*
X318083Y779250D01*
X318000Y778917D01*
X317792Y778667D01*
X317417Y778542D01*
X316417D01*
G01X319517Y777500D02*
Y780000D01*
X320558D01*
X320892Y779875D01*
X321100Y779708D01*
X321183Y779375D01*
X321100Y779042D01*
X320850Y778833D01*
X320558Y778708D01*
X319517D01*
G01X320558D02*
X321183Y777500D01*
G01X322742Y777792D02*
X323033Y777583D01*
X323367Y777500D01*
X323700Y777583D01*
X323992Y777833D01*
X324200Y778208D01*
X324283Y778583D01*
Y779042D01*
X324200Y779417D01*
X323992Y779750D01*
X323742Y779917D01*
X323450Y780000D01*
X323117Y779917D01*
X322867Y779750D01*
X322700Y779500D01*
X322617Y779167D01*
X322700Y778875D01*
X322908Y778583D01*
X323158Y778417D01*
X323450Y778375D01*
X323783Y778458D01*
X324033Y778667D01*
X324283Y779042D01*
G01X326550Y780000D02*
X326217Y779917D01*
X325967Y779708D01*
X325800Y779458D01*
X325675Y779125D01*
X325633Y778750D01*
X325675Y778375D01*
X325800Y778042D01*
X325967Y777792D01*
X326217Y777583D01*
X326550Y777500D01*
X326883Y777583D01*
X327133Y777792D01*
X327300Y778042D01*
X327425Y778375D01*
X327467Y778750D01*
X327425Y779125D01*
X327300Y779458D01*
X327133Y779708D01*
X326883Y779917D01*
X326550Y780000D01*
G01X328733Y778000D02*
X328983Y777708D01*
X329317Y777542D01*
X329692Y777500D01*
X330025Y777542D01*
X330358Y777750D01*
X330567Y778000D01*
X330608Y778250D01*
X330525Y778542D01*
X330233Y778750D01*
X329942Y778833D01*
X329567D01*
G01X329942D02*
X330192Y778958D01*
X330400Y779167D01*
X330483Y779417D01*
X330400Y779667D01*
X330192Y779875D01*
X329817Y780000D01*
X329442Y779958D01*
X329067Y779792D01*
G01X332042Y777792D02*
X332333Y777583D01*
X332667Y777500D01*
X333000Y777583D01*
X333292Y777833D01*
X333500Y778208D01*
X333583Y778583D01*
Y779042D01*
X333500Y779417D01*
X333292Y779750D01*
X333042Y779917D01*
X332750Y780000D01*
X332417Y779917D01*
X332167Y779750D01*
X332000Y779500D01*
X331917Y779167D01*
X332000Y778875D01*
X332208Y778583D01*
X332458Y778417D01*
X332750Y778375D01*
X333083Y778458D01*
X333333Y778667D01*
X333583Y779042D01*
G01X328800Y809000D02*
Y805000D01*
X336200D01*
G01X316857Y797691D02*
Y800191D01*
X317857D01*
X318190Y800066D01*
X318440Y799774D01*
X318523Y799441D01*
X318440Y799108D01*
X318232Y798858D01*
X317857Y798733D01*
X316857D01*
G01X319957Y797691D02*
Y800191D01*
X320998D01*
X321332Y800066D01*
X321540Y799899D01*
X321623Y799566D01*
X321540Y799233D01*
X321290Y799024D01*
X320998Y798899D01*
X319957D01*
G01X320998D02*
X321623Y797691D01*
G01X323182Y797983D02*
X323473Y797774D01*
X323807Y797691D01*
X324140Y797774D01*
X324432Y798024D01*
X324640Y798399D01*
X324723Y798774D01*
Y799233D01*
X324640Y799608D01*
X324432Y799941D01*
X324182Y800108D01*
X323890Y800191D01*
X323557Y800108D01*
X323307Y799941D01*
X323140Y799691D01*
X323057Y799358D01*
X323140Y799066D01*
X323348Y798774D01*
X323598Y798608D01*
X323890Y798566D01*
X324223Y798649D01*
X324473Y798858D01*
X324723Y799233D01*
G01X326990Y800191D02*
X326657Y800108D01*
X326407Y799899D01*
X326240Y799649D01*
X326115Y799316D01*
X326073Y798941D01*
X326115Y798566D01*
X326240Y798233D01*
X326407Y797983D01*
X326657Y797774D01*
X326990Y797691D01*
X327323Y797774D01*
X327573Y797983D01*
X327740Y798233D01*
X327865Y798566D01*
X327907Y798941D01*
X327865Y799316D01*
X327740Y799649D01*
X327573Y799899D01*
X327323Y800108D01*
X326990Y800191D01*
G01X330590Y797691D02*
Y800191D01*
X329048Y798399D01*
X331132D01*
G01X333190Y800191D02*
X332857Y800108D01*
X332607Y799899D01*
X332440Y799649D01*
X332315Y799316D01*
X332273Y798941D01*
X332315Y798566D01*
X332440Y798233D01*
X332607Y797983D01*
X332857Y797774D01*
X333190Y797691D01*
X333523Y797774D01*
X333773Y797983D01*
X333940Y798233D01*
X334065Y798566D01*
X334107Y798941D01*
X334065Y799316D01*
X333940Y799649D01*
X333773Y799899D01*
X333523Y800108D01*
X333190Y800191D01*
G01X280367Y846700D02*
Y849200D01*
X281367D01*
X281700Y849075D01*
X281950Y848783D01*
X282033Y848450D01*
X281950Y848117D01*
X281742Y847867D01*
X281367Y847742D01*
X280367D01*
G01X283467Y846700D02*
Y849200D01*
X284508D01*
X284842Y849075D01*
X285050Y848908D01*
X285133Y848575D01*
X285050Y848242D01*
X284800Y848033D01*
X284508Y847908D01*
X283467D01*
G01X284508D02*
X285133Y846700D01*
G01X286692Y846992D02*
X286983Y846783D01*
X287317Y846700D01*
X287650Y846783D01*
X287942Y847033D01*
X288150Y847408D01*
X288233Y847783D01*
Y848242D01*
X288150Y848617D01*
X287942Y848950D01*
X287692Y849117D01*
X287400Y849200D01*
X287067Y849117D01*
X286817Y848950D01*
X286650Y848700D01*
X286567Y848367D01*
X286650Y848075D01*
X286858Y847783D01*
X287108Y847617D01*
X287400Y847575D01*
X287733Y847658D01*
X287983Y847867D01*
X288233Y848242D01*
G01X290500Y849200D02*
X290167Y849117D01*
X289917Y848908D01*
X289750Y848658D01*
X289625Y848325D01*
X289583Y847950D01*
X289625Y847575D01*
X289750Y847242D01*
X289917Y846992D01*
X290167Y846783D01*
X290500Y846700D01*
X290833Y846783D01*
X291083Y846992D01*
X291250Y847242D01*
X291375Y847575D01*
X291417Y847950D01*
X291375Y848325D01*
X291250Y848658D01*
X291083Y848908D01*
X290833Y849117D01*
X290500Y849200D01*
G01X292808Y847742D02*
X293100Y848033D01*
X293350Y848200D01*
X293683Y848283D01*
X293975Y848200D01*
X294183Y848033D01*
X294350Y847783D01*
X294392Y847492D01*
X294350Y847242D01*
X294183Y846992D01*
X293933Y846783D01*
X293642Y846700D01*
X293308Y846783D01*
X293017Y847033D01*
X292850Y847408D01*
X292808Y847825D01*
X292892Y848367D01*
X293017Y848658D01*
X293225Y848950D01*
X293517Y849158D01*
X293808Y849200D01*
X294100Y849117D01*
X294308Y848908D01*
G01X295783Y847200D02*
X296033Y846908D01*
X296367Y846742D01*
X296742Y846700D01*
X297075Y846742D01*
X297408Y846950D01*
X297617Y847200D01*
X297658Y847450D01*
X297575Y847742D01*
X297283Y847950D01*
X296992Y848033D01*
X296617D01*
G01X296992D02*
X297242Y848158D01*
X297450Y848367D01*
X297533Y848617D01*
X297450Y848867D01*
X297242Y849075D01*
X296867Y849200D01*
X296492Y849158D01*
X296117Y848992D01*
G01X330200Y841000D02*
Y845000D01*
X322800D01*
G01X336200Y801000D02*
Y805000D01*
X328800D01*
G01X316467Y793500D02*
Y796000D01*
X317508D01*
X317842Y795875D01*
X318050Y795708D01*
X318133Y795375D01*
X318050Y795042D01*
X317800Y794833D01*
X317508Y794708D01*
X316467D01*
G01X317508D02*
X318133Y793500D01*
G01X319692Y793792D02*
X319983Y793583D01*
X320317Y793500D01*
X320650Y793583D01*
X320942Y793833D01*
X321150Y794208D01*
X321233Y794583D01*
Y795042D01*
X321150Y795417D01*
X320942Y795750D01*
X320692Y795917D01*
X320400Y796000D01*
X320067Y795917D01*
X319817Y795750D01*
X319650Y795500D01*
X319567Y795167D01*
X319650Y794875D01*
X319858Y794583D01*
X320108Y794417D01*
X320400Y794375D01*
X320733Y794458D01*
X320983Y794667D01*
X321233Y795042D01*
G01X323500Y793500D02*
Y796000D01*
X323000Y795500D01*
G01Y793500D02*
X324000D01*
G01X326600D02*
Y796000D01*
X326100Y795500D01*
G01Y793500D02*
X327100D01*
G01X328992Y793792D02*
X329283Y793583D01*
X329617Y793500D01*
X329950Y793583D01*
X330242Y793833D01*
X330450Y794208D01*
X330533Y794583D01*
Y795042D01*
X330450Y795417D01*
X330242Y795750D01*
X329992Y795917D01*
X329700Y796000D01*
X329367Y795917D01*
X329117Y795750D01*
X328950Y795500D01*
X328867Y795167D01*
X328950Y794875D01*
X329158Y794583D01*
X329408Y794417D01*
X329700Y794375D01*
X330033Y794458D01*
X330283Y794667D01*
X330533Y795042D01*
G01X280325Y843033D02*
X280658Y842825D01*
X281033Y842700D01*
X281367D01*
X281700Y842825D01*
X281950Y843033D01*
X282075Y843325D01*
X281992Y843617D01*
X281783Y843867D01*
X281408Y844033D01*
X280908Y844117D01*
X280617Y844283D01*
X280492Y844575D01*
X280575Y844867D01*
X280783Y845075D01*
X281075Y845200D01*
X281367D01*
X281658Y845117D01*
X281908Y844908D01*
G01X283467Y842700D02*
Y845200D01*
X284508D01*
X284842Y845075D01*
X285050Y844908D01*
X285133Y844575D01*
X285050Y844242D01*
X284800Y844033D01*
X284508Y843908D01*
X283467D01*
G01X284508D02*
X285133Y842700D01*
G01X286692Y842992D02*
X286983Y842783D01*
X287317Y842700D01*
X287650Y842783D01*
X287942Y843033D01*
X288150Y843408D01*
X288233Y843783D01*
Y844242D01*
X288150Y844617D01*
X287942Y844950D01*
X287692Y845117D01*
X287400Y845200D01*
X287067Y845117D01*
X286817Y844950D01*
X286650Y844700D01*
X286567Y844367D01*
X286650Y844075D01*
X286858Y843783D01*
X287108Y843617D01*
X287400Y843575D01*
X287733Y843658D01*
X287983Y843867D01*
X288233Y844242D01*
G01X289583Y843075D02*
X289833Y842867D01*
X290125Y842742D01*
X290500Y842700D01*
X290875Y842783D01*
X291167Y842950D01*
X291375Y843242D01*
X291417Y843575D01*
X291333Y843908D01*
X291125Y844117D01*
X290833Y844283D01*
X290542Y844325D01*
X290250Y844283D01*
X289875Y844117D01*
X290000Y845200D01*
X291125D01*
G01X292808Y844783D02*
X293058Y845033D01*
X293350Y845158D01*
X293683Y845200D01*
X294100Y845117D01*
X294392Y844908D01*
X294475Y844658D01*
X294433Y844408D01*
X294267Y844200D01*
X293433Y843783D01*
X293058Y843492D01*
X292808Y843075D01*
X292725Y842700D01*
X294475D01*
G01X322800Y840500D02*
Y836500D01*
X330200D01*
G01X322800Y849000D02*
Y845000D01*
X330200D01*
G01X280367Y838700D02*
Y841200D01*
X281408D01*
X281742Y841075D01*
X281950Y840908D01*
X282033Y840575D01*
X281950Y840242D01*
X281700Y840033D01*
X281408Y839908D01*
X280367D01*
G01X281408D02*
X282033Y838700D01*
G01X283592Y838992D02*
X283883Y838783D01*
X284217Y838700D01*
X284550Y838783D01*
X284842Y839033D01*
X285050Y839408D01*
X285133Y839783D01*
Y840242D01*
X285050Y840617D01*
X284842Y840950D01*
X284592Y841117D01*
X284300Y841200D01*
X283967Y841117D01*
X283717Y840950D01*
X283550Y840700D01*
X283467Y840367D01*
X283550Y840075D01*
X283758Y839783D01*
X284008Y839617D01*
X284300Y839575D01*
X284633Y839658D01*
X284883Y839867D01*
X285133Y840242D01*
G01X286483Y839200D02*
X286733Y838908D01*
X287067Y838742D01*
X287442Y838700D01*
X287775Y838742D01*
X288108Y838950D01*
X288317Y839200D01*
X288358Y839450D01*
X288275Y839742D01*
X287983Y839950D01*
X287692Y840033D01*
X287317D01*
G01X287692D02*
X287942Y840158D01*
X288150Y840367D01*
X288233Y840617D01*
X288150Y840867D01*
X287942Y841075D01*
X287567Y841200D01*
X287192Y841158D01*
X286817Y840992D01*
G01X289583Y839075D02*
X289833Y838867D01*
X290125Y838742D01*
X290500Y838700D01*
X290875Y838783D01*
X291167Y838950D01*
X291375Y839242D01*
X291417Y839575D01*
X291333Y839908D01*
X291125Y840117D01*
X290833Y840283D01*
X290542Y840325D01*
X290250Y840283D01*
X289875Y840117D01*
X290000Y841200D01*
X291125D01*
G01X292683Y839075D02*
X292933Y838867D01*
X293225Y838742D01*
X293600Y838700D01*
X293975Y838783D01*
X294267Y838950D01*
X294475Y839242D01*
X294517Y839575D01*
X294433Y839908D01*
X294225Y840117D01*
X293933Y840283D01*
X293642Y840325D01*
X293350Y840283D01*
X292975Y840117D01*
X293100Y841200D01*
X294225D01*
G01X322800Y836400D02*
Y832400D01*
X330200D01*
G01X316457Y785691D02*
Y788191D01*
X317498D01*
X317832Y788066D01*
X318040Y787899D01*
X318123Y787566D01*
X318040Y787233D01*
X317790Y787024D01*
X317498Y786899D01*
X316457D01*
G01X317498D02*
X318123Y785691D01*
G01X320890D02*
Y788191D01*
X319348Y786399D01*
X321432D01*
G01X322698Y787774D02*
X322948Y788024D01*
X323240Y788149D01*
X323573Y788191D01*
X323990Y788108D01*
X324282Y787899D01*
X324365Y787649D01*
X324323Y787399D01*
X324157Y787191D01*
X323323Y786774D01*
X322948Y786483D01*
X322698Y786066D01*
X322615Y785691D01*
X324365D01*
G01X325673Y786191D02*
X325923Y785899D01*
X326257Y785733D01*
X326632Y785691D01*
X326965Y785733D01*
X327298Y785941D01*
X327507Y786191D01*
X327548Y786441D01*
X327465Y786733D01*
X327173Y786941D01*
X326882Y787024D01*
X326507D01*
G01X326882D02*
X327132Y787149D01*
X327340Y787358D01*
X327423Y787608D01*
X327340Y787858D01*
X327132Y788066D01*
X326757Y788191D01*
X326382Y788149D01*
X326007Y787983D01*
G01X328800Y817000D02*
Y813000D01*
X336200D01*
G01X316457Y781691D02*
Y784191D01*
X317498D01*
X317832Y784066D01*
X318040Y783899D01*
X318123Y783566D01*
X318040Y783233D01*
X317790Y783024D01*
X317498Y782899D01*
X316457D01*
G01X317498D02*
X318123Y781691D01*
G01X320890D02*
Y784191D01*
X319348Y782399D01*
X321432D01*
G01X322698Y783774D02*
X322948Y784024D01*
X323240Y784149D01*
X323573Y784191D01*
X323990Y784108D01*
X324282Y783899D01*
X324365Y783649D01*
X324323Y783399D01*
X324157Y783191D01*
X323323Y782774D01*
X322948Y782483D01*
X322698Y782066D01*
X322615Y781691D01*
X324365D01*
G01X327090D02*
Y784191D01*
X325548Y782399D01*
X327632D01*
G01X328800Y813000D02*
Y809000D01*
X336200D01*
G01X303276Y781919D02*
X300776D01*
Y782960D01*
X300901Y783294D01*
X301068Y783502D01*
X301401Y783585D01*
X301734Y783502D01*
X301943Y783252D01*
X302068Y782960D01*
Y781919D01*
G01Y782960D02*
X303276Y783585D01*
G01X302984Y785144D02*
X303193Y785435D01*
X303276Y785769D01*
X303193Y786102D01*
X302943Y786394D01*
X302568Y786602D01*
X302193Y786685D01*
X301734D01*
X301359Y786602D01*
X301026Y786394D01*
X300859Y786144D01*
X300776Y785852D01*
X300859Y785519D01*
X301026Y785269D01*
X301276Y785102D01*
X301609Y785019D01*
X301901Y785102D01*
X302193Y785310D01*
X302359Y785560D01*
X302401Y785852D01*
X302318Y786185D01*
X302109Y786435D01*
X301734Y786685D01*
G01X302984Y788244D02*
X303193Y788535D01*
X303276Y788869D01*
X303193Y789202D01*
X302943Y789494D01*
X302568Y789702D01*
X302193Y789785D01*
X301734D01*
X301359Y789702D01*
X301026Y789494D01*
X300859Y789244D01*
X300776Y788952D01*
X300859Y788619D01*
X301026Y788369D01*
X301276Y788202D01*
X301609Y788119D01*
X301901Y788202D01*
X302193Y788410D01*
X302359Y788660D01*
X302401Y788952D01*
X302318Y789285D01*
X302109Y789535D01*
X301734Y789785D01*
G01X303276Y791969D02*
X302734Y792052D01*
X302276Y792177D01*
X301859Y792344D01*
X301401Y792552D01*
X300776Y792885D01*
Y791219D01*
G01X303276Y795152D02*
X300776D01*
X301276Y794652D01*
G01X303276D02*
Y795652D01*
G01X306500Y828000D02*
X302500D01*
Y820600D01*
G01X302576Y799319D02*
X300076D01*
Y800360D01*
X300201Y800694D01*
X300368Y800902D01*
X300701Y800985D01*
X301034Y800902D01*
X301243Y800652D01*
X301368Y800360D01*
Y799319D01*
G01Y800360D02*
X302576Y800985D01*
G01X302284Y802544D02*
X302493Y802835D01*
X302576Y803169D01*
X302493Y803502D01*
X302243Y803794D01*
X301868Y804002D01*
X301493Y804085D01*
X301034D01*
X300659Y804002D01*
X300326Y803794D01*
X300159Y803544D01*
X300076Y803252D01*
X300159Y802919D01*
X300326Y802669D01*
X300576Y802502D01*
X300909Y802419D01*
X301201Y802502D01*
X301493Y802710D01*
X301659Y802960D01*
X301701Y803252D01*
X301618Y803585D01*
X301409Y803835D01*
X301034Y804085D01*
G01X302284Y805644D02*
X302493Y805935D01*
X302576Y806269D01*
X302493Y806602D01*
X302243Y806894D01*
X301868Y807102D01*
X301493Y807185D01*
X301034D01*
X300659Y807102D01*
X300326Y806894D01*
X300159Y806644D01*
X300076Y806352D01*
X300159Y806019D01*
X300326Y805769D01*
X300576Y805602D01*
X300909Y805519D01*
X301201Y805602D01*
X301493Y805810D01*
X301659Y806060D01*
X301701Y806352D01*
X301618Y806685D01*
X301409Y806935D01*
X301034Y807185D01*
G01X302576Y809369D02*
X302034Y809452D01*
X301576Y809577D01*
X301159Y809744D01*
X300701Y809952D01*
X300076Y810285D01*
Y808619D01*
G01Y812552D02*
X300159Y812219D01*
X300368Y811969D01*
X300618Y811802D01*
X300951Y811677D01*
X301326Y811635D01*
X301701Y811677D01*
X302034Y811802D01*
X302284Y811969D01*
X302493Y812219D01*
X302576Y812552D01*
X302493Y812885D01*
X302284Y813135D01*
X302034Y813302D01*
X301701Y813427D01*
X301326Y813469D01*
X300951Y813427D01*
X300618Y813302D01*
X300368Y813135D01*
X300159Y812885D01*
X300076Y812552D01*
G01X302500Y828100D02*
X306500D01*
Y835500D01*
G01X306776Y799319D02*
X304276D01*
Y800360D01*
X304401Y800694D01*
X304568Y800902D01*
X304901Y800985D01*
X305234Y800902D01*
X305443Y800652D01*
X305568Y800360D01*
Y799319D01*
G01Y800360D02*
X306776Y800985D01*
G01X306484Y802544D02*
X306693Y802835D01*
X306776Y803169D01*
X306693Y803502D01*
X306443Y803794D01*
X306068Y804002D01*
X305693Y804085D01*
X305234D01*
X304859Y804002D01*
X304526Y803794D01*
X304359Y803544D01*
X304276Y803252D01*
X304359Y802919D01*
X304526Y802669D01*
X304776Y802502D01*
X305109Y802419D01*
X305401Y802502D01*
X305693Y802710D01*
X305859Y802960D01*
X305901Y803252D01*
X305818Y803585D01*
X305609Y803835D01*
X305234Y804085D01*
G01X306484Y805644D02*
X306693Y805935D01*
X306776Y806269D01*
X306693Y806602D01*
X306443Y806894D01*
X306068Y807102D01*
X305693Y807185D01*
X305234D01*
X304859Y807102D01*
X304526Y806894D01*
X304359Y806644D01*
X304276Y806352D01*
X304359Y806019D01*
X304526Y805769D01*
X304776Y805602D01*
X305109Y805519D01*
X305401Y805602D01*
X305693Y805810D01*
X305859Y806060D01*
X305901Y806352D01*
X305818Y806685D01*
X305609Y806935D01*
X305234Y807185D01*
G01X305734Y808660D02*
X305443Y808952D01*
X305276Y809202D01*
X305193Y809535D01*
X305276Y809827D01*
X305443Y810035D01*
X305693Y810202D01*
X305984Y810244D01*
X306234Y810202D01*
X306484Y810035D01*
X306693Y809785D01*
X306776Y809494D01*
X306693Y809160D01*
X306443Y808869D01*
X306068Y808702D01*
X305651Y808660D01*
X305109Y808744D01*
X304818Y808869D01*
X304526Y809077D01*
X304318Y809369D01*
X304276Y809660D01*
X304359Y809952D01*
X304568Y810160D01*
G01X306776Y812552D02*
X306734Y812844D01*
X306609Y813177D01*
X306401Y813385D01*
X306109Y813469D01*
X305818Y813385D01*
X305568Y813135D01*
X305443Y812760D01*
Y812344D01*
X305359Y812094D01*
X305151Y811885D01*
X304859Y811802D01*
X304568Y811927D01*
X304359Y812219D01*
X304276Y812552D01*
X304359Y812885D01*
X304568Y813177D01*
X304859Y813302D01*
X305151Y813219D01*
X305359Y813010D01*
X305443Y812760D01*
Y812344D01*
X305568Y811969D01*
X305818Y811719D01*
X306109Y811635D01*
X306401Y811719D01*
X306609Y811927D01*
X306734Y812260D01*
X306776Y812552D01*
G01X310600Y835500D02*
X306600D01*
Y828100D01*
G01X307776Y781919D02*
X305276D01*
Y782960D01*
X305401Y783294D01*
X305568Y783502D01*
X305901Y783585D01*
X306234Y783502D01*
X306443Y783252D01*
X306568Y782960D01*
Y781919D01*
G01Y782960D02*
X307776Y783585D01*
G01X307484Y785144D02*
X307693Y785435D01*
X307776Y785769D01*
X307693Y786102D01*
X307443Y786394D01*
X307068Y786602D01*
X306693Y786685D01*
X306234D01*
X305859Y786602D01*
X305526Y786394D01*
X305359Y786144D01*
X305276Y785852D01*
X305359Y785519D01*
X305526Y785269D01*
X305776Y785102D01*
X306109Y785019D01*
X306401Y785102D01*
X306693Y785310D01*
X306859Y785560D01*
X306901Y785852D01*
X306818Y786185D01*
X306609Y786435D01*
X306234Y786685D01*
G01X307484Y788244D02*
X307693Y788535D01*
X307776Y788869D01*
X307693Y789202D01*
X307443Y789494D01*
X307068Y789702D01*
X306693Y789785D01*
X306234D01*
X305859Y789702D01*
X305526Y789494D01*
X305359Y789244D01*
X305276Y788952D01*
X305359Y788619D01*
X305526Y788369D01*
X305776Y788202D01*
X306109Y788119D01*
X306401Y788202D01*
X306693Y788410D01*
X306859Y788660D01*
X306901Y788952D01*
X306818Y789285D01*
X306609Y789535D01*
X306234Y789785D01*
G01X306734Y791260D02*
X306443Y791552D01*
X306276Y791802D01*
X306193Y792135D01*
X306276Y792427D01*
X306443Y792635D01*
X306693Y792802D01*
X306984Y792844D01*
X307234Y792802D01*
X307484Y792635D01*
X307693Y792385D01*
X307776Y792094D01*
X307693Y791760D01*
X307443Y791469D01*
X307068Y791302D01*
X306651Y791260D01*
X306109Y791344D01*
X305818Y791469D01*
X305526Y791677D01*
X305318Y791969D01*
X305276Y792260D01*
X305359Y792552D01*
X305568Y792760D01*
G01X307776Y795069D02*
X307234Y795152D01*
X306776Y795277D01*
X306359Y795444D01*
X305901Y795652D01*
X305276Y795985D01*
Y794319D01*
G01X306600Y820600D02*
X310600D01*
Y828000D01*
G01X313800Y798367D02*
X311300D01*
Y799408D01*
X311425Y799742D01*
X311592Y799950D01*
X311925Y800033D01*
X312258Y799950D01*
X312467Y799700D01*
X312592Y799408D01*
Y798367D01*
G01Y799408D02*
X313800Y800033D01*
G01X313508Y801592D02*
X313717Y801883D01*
X313800Y802217D01*
X313717Y802550D01*
X313467Y802842D01*
X313092Y803050D01*
X312717Y803133D01*
X312258D01*
X311883Y803050D01*
X311550Y802842D01*
X311383Y802592D01*
X311300Y802300D01*
X311383Y801967D01*
X311550Y801717D01*
X311800Y801550D01*
X312133Y801467D01*
X312425Y801550D01*
X312717Y801758D01*
X312883Y802008D01*
X312925Y802300D01*
X312842Y802633D01*
X312633Y802883D01*
X312258Y803133D01*
G01X313508Y804692D02*
X313717Y804983D01*
X313800Y805317D01*
X313717Y805650D01*
X313467Y805942D01*
X313092Y806150D01*
X312717Y806233D01*
X312258D01*
X311883Y806150D01*
X311550Y805942D01*
X311383Y805692D01*
X311300Y805400D01*
X311383Y805067D01*
X311550Y804817D01*
X311800Y804650D01*
X312133Y804567D01*
X312425Y804650D01*
X312717Y804858D01*
X312883Y805108D01*
X312925Y805400D01*
X312842Y805733D01*
X312633Y805983D01*
X312258Y806233D01*
G01X312758Y807708D02*
X312467Y808000D01*
X312300Y808250D01*
X312217Y808583D01*
X312300Y808875D01*
X312467Y809083D01*
X312717Y809250D01*
X313008Y809292D01*
X313258Y809250D01*
X313508Y809083D01*
X313717Y808833D01*
X313800Y808542D01*
X313717Y808208D01*
X313467Y807917D01*
X313092Y807750D01*
X312675Y807708D01*
X312133Y807792D01*
X311842Y807917D01*
X311550Y808125D01*
X311342Y808417D01*
X311300Y808708D01*
X311383Y809000D01*
X311592Y809208D01*
G01X313508Y810892D02*
X313717Y811183D01*
X313800Y811517D01*
X313717Y811850D01*
X313467Y812142D01*
X313092Y812350D01*
X312717Y812433D01*
X312258D01*
X311883Y812350D01*
X311550Y812142D01*
X311383Y811892D01*
X311300Y811600D01*
X311383Y811267D01*
X311550Y811017D01*
X311800Y810850D01*
X312133Y810767D01*
X312425Y810850D01*
X312717Y811058D01*
X312883Y811308D01*
X312925Y811600D01*
X312842Y811933D01*
X312633Y812183D01*
X312258Y812433D01*
G01X322417Y886092D02*
X322167Y886217D01*
X321875Y886300D01*
X321542D01*
X321167Y886175D01*
X320875Y885967D01*
X320667Y885717D01*
X320500Y885300D01*
X320458Y884925D01*
X320542Y884550D01*
X320667Y884300D01*
X320917Y884050D01*
X321208Y883883D01*
X321500Y883800D01*
X321792D01*
X322083Y883883D01*
X322333Y884008D01*
X322542Y884175D01*
G01X323892Y884092D02*
X324183Y883883D01*
X324517Y883800D01*
X324850Y883883D01*
X325142Y884133D01*
X325350Y884508D01*
X325433Y884883D01*
Y885342D01*
X325350Y885717D01*
X325142Y886050D01*
X324892Y886217D01*
X324600Y886300D01*
X324267Y886217D01*
X324017Y886050D01*
X323850Y885800D01*
X323767Y885467D01*
X323850Y885175D01*
X324058Y884883D01*
X324308Y884717D01*
X324600Y884675D01*
X324933Y884758D01*
X325183Y884967D01*
X325433Y885342D01*
G01X326783Y884300D02*
X327033Y884008D01*
X327367Y883842D01*
X327742Y883800D01*
X328075Y883842D01*
X328408Y884050D01*
X328617Y884300D01*
X328658Y884550D01*
X328575Y884842D01*
X328283Y885050D01*
X327992Y885133D01*
X327617D01*
G01X327992D02*
X328242Y885258D01*
X328450Y885467D01*
X328533Y885717D01*
X328450Y885967D01*
X328242Y886175D01*
X327867Y886300D01*
X327492Y886258D01*
X327117Y886092D01*
G01X330008Y884842D02*
X330300Y885133D01*
X330550Y885300D01*
X330883Y885383D01*
X331175Y885300D01*
X331383Y885133D01*
X331550Y884883D01*
X331592Y884592D01*
X331550Y884342D01*
X331383Y884092D01*
X331133Y883883D01*
X330842Y883800D01*
X330508Y883883D01*
X330217Y884133D01*
X330050Y884508D01*
X330008Y884925D01*
X330092Y885467D01*
X330217Y885758D01*
X330425Y886050D01*
X330717Y886258D01*
X331008Y886300D01*
X331300Y886217D01*
X331508Y886008D01*
G01X333900Y883800D02*
Y886300D01*
X333400Y885800D01*
G01Y883800D02*
X334400D01*
G01X305817Y885992D02*
X305567Y886117D01*
X305275Y886200D01*
X304942D01*
X304567Y886075D01*
X304275Y885867D01*
X304067Y885617D01*
X303900Y885200D01*
X303858Y884825D01*
X303942Y884450D01*
X304067Y884200D01*
X304317Y883950D01*
X304608Y883783D01*
X304900Y883700D01*
X305192D01*
X305483Y883783D01*
X305733Y883908D01*
X305942Y884075D01*
G01X307292Y883992D02*
X307583Y883783D01*
X307917Y883700D01*
X308250Y883783D01*
X308542Y884033D01*
X308750Y884408D01*
X308833Y884783D01*
Y885242D01*
X308750Y885617D01*
X308542Y885950D01*
X308292Y886117D01*
X308000Y886200D01*
X307667Y886117D01*
X307417Y885950D01*
X307250Y885700D01*
X307167Y885367D01*
X307250Y885075D01*
X307458Y884783D01*
X307708Y884617D01*
X308000Y884575D01*
X308333Y884658D01*
X308583Y884867D01*
X308833Y885242D01*
G01X310183Y884200D02*
X310433Y883908D01*
X310767Y883742D01*
X311142Y883700D01*
X311475Y883742D01*
X311808Y883950D01*
X312017Y884200D01*
X312058Y884450D01*
X311975Y884742D01*
X311683Y884950D01*
X311392Y885033D01*
X311017D01*
G01X311392D02*
X311642Y885158D01*
X311850Y885367D01*
X311933Y885617D01*
X311850Y885867D01*
X311642Y886075D01*
X311267Y886200D01*
X310892Y886158D01*
X310517Y885992D01*
G01X314117Y883700D02*
X314200Y884242D01*
X314325Y884700D01*
X314492Y885117D01*
X314700Y885575D01*
X315033Y886200D01*
X313367D01*
G01X316508Y885783D02*
X316758Y886033D01*
X317050Y886158D01*
X317383Y886200D01*
X317800Y886117D01*
X318092Y885908D01*
X318175Y885658D01*
X318133Y885408D01*
X317967Y885200D01*
X317133Y884783D01*
X316758Y884492D01*
X316508Y884075D01*
X316425Y883700D01*
X318175D01*
G01X298618Y860067D02*
X298493Y859817D01*
X298410Y859525D01*
Y859192D01*
X298535Y858817D01*
X298743Y858525D01*
X298993Y858317D01*
X299410Y858150D01*
X299785Y858108D01*
X300160Y858192D01*
X300410Y858317D01*
X300660Y858567D01*
X300827Y858858D01*
X300910Y859150D01*
Y859442D01*
X300827Y859733D01*
X300702Y859983D01*
X300535Y860192D01*
G01X300910Y862250D02*
X300868Y862542D01*
X300743Y862875D01*
X300535Y863083D01*
X300243Y863167D01*
X299952Y863083D01*
X299702Y862833D01*
X299577Y862458D01*
Y862042D01*
X299493Y861792D01*
X299285Y861583D01*
X298993Y861500D01*
X298702Y861625D01*
X298493Y861917D01*
X298410Y862250D01*
X298493Y862583D01*
X298702Y862875D01*
X298993Y863000D01*
X299285Y862917D01*
X299493Y862708D01*
X299577Y862458D01*
Y862042D01*
X299702Y861667D01*
X299952Y861417D01*
X300243Y861333D01*
X300535Y861417D01*
X300743Y861625D01*
X300868Y861958D01*
X300910Y862250D01*
G01X300618Y864642D02*
X300827Y864933D01*
X300910Y865267D01*
X300827Y865600D01*
X300577Y865892D01*
X300202Y866100D01*
X299827Y866183D01*
X299368D01*
X298993Y866100D01*
X298660Y865892D01*
X298493Y865642D01*
X298410Y865350D01*
X298493Y865017D01*
X298660Y864767D01*
X298910Y864600D01*
X299243Y864517D01*
X299535Y864600D01*
X299827Y864808D01*
X299993Y865058D01*
X300035Y865350D01*
X299952Y865683D01*
X299743Y865933D01*
X299368Y866183D01*
G01X300910Y868450D02*
X298410D01*
X298910Y867950D01*
G01X300910D02*
Y868950D01*
G01X300410Y870633D02*
X300702Y870883D01*
X300868Y871217D01*
X300910Y871592D01*
X300868Y871925D01*
X300660Y872258D01*
X300410Y872467D01*
X300160Y872508D01*
X299868Y872425D01*
X299660Y872133D01*
X299577Y871842D01*
Y871467D01*
G01Y871842D02*
X299452Y872092D01*
X299243Y872300D01*
X298993Y872383D01*
X298743Y872300D01*
X298535Y872092D01*
X298410Y871717D01*
X298452Y871342D01*
X298618Y870967D01*
G01X302897Y860347D02*
X302772Y860097D01*
X302689Y859805D01*
Y859472D01*
X302814Y859097D01*
X303022Y858805D01*
X303272Y858597D01*
X303689Y858430D01*
X304064Y858388D01*
X304439Y858472D01*
X304689Y858597D01*
X304939Y858847D01*
X305106Y859138D01*
X305189Y859430D01*
Y859722D01*
X305106Y860013D01*
X304981Y860263D01*
X304814Y860472D01*
G01X305189Y862530D02*
X305147Y862822D01*
X305022Y863155D01*
X304814Y863363D01*
X304522Y863447D01*
X304231Y863363D01*
X303981Y863113D01*
X303856Y862738D01*
Y862322D01*
X303772Y862072D01*
X303564Y861863D01*
X303272Y861780D01*
X302981Y861905D01*
X302772Y862197D01*
X302689Y862530D01*
X302772Y862863D01*
X302981Y863155D01*
X303272Y863280D01*
X303564Y863197D01*
X303772Y862988D01*
X303856Y862738D01*
Y862322D01*
X303981Y861947D01*
X304231Y861697D01*
X304522Y861613D01*
X304814Y861697D01*
X305022Y861905D01*
X305147Y862238D01*
X305189Y862530D01*
G01X304897Y864922D02*
X305106Y865213D01*
X305189Y865547D01*
X305106Y865880D01*
X304856Y866172D01*
X304481Y866380D01*
X304106Y866463D01*
X303647D01*
X303272Y866380D01*
X302939Y866172D01*
X302772Y865922D01*
X302689Y865630D01*
X302772Y865297D01*
X302939Y865047D01*
X303189Y864880D01*
X303522Y864797D01*
X303814Y864880D01*
X304106Y865088D01*
X304272Y865338D01*
X304314Y865630D01*
X304231Y865963D01*
X304022Y866213D01*
X303647Y866463D01*
G01X305189Y868730D02*
X302689D01*
X303189Y868230D01*
G01X305189D02*
Y869230D01*
G01X304814Y870913D02*
X305022Y871163D01*
X305147Y871455D01*
X305189Y871830D01*
X305106Y872205D01*
X304939Y872497D01*
X304647Y872705D01*
X304314Y872747D01*
X303981Y872663D01*
X303772Y872455D01*
X303606Y872163D01*
X303564Y871872D01*
X303606Y871580D01*
X303772Y871205D01*
X302689Y871330D01*
Y872455D01*
G01X320667Y891800D02*
Y894300D01*
X321708D01*
X322042Y894175D01*
X322250Y894008D01*
X322333Y893675D01*
X322250Y893342D01*
X322000Y893133D01*
X321708Y893008D01*
X320667D01*
G01X321708D02*
X322333Y891800D01*
G01X323892Y892092D02*
X324183Y891883D01*
X324517Y891800D01*
X324850Y891883D01*
X325142Y892133D01*
X325350Y892508D01*
X325433Y892883D01*
Y893342D01*
X325350Y893717D01*
X325142Y894050D01*
X324892Y894217D01*
X324600Y894300D01*
X324267Y894217D01*
X324017Y894050D01*
X323850Y893800D01*
X323767Y893467D01*
X323850Y893175D01*
X324058Y892883D01*
X324308Y892717D01*
X324600Y892675D01*
X324933Y892758D01*
X325183Y892967D01*
X325433Y893342D01*
G01X328200Y891800D02*
Y894300D01*
X326658Y892508D01*
X328742D01*
G01X330717Y891800D02*
X330800Y892342D01*
X330925Y892800D01*
X331092Y893217D01*
X331300Y893675D01*
X331633Y894300D01*
X329967D01*
G01X333192Y892092D02*
X333483Y891883D01*
X333817Y891800D01*
X334150Y891883D01*
X334442Y892133D01*
X334650Y892508D01*
X334733Y892883D01*
Y893342D01*
X334650Y893717D01*
X334442Y894050D01*
X334192Y894217D01*
X333900Y894300D01*
X333567Y894217D01*
X333317Y894050D01*
X333150Y893800D01*
X333067Y893467D01*
X333150Y893175D01*
X333358Y892883D01*
X333608Y892717D01*
X333900Y892675D01*
X334233Y892758D01*
X334483Y892967D01*
X334733Y893342D01*
G01X331260Y866317D02*
X328760D01*
Y867358D01*
X328885Y867692D01*
X329052Y867900D01*
X329385Y867983D01*
X329718Y867900D01*
X329927Y867650D01*
X330052Y867358D01*
Y866317D01*
G01Y867358D02*
X331260Y867983D01*
G01X330968Y869542D02*
X331177Y869833D01*
X331260Y870167D01*
X331177Y870500D01*
X330927Y870792D01*
X330552Y871000D01*
X330177Y871083D01*
X329718D01*
X329343Y871000D01*
X329010Y870792D01*
X328843Y870542D01*
X328760Y870250D01*
X328843Y869917D01*
X329010Y869667D01*
X329260Y869500D01*
X329593Y869417D01*
X329885Y869500D01*
X330177Y869708D01*
X330343Y869958D01*
X330385Y870250D01*
X330302Y870583D01*
X330093Y870833D01*
X329718Y871083D01*
G01X328760Y873350D02*
X328843Y873017D01*
X329052Y872767D01*
X329302Y872600D01*
X329635Y872475D01*
X330010Y872433D01*
X330385Y872475D01*
X330718Y872600D01*
X330968Y872767D01*
X331177Y873017D01*
X331260Y873350D01*
X331177Y873683D01*
X330968Y873933D01*
X330718Y874100D01*
X330385Y874225D01*
X330010Y874267D01*
X329635Y874225D01*
X329302Y874100D01*
X329052Y873933D01*
X328843Y873683D01*
X328760Y873350D01*
G01X331260Y876450D02*
X331218Y876742D01*
X331093Y877075D01*
X330885Y877283D01*
X330593Y877367D01*
X330302Y877283D01*
X330052Y877033D01*
X329927Y876658D01*
Y876242D01*
X329843Y875992D01*
X329635Y875783D01*
X329343Y875700D01*
X329052Y875825D01*
X328843Y876117D01*
X328760Y876450D01*
X328843Y876783D01*
X329052Y877075D01*
X329343Y877200D01*
X329635Y877117D01*
X329843Y876908D01*
X329927Y876658D01*
Y876242D01*
X330052Y875867D01*
X330302Y875617D01*
X330593Y875533D01*
X330885Y875617D01*
X331093Y875825D01*
X331218Y876158D01*
X331260Y876450D01*
G01X328760Y879550D02*
X328843Y879217D01*
X329052Y878967D01*
X329302Y878800D01*
X329635Y878675D01*
X330010Y878633D01*
X330385Y878675D01*
X330718Y878800D01*
X330968Y878967D01*
X331177Y879217D01*
X331260Y879550D01*
X331177Y879883D01*
X330968Y880133D01*
X330718Y880300D01*
X330385Y880425D01*
X330010Y880467D01*
X329635Y880425D01*
X329302Y880300D01*
X329052Y880133D01*
X328843Y879883D01*
X328760Y879550D01*
G01X321519Y866227D02*
X319019D01*
Y867268D01*
X319144Y867602D01*
X319311Y867810D01*
X319644Y867893D01*
X319977Y867810D01*
X320186Y867560D01*
X320311Y867268D01*
Y866227D01*
G01Y867268D02*
X321519Y867893D01*
G01X321227Y869452D02*
X321436Y869743D01*
X321519Y870077D01*
X321436Y870410D01*
X321186Y870702D01*
X320811Y870910D01*
X320436Y870993D01*
X319977D01*
X319602Y870910D01*
X319269Y870702D01*
X319102Y870452D01*
X319019Y870160D01*
X319102Y869827D01*
X319269Y869577D01*
X319519Y869410D01*
X319852Y869327D01*
X320144Y869410D01*
X320436Y869618D01*
X320602Y869868D01*
X320644Y870160D01*
X320561Y870493D01*
X320352Y870743D01*
X319977Y870993D01*
G01X319019Y873260D02*
X319102Y872927D01*
X319311Y872677D01*
X319561Y872510D01*
X319894Y872385D01*
X320269Y872343D01*
X320644Y872385D01*
X320977Y872510D01*
X321227Y872677D01*
X321436Y872927D01*
X321519Y873260D01*
X321436Y873593D01*
X321227Y873843D01*
X320977Y874010D01*
X320644Y874135D01*
X320269Y874177D01*
X319894Y874135D01*
X319561Y874010D01*
X319311Y873843D01*
X319102Y873593D01*
X319019Y873260D01*
G01X321519Y876360D02*
X321477Y876652D01*
X321352Y876985D01*
X321144Y877193D01*
X320852Y877277D01*
X320561Y877193D01*
X320311Y876943D01*
X320186Y876568D01*
Y876152D01*
X320102Y875902D01*
X319894Y875693D01*
X319602Y875610D01*
X319311Y875735D01*
X319102Y876027D01*
X319019Y876360D01*
X319102Y876693D01*
X319311Y876985D01*
X319602Y877110D01*
X319894Y877027D01*
X320102Y876818D01*
X320186Y876568D01*
Y876152D01*
X320311Y875777D01*
X320561Y875527D01*
X320852Y875443D01*
X321144Y875527D01*
X321352Y875735D01*
X321477Y876068D01*
X321519Y876360D01*
G01X321227Y878752D02*
X321436Y879043D01*
X321519Y879377D01*
X321436Y879710D01*
X321186Y880002D01*
X320811Y880210D01*
X320436Y880293D01*
X319977D01*
X319602Y880210D01*
X319269Y880002D01*
X319102Y879752D01*
X319019Y879460D01*
X319102Y879127D01*
X319269Y878877D01*
X319519Y878710D01*
X319852Y878627D01*
X320144Y878710D01*
X320436Y878918D01*
X320602Y879168D01*
X320644Y879460D01*
X320561Y879793D01*
X320352Y880043D01*
X319977Y880293D01*
G01X325519Y866227D02*
X323019D01*
Y867268D01*
X323144Y867602D01*
X323311Y867810D01*
X323644Y867893D01*
X323977Y867810D01*
X324186Y867560D01*
X324311Y867268D01*
Y866227D01*
G01Y867268D02*
X325519Y867893D01*
G01X325227Y869452D02*
X325436Y869743D01*
X325519Y870077D01*
X325436Y870410D01*
X325186Y870702D01*
X324811Y870910D01*
X324436Y870993D01*
X323977D01*
X323602Y870910D01*
X323269Y870702D01*
X323102Y870452D01*
X323019Y870160D01*
X323102Y869827D01*
X323269Y869577D01*
X323519Y869410D01*
X323852Y869327D01*
X324144Y869410D01*
X324436Y869618D01*
X324602Y869868D01*
X324644Y870160D01*
X324561Y870493D01*
X324352Y870743D01*
X323977Y870993D01*
G01X323019Y873260D02*
X323102Y872927D01*
X323311Y872677D01*
X323561Y872510D01*
X323894Y872385D01*
X324269Y872343D01*
X324644Y872385D01*
X324977Y872510D01*
X325227Y872677D01*
X325436Y872927D01*
X325519Y873260D01*
X325436Y873593D01*
X325227Y873843D01*
X324977Y874010D01*
X324644Y874135D01*
X324269Y874177D01*
X323894Y874135D01*
X323561Y874010D01*
X323311Y873843D01*
X323102Y873593D01*
X323019Y873260D01*
G01X325227Y875652D02*
X325436Y875943D01*
X325519Y876277D01*
X325436Y876610D01*
X325186Y876902D01*
X324811Y877110D01*
X324436Y877193D01*
X323977D01*
X323602Y877110D01*
X323269Y876902D01*
X323102Y876652D01*
X323019Y876360D01*
X323102Y876027D01*
X323269Y875777D01*
X323519Y875610D01*
X323852Y875527D01*
X324144Y875610D01*
X324436Y875818D01*
X324602Y876068D01*
X324644Y876360D01*
X324561Y876693D01*
X324352Y876943D01*
X323977Y877193D01*
G01X323019Y879460D02*
X323102Y879127D01*
X323311Y878877D01*
X323561Y878710D01*
X323894Y878585D01*
X324269Y878543D01*
X324644Y878585D01*
X324977Y878710D01*
X325227Y878877D01*
X325436Y879127D01*
X325519Y879460D01*
X325436Y879793D01*
X325227Y880043D01*
X324977Y880210D01*
X324644Y880335D01*
X324269Y880377D01*
X323894Y880335D01*
X323561Y880210D01*
X323311Y880043D01*
X323102Y879793D01*
X323019Y879460D01*
G01X280325Y855033D02*
X280658Y854825D01*
X281033Y854700D01*
X281367D01*
X281700Y854825D01*
X281950Y855033D01*
X282075Y855325D01*
X281992Y855617D01*
X281783Y855867D01*
X281408Y856033D01*
X280908Y856117D01*
X280617Y856283D01*
X280492Y856575D01*
X280575Y856867D01*
X280783Y857075D01*
X281075Y857200D01*
X281367D01*
X281658Y857117D01*
X281908Y856908D01*
G01X283467Y854700D02*
Y857200D01*
X284508D01*
X284842Y857075D01*
X285050Y856908D01*
X285133Y856575D01*
X285050Y856242D01*
X284800Y856033D01*
X284508Y855908D01*
X283467D01*
G01X284508D02*
X285133Y854700D01*
G01X286692Y854992D02*
X286983Y854783D01*
X287317Y854700D01*
X287650Y854783D01*
X287942Y855033D01*
X288150Y855408D01*
X288233Y855783D01*
Y856242D01*
X288150Y856617D01*
X287942Y856950D01*
X287692Y857117D01*
X287400Y857200D01*
X287067Y857117D01*
X286817Y856950D01*
X286650Y856700D01*
X286567Y856367D01*
X286650Y856075D01*
X286858Y855783D01*
X287108Y855617D01*
X287400Y855575D01*
X287733Y855658D01*
X287983Y855867D01*
X288233Y856242D01*
G01X289583Y855075D02*
X289833Y854867D01*
X290125Y854742D01*
X290500Y854700D01*
X290875Y854783D01*
X291167Y854950D01*
X291375Y855242D01*
X291417Y855575D01*
X291333Y855908D01*
X291125Y856117D01*
X290833Y856283D01*
X290542Y856325D01*
X290250Y856283D01*
X289875Y856117D01*
X290000Y857200D01*
X291125D01*
G01X293600Y854700D02*
Y857200D01*
X293100Y856700D01*
G01Y854700D02*
X294100D01*
G01X322800Y853000D02*
Y849000D01*
X330200D01*
G01X280325Y851033D02*
X280658Y850825D01*
X281033Y850700D01*
X281367D01*
X281700Y850825D01*
X281950Y851033D01*
X282075Y851325D01*
X281992Y851617D01*
X281783Y851867D01*
X281408Y852033D01*
X280908Y852117D01*
X280617Y852283D01*
X280492Y852575D01*
X280575Y852867D01*
X280783Y853075D01*
X281075Y853200D01*
X281367D01*
X281658Y853117D01*
X281908Y852908D01*
G01X283467Y850700D02*
Y853200D01*
X284508D01*
X284842Y853075D01*
X285050Y852908D01*
X285133Y852575D01*
X285050Y852242D01*
X284800Y852033D01*
X284508Y851908D01*
X283467D01*
G01X284508D02*
X285133Y850700D01*
G01X286692Y850992D02*
X286983Y850783D01*
X287317Y850700D01*
X287650Y850783D01*
X287942Y851033D01*
X288150Y851408D01*
X288233Y851783D01*
Y852242D01*
X288150Y852617D01*
X287942Y852950D01*
X287692Y853117D01*
X287400Y853200D01*
X287067Y853117D01*
X286817Y852950D01*
X286650Y852700D01*
X286567Y852367D01*
X286650Y852075D01*
X286858Y851783D01*
X287108Y851617D01*
X287400Y851575D01*
X287733Y851658D01*
X287983Y851867D01*
X288233Y852242D01*
G01X289583Y851075D02*
X289833Y850867D01*
X290125Y850742D01*
X290500Y850700D01*
X290875Y850783D01*
X291167Y850950D01*
X291375Y851242D01*
X291417Y851575D01*
X291333Y851908D01*
X291125Y852117D01*
X290833Y852283D01*
X290542Y852325D01*
X290250Y852283D01*
X289875Y852117D01*
X290000Y853200D01*
X291125D01*
G01X292683Y851200D02*
X292933Y850908D01*
X293267Y850742D01*
X293642Y850700D01*
X293975Y850742D01*
X294308Y850950D01*
X294517Y851200D01*
X294558Y851450D01*
X294475Y851742D01*
X294183Y851950D01*
X293892Y852033D01*
X293517D01*
G01X293892D02*
X294142Y852158D01*
X294350Y852367D01*
X294433Y852617D01*
X294350Y852867D01*
X294142Y853075D01*
X293767Y853200D01*
X293392Y853158D01*
X293017Y852992D01*
G01X304067Y891700D02*
Y894200D01*
X305108D01*
X305442Y894075D01*
X305650Y893908D01*
X305733Y893575D01*
X305650Y893242D01*
X305400Y893033D01*
X305108Y892908D01*
X304067D01*
G01X305108D02*
X305733Y891700D01*
G01X307292Y891992D02*
X307583Y891783D01*
X307917Y891700D01*
X308250Y891783D01*
X308542Y892033D01*
X308750Y892408D01*
X308833Y892783D01*
Y893242D01*
X308750Y893617D01*
X308542Y893950D01*
X308292Y894117D01*
X308000Y894200D01*
X307667Y894117D01*
X307417Y893950D01*
X307250Y893700D01*
X307167Y893367D01*
X307250Y893075D01*
X307458Y892783D01*
X307708Y892617D01*
X308000Y892575D01*
X308333Y892658D01*
X308583Y892867D01*
X308833Y893242D01*
G01X310183Y892075D02*
X310433Y891867D01*
X310725Y891742D01*
X311100Y891700D01*
X311475Y891783D01*
X311767Y891950D01*
X311975Y892242D01*
X312017Y892575D01*
X311933Y892908D01*
X311725Y893117D01*
X311433Y893283D01*
X311142Y893325D01*
X310850Y893283D01*
X310475Y893117D01*
X310600Y894200D01*
X311725D01*
G01X314200Y891700D02*
Y894200D01*
X313700Y893700D01*
G01Y891700D02*
X314700D01*
G01X317217D02*
X317300Y892242D01*
X317425Y892700D01*
X317592Y893117D01*
X317800Y893575D01*
X318133Y894200D01*
X316467D01*
G01X280367Y858700D02*
Y861200D01*
X281408D01*
X281742Y861075D01*
X281950Y860908D01*
X282033Y860575D01*
X281950Y860242D01*
X281700Y860033D01*
X281408Y859908D01*
X280367D01*
G01X281408D02*
X282033Y858700D01*
G01X283592Y858992D02*
X283883Y858783D01*
X284217Y858700D01*
X284550Y858783D01*
X284842Y859033D01*
X285050Y859408D01*
X285133Y859783D01*
Y860242D01*
X285050Y860617D01*
X284842Y860950D01*
X284592Y861117D01*
X284300Y861200D01*
X283967Y861117D01*
X283717Y860950D01*
X283550Y860700D01*
X283467Y860367D01*
X283550Y860075D01*
X283758Y859783D01*
X284008Y859617D01*
X284300Y859575D01*
X284633Y859658D01*
X284883Y859867D01*
X285133Y860242D01*
G01X286483Y859200D02*
X286733Y858908D01*
X287067Y858742D01*
X287442Y858700D01*
X287775Y858742D01*
X288108Y858950D01*
X288317Y859200D01*
X288358Y859450D01*
X288275Y859742D01*
X287983Y859950D01*
X287692Y860033D01*
X287317D01*
G01X287692D02*
X287942Y860158D01*
X288150Y860367D01*
X288233Y860617D01*
X288150Y860867D01*
X287942Y861075D01*
X287567Y861200D01*
X287192Y861158D01*
X286817Y860992D01*
G01X289583Y859075D02*
X289833Y858867D01*
X290125Y858742D01*
X290500Y858700D01*
X290875Y858783D01*
X291167Y858950D01*
X291375Y859242D01*
X291417Y859575D01*
X291333Y859908D01*
X291125Y860117D01*
X290833Y860283D01*
X290542Y860325D01*
X290250Y860283D01*
X289875Y860117D01*
X290000Y861200D01*
X291125D01*
G01X292808Y859742D02*
X293100Y860033D01*
X293350Y860200D01*
X293683Y860283D01*
X293975Y860200D01*
X294183Y860033D01*
X294350Y859783D01*
X294392Y859492D01*
X294350Y859242D01*
X294183Y858992D01*
X293933Y858783D01*
X293642Y858700D01*
X293308Y858783D01*
X293017Y859033D01*
X292850Y859408D01*
X292808Y859825D01*
X292892Y860367D01*
X293017Y860658D01*
X293225Y860950D01*
X293517Y861158D01*
X293808Y861200D01*
X294100Y861117D01*
X294308Y860908D01*
G01X322800Y857000D02*
Y853000D01*
X330200D01*
G01X303467Y887667D02*
Y890167D01*
X304508D01*
X304842Y890042D01*
X305050Y889875D01*
X305133Y889542D01*
X305050Y889209D01*
X304800Y889000D01*
X304508Y888875D01*
X303467D01*
G01X304508D02*
X305133Y887667D01*
G01X306692Y887959D02*
X306983Y887750D01*
X307317Y887667D01*
X307650Y887750D01*
X307942Y888000D01*
X308150Y888375D01*
X308233Y888750D01*
Y889209D01*
X308150Y889584D01*
X307942Y889917D01*
X307692Y890084D01*
X307400Y890167D01*
X307067Y890084D01*
X306817Y889917D01*
X306650Y889667D01*
X306567Y889334D01*
X306650Y889042D01*
X306858Y888750D01*
X307108Y888584D01*
X307400Y888542D01*
X307733Y888625D01*
X307983Y888834D01*
X308233Y889209D01*
G01X309708Y888709D02*
X310000Y889000D01*
X310250Y889167D01*
X310583Y889250D01*
X310875Y889167D01*
X311083Y889000D01*
X311250Y888750D01*
X311292Y888459D01*
X311250Y888209D01*
X311083Y887959D01*
X310833Y887750D01*
X310542Y887667D01*
X310208Y887750D01*
X309917Y888000D01*
X309750Y888375D01*
X309708Y888792D01*
X309792Y889334D01*
X309917Y889625D01*
X310125Y889917D01*
X310417Y890125D01*
X310708Y890167D01*
X311000Y890084D01*
X311208Y889875D01*
G01X313600Y887667D02*
Y890167D01*
X313100Y889667D01*
G01Y887667D02*
X314100D01*
G01X315908Y889750D02*
X316158Y890000D01*
X316450Y890125D01*
X316783Y890167D01*
X317200Y890084D01*
X317492Y889875D01*
X317575Y889625D01*
X317533Y889375D01*
X317367Y889167D01*
X316533Y888750D01*
X316158Y888459D01*
X315908Y888042D01*
X315825Y887667D01*
X317575D01*
G01X320719Y887524D02*
Y890024D01*
X321760D01*
X322094Y889899D01*
X322302Y889732D01*
X322385Y889399D01*
X322302Y889066D01*
X322052Y888857D01*
X321760Y888732D01*
X320719D01*
G01X321760D02*
X322385Y887524D01*
G01X323944Y887816D02*
X324235Y887607D01*
X324569Y887524D01*
X324902Y887607D01*
X325194Y887857D01*
X325402Y888232D01*
X325485Y888607D01*
Y889066D01*
X325402Y889441D01*
X325194Y889774D01*
X324944Y889941D01*
X324652Y890024D01*
X324319Y889941D01*
X324069Y889774D01*
X323902Y889524D01*
X323819Y889191D01*
X323902Y888899D01*
X324110Y888607D01*
X324360Y888441D01*
X324652Y888399D01*
X324985Y888482D01*
X325235Y888691D01*
X325485Y889066D01*
G01X326960Y888566D02*
X327252Y888857D01*
X327502Y889024D01*
X327835Y889107D01*
X328127Y889024D01*
X328335Y888857D01*
X328502Y888607D01*
X328544Y888316D01*
X328502Y888066D01*
X328335Y887816D01*
X328085Y887607D01*
X327794Y887524D01*
X327460Y887607D01*
X327169Y887857D01*
X327002Y888232D01*
X326960Y888649D01*
X327044Y889191D01*
X327169Y889482D01*
X327377Y889774D01*
X327669Y889982D01*
X327960Y890024D01*
X328252Y889941D01*
X328460Y889732D01*
G01X330852Y887524D02*
Y890024D01*
X330352Y889524D01*
G01Y887524D02*
X331352D01*
G01X333035Y888024D02*
X333285Y887732D01*
X333619Y887566D01*
X333994Y887524D01*
X334327Y887566D01*
X334660Y887774D01*
X334869Y888024D01*
X334910Y888274D01*
X334827Y888566D01*
X334535Y888774D01*
X334244Y888857D01*
X333869D01*
G01X334244D02*
X334494Y888982D01*
X334702Y889191D01*
X334785Y889441D01*
X334702Y889691D01*
X334494Y889899D01*
X334119Y890024D01*
X333744Y889982D01*
X333369Y889816D01*
G01X264708Y856000D02*
Y858500D01*
X266292D01*
G01X265708Y857292D02*
X264708D01*
G01X268933Y857333D02*
X269100Y857458D01*
X269225Y857667D01*
X269308Y857958D01*
X269225Y858208D01*
X269058Y858375D01*
X268767Y858500D01*
X267642D01*
Y856000D01*
X269017D01*
X269308Y856167D01*
X269475Y856417D01*
X269558Y856708D01*
X269475Y857000D01*
X269225Y857250D01*
X268933Y857333D01*
X267642D01*
G01X270992Y856292D02*
X271283Y856083D01*
X271617Y856000D01*
X271950Y856083D01*
X272242Y856333D01*
X272450Y856708D01*
X272533Y857083D01*
Y857542D01*
X272450Y857917D01*
X272242Y858250D01*
X271992Y858417D01*
X271700Y858500D01*
X271367Y858417D01*
X271117Y858250D01*
X270950Y858000D01*
X270867Y857667D01*
X270950Y857375D01*
X271158Y857083D01*
X271408Y856917D01*
X271700Y856875D01*
X272033Y856958D01*
X272283Y857167D01*
X272533Y857542D01*
G01X305000Y849600D02*
Y856600D01*
X318400D01*
Y849600D01*
X305000D01*
G01X266417Y854292D02*
X266167Y854417D01*
X265875Y854500D01*
X265542D01*
X265167Y854375D01*
X264875Y854167D01*
X264667Y853917D01*
X264500Y853500D01*
X264458Y853125D01*
X264542Y852750D01*
X264667Y852500D01*
X264917Y852250D01*
X265208Y852083D01*
X265500Y852000D01*
X265792D01*
X266083Y852083D01*
X266333Y852208D01*
X266542Y852375D01*
G01X268600Y852000D02*
X268892Y852042D01*
X269225Y852167D01*
X269433Y852375D01*
X269517Y852667D01*
X269433Y852958D01*
X269183Y853208D01*
X268808Y853333D01*
X268392D01*
X268142Y853417D01*
X267933Y853625D01*
X267850Y853917D01*
X267975Y854208D01*
X268267Y854417D01*
X268600Y854500D01*
X268933Y854417D01*
X269225Y854208D01*
X269350Y853917D01*
X269267Y853625D01*
X269058Y853417D01*
X268808Y853333D01*
X268392D01*
X268017Y853208D01*
X267767Y852958D01*
X267683Y852667D01*
X267767Y852375D01*
X267975Y852167D01*
X268308Y852042D01*
X268600Y852000D01*
G01X270992Y852292D02*
X271283Y852083D01*
X271617Y852000D01*
X271950Y852083D01*
X272242Y852333D01*
X272450Y852708D01*
X272533Y853083D01*
Y853542D01*
X272450Y853917D01*
X272242Y854250D01*
X271992Y854417D01*
X271700Y854500D01*
X271367Y854417D01*
X271117Y854250D01*
X270950Y854000D01*
X270867Y853667D01*
X270950Y853375D01*
X271158Y853083D01*
X271408Y852917D01*
X271700Y852875D01*
X272033Y852958D01*
X272283Y853167D01*
X272533Y853542D01*
G01X273883Y852500D02*
X274133Y852208D01*
X274467Y852042D01*
X274842Y852000D01*
X275175Y852042D01*
X275508Y852250D01*
X275717Y852500D01*
X275758Y852750D01*
X275675Y853042D01*
X275383Y853250D01*
X275092Y853333D01*
X274717D01*
G01X275092D02*
X275342Y853458D01*
X275550Y853667D01*
X275633Y853917D01*
X275550Y854167D01*
X275342Y854375D01*
X274967Y854500D01*
X274592Y854458D01*
X274217Y854292D01*
G01X277900Y854500D02*
X277567Y854417D01*
X277317Y854208D01*
X277150Y853958D01*
X277025Y853625D01*
X276983Y853250D01*
X277025Y852875D01*
X277150Y852542D01*
X277317Y852292D01*
X277567Y852083D01*
X277900Y852000D01*
X278233Y852083D01*
X278483Y852292D01*
X278650Y852542D01*
X278775Y852875D01*
X278817Y853250D01*
X278775Y853625D01*
X278650Y853958D01*
X278483Y854208D01*
X278233Y854417D01*
X277900Y854500D01*
G01X272075Y1110867D02*
Y1113367D01*
G01X273825D02*
Y1110867D01*
G01Y1112117D02*
X272075D01*
G01X276550Y1110867D02*
Y1113367D01*
X275008Y1111575D01*
X277092D01*
G01X296138Y1206817D02*
X296013Y1206567D01*
X295930Y1206275D01*
Y1205942D01*
X296055Y1205567D01*
X296263Y1205275D01*
X296513Y1205067D01*
X296930Y1204900D01*
X297305Y1204858D01*
X297680Y1204942D01*
X297930Y1205067D01*
X298180Y1205317D01*
X298347Y1205608D01*
X298430Y1205900D01*
Y1206192D01*
X298347Y1206483D01*
X298222Y1206733D01*
X298055Y1206942D01*
G01X298430Y1209000D02*
X298388Y1209292D01*
X298263Y1209625D01*
X298055Y1209833D01*
X297763Y1209917D01*
X297472Y1209833D01*
X297222Y1209583D01*
X297097Y1209208D01*
Y1208792D01*
X297013Y1208542D01*
X296805Y1208333D01*
X296513Y1208250D01*
X296222Y1208375D01*
X296013Y1208667D01*
X295930Y1209000D01*
X296013Y1209333D01*
X296222Y1209625D01*
X296513Y1209750D01*
X296805Y1209667D01*
X297013Y1209458D01*
X297097Y1209208D01*
Y1208792D01*
X297222Y1208417D01*
X297472Y1208167D01*
X297763Y1208083D01*
X298055Y1208167D01*
X298263Y1208375D01*
X298388Y1208708D01*
X298430Y1209000D01*
G01X298138Y1211392D02*
X298347Y1211683D01*
X298430Y1212017D01*
X298347Y1212350D01*
X298097Y1212642D01*
X297722Y1212850D01*
X297347Y1212933D01*
X296888D01*
X296513Y1212850D01*
X296180Y1212642D01*
X296013Y1212392D01*
X295930Y1212100D01*
X296013Y1211767D01*
X296180Y1211517D01*
X296430Y1211350D01*
X296763Y1211267D01*
X297055Y1211350D01*
X297347Y1211558D01*
X297513Y1211808D01*
X297555Y1212100D01*
X297472Y1212433D01*
X297263Y1212683D01*
X296888Y1212933D01*
G01X298430Y1215200D02*
X295930D01*
X296430Y1214700D01*
G01X298430D02*
Y1215700D01*
G01Y1218300D02*
X295930D01*
X296430Y1217800D01*
G01X298430D02*
Y1218800D01*
G01X300747Y1206737D02*
X300622Y1206487D01*
X300539Y1206195D01*
Y1205862D01*
X300664Y1205487D01*
X300872Y1205195D01*
X301122Y1204987D01*
X301539Y1204820D01*
X301914Y1204778D01*
X302289Y1204862D01*
X302539Y1204987D01*
X302789Y1205237D01*
X302956Y1205528D01*
X303039Y1205820D01*
Y1206112D01*
X302956Y1206403D01*
X302831Y1206653D01*
X302664Y1206862D01*
G01X303039Y1208920D02*
X302997Y1209212D01*
X302872Y1209545D01*
X302664Y1209753D01*
X302372Y1209837D01*
X302081Y1209753D01*
X301831Y1209503D01*
X301706Y1209128D01*
Y1208712D01*
X301622Y1208462D01*
X301414Y1208253D01*
X301122Y1208170D01*
X300831Y1208295D01*
X300622Y1208587D01*
X300539Y1208920D01*
X300622Y1209253D01*
X300831Y1209545D01*
X301122Y1209670D01*
X301414Y1209587D01*
X301622Y1209378D01*
X301706Y1209128D01*
Y1208712D01*
X301831Y1208337D01*
X302081Y1208087D01*
X302372Y1208003D01*
X302664Y1208087D01*
X302872Y1208295D01*
X302997Y1208628D01*
X303039Y1208920D01*
G01X302747Y1211312D02*
X302956Y1211603D01*
X303039Y1211937D01*
X302956Y1212270D01*
X302706Y1212562D01*
X302331Y1212770D01*
X301956Y1212853D01*
X301497D01*
X301122Y1212770D01*
X300789Y1212562D01*
X300622Y1212312D01*
X300539Y1212020D01*
X300622Y1211687D01*
X300789Y1211437D01*
X301039Y1211270D01*
X301372Y1211187D01*
X301664Y1211270D01*
X301956Y1211478D01*
X302122Y1211728D01*
X302164Y1212020D01*
X302081Y1212353D01*
X301872Y1212603D01*
X301497Y1212853D01*
G01X303039Y1215120D02*
X300539D01*
X301039Y1214620D01*
G01X303039D02*
Y1215620D01*
G01X300956Y1217428D02*
X300706Y1217678D01*
X300581Y1217970D01*
X300539Y1218303D01*
X300622Y1218720D01*
X300831Y1219012D01*
X301081Y1219095D01*
X301331Y1219053D01*
X301539Y1218887D01*
X301956Y1218053D01*
X302247Y1217678D01*
X302664Y1217428D01*
X303039Y1217345D01*
Y1219095D01*
G01X318937Y1164391D02*
Y1166891D01*
X319937D01*
X320270Y1166766D01*
X320520Y1166474D01*
X320603Y1166141D01*
X320520Y1165808D01*
X320312Y1165558D01*
X319937Y1165433D01*
X318937D01*
G01X322037Y1164391D02*
Y1166891D01*
X323078D01*
X323412Y1166766D01*
X323620Y1166599D01*
X323703Y1166266D01*
X323620Y1165933D01*
X323370Y1165724D01*
X323078Y1165599D01*
X322037D01*
G01X323078D02*
X323703Y1164391D01*
G01X325262Y1164683D02*
X325553Y1164474D01*
X325887Y1164391D01*
X326220Y1164474D01*
X326512Y1164724D01*
X326720Y1165099D01*
X326803Y1165474D01*
Y1165933D01*
X326720Y1166308D01*
X326512Y1166641D01*
X326262Y1166808D01*
X325970Y1166891D01*
X325637Y1166808D01*
X325387Y1166641D01*
X325220Y1166391D01*
X325137Y1166058D01*
X325220Y1165766D01*
X325428Y1165474D01*
X325678Y1165308D01*
X325970Y1165266D01*
X326303Y1165349D01*
X326553Y1165558D01*
X326803Y1165933D01*
G01X329070Y1166891D02*
X328737Y1166808D01*
X328487Y1166599D01*
X328320Y1166349D01*
X328195Y1166016D01*
X328153Y1165641D01*
X328195Y1165266D01*
X328320Y1164933D01*
X328487Y1164683D01*
X328737Y1164474D01*
X329070Y1164391D01*
X329403Y1164474D01*
X329653Y1164683D01*
X329820Y1164933D01*
X329945Y1165266D01*
X329987Y1165641D01*
X329945Y1166016D01*
X329820Y1166349D01*
X329653Y1166599D01*
X329403Y1166808D01*
X329070Y1166891D01*
G01X331253Y1164891D02*
X331503Y1164599D01*
X331837Y1164433D01*
X332212Y1164391D01*
X332545Y1164433D01*
X332878Y1164641D01*
X333087Y1164891D01*
X333128Y1165141D01*
X333045Y1165433D01*
X332753Y1165641D01*
X332462Y1165724D01*
X332087D01*
G01X332462D02*
X332712Y1165849D01*
X332920Y1166058D01*
X333003Y1166308D01*
X332920Y1166558D01*
X332712Y1166766D01*
X332337Y1166891D01*
X331962Y1166849D01*
X331587Y1166683D01*
G01X335270Y1164391D02*
X335562Y1164433D01*
X335895Y1164558D01*
X336103Y1164766D01*
X336187Y1165058D01*
X336103Y1165349D01*
X335853Y1165599D01*
X335478Y1165724D01*
X335062D01*
X334812Y1165808D01*
X334603Y1166016D01*
X334520Y1166308D01*
X334645Y1166599D01*
X334937Y1166808D01*
X335270Y1166891D01*
X335603Y1166808D01*
X335895Y1166599D01*
X336020Y1166308D01*
X335937Y1166016D01*
X335728Y1165808D01*
X335478Y1165724D01*
X335062D01*
X334687Y1165599D01*
X334437Y1165349D01*
X334353Y1165058D01*
X334437Y1164766D01*
X334645Y1164558D01*
X334978Y1164433D01*
X335270Y1164391D01*
G01X324987Y1146891D02*
Y1149391D01*
X326028D01*
X326362Y1149266D01*
X326570Y1149099D01*
X326653Y1148766D01*
X326570Y1148433D01*
X326320Y1148224D01*
X326028Y1148099D01*
X324987D01*
G01X326028D02*
X326653Y1146891D01*
G01X328212Y1147183D02*
X328503Y1146974D01*
X328837Y1146891D01*
X329170Y1146974D01*
X329462Y1147224D01*
X329670Y1147599D01*
X329753Y1147974D01*
Y1148433D01*
X329670Y1148808D01*
X329462Y1149141D01*
X329212Y1149308D01*
X328920Y1149391D01*
X328587Y1149308D01*
X328337Y1149141D01*
X328170Y1148891D01*
X328087Y1148558D01*
X328170Y1148266D01*
X328378Y1147974D01*
X328628Y1147808D01*
X328920Y1147766D01*
X329253Y1147849D01*
X329503Y1148058D01*
X329753Y1148433D01*
G01X332020Y1149391D02*
X331687Y1149308D01*
X331437Y1149099D01*
X331270Y1148849D01*
X331145Y1148516D01*
X331103Y1148141D01*
X331145Y1147766D01*
X331270Y1147433D01*
X331437Y1147183D01*
X331687Y1146974D01*
X332020Y1146891D01*
X332353Y1146974D01*
X332603Y1147183D01*
X332770Y1147433D01*
X332895Y1147766D01*
X332937Y1148141D01*
X332895Y1148516D01*
X332770Y1148849D01*
X332603Y1149099D01*
X332353Y1149308D01*
X332020Y1149391D01*
G01X334203Y1147391D02*
X334453Y1147099D01*
X334787Y1146933D01*
X335162Y1146891D01*
X335495Y1146933D01*
X335828Y1147141D01*
X336037Y1147391D01*
X336078Y1147641D01*
X335995Y1147933D01*
X335703Y1148141D01*
X335412Y1148224D01*
X335037D01*
G01X335412D02*
X335662Y1148349D01*
X335870Y1148558D01*
X335953Y1148808D01*
X335870Y1149058D01*
X335662Y1149266D01*
X335287Y1149391D01*
X334912Y1149349D01*
X334537Y1149183D01*
G01X338137Y1146891D02*
X338220Y1147433D01*
X338345Y1147891D01*
X338512Y1148308D01*
X338720Y1148766D01*
X339053Y1149391D01*
X337387D01*
G01X336200Y1172500D02*
Y1176500D01*
X328800D01*
G01X324987Y1150891D02*
Y1153391D01*
X326028D01*
X326362Y1153266D01*
X326570Y1153099D01*
X326653Y1152766D01*
X326570Y1152433D01*
X326320Y1152224D01*
X326028Y1152099D01*
X324987D01*
G01X326028D02*
X326653Y1150891D01*
G01X328212Y1151183D02*
X328503Y1150974D01*
X328837Y1150891D01*
X329170Y1150974D01*
X329462Y1151224D01*
X329670Y1151599D01*
X329753Y1151974D01*
Y1152433D01*
X329670Y1152808D01*
X329462Y1153141D01*
X329212Y1153308D01*
X328920Y1153391D01*
X328587Y1153308D01*
X328337Y1153141D01*
X328170Y1152891D01*
X328087Y1152558D01*
X328170Y1152266D01*
X328378Y1151974D01*
X328628Y1151808D01*
X328920Y1151766D01*
X329253Y1151849D01*
X329503Y1152058D01*
X329753Y1152433D01*
G01X332020Y1153391D02*
X331687Y1153308D01*
X331437Y1153099D01*
X331270Y1152849D01*
X331145Y1152516D01*
X331103Y1152141D01*
X331145Y1151766D01*
X331270Y1151433D01*
X331437Y1151183D01*
X331687Y1150974D01*
X332020Y1150891D01*
X332353Y1150974D01*
X332603Y1151183D01*
X332770Y1151433D01*
X332895Y1151766D01*
X332937Y1152141D01*
X332895Y1152516D01*
X332770Y1152849D01*
X332603Y1153099D01*
X332353Y1153308D01*
X332020Y1153391D01*
G01X334412Y1151183D02*
X334703Y1150974D01*
X335037Y1150891D01*
X335370Y1150974D01*
X335662Y1151224D01*
X335870Y1151599D01*
X335953Y1151974D01*
Y1152433D01*
X335870Y1152808D01*
X335662Y1153141D01*
X335412Y1153308D01*
X335120Y1153391D01*
X334787Y1153308D01*
X334537Y1153141D01*
X334370Y1152891D01*
X334287Y1152558D01*
X334370Y1152266D01*
X334578Y1151974D01*
X334828Y1151808D01*
X335120Y1151766D01*
X335453Y1151849D01*
X335703Y1152058D01*
X335953Y1152433D01*
G01X337428Y1152974D02*
X337678Y1153224D01*
X337970Y1153349D01*
X338303Y1153391D01*
X338720Y1153308D01*
X339012Y1153099D01*
X339095Y1152849D01*
X339053Y1152599D01*
X338887Y1152391D01*
X338053Y1151974D01*
X337678Y1151683D01*
X337428Y1151266D01*
X337345Y1150891D01*
X339095D01*
G01X328800Y1180500D02*
Y1176500D01*
X336200D01*
G01X320487Y1168391D02*
Y1170891D01*
X321528D01*
X321862Y1170766D01*
X322070Y1170599D01*
X322153Y1170266D01*
X322070Y1169933D01*
X321820Y1169724D01*
X321528Y1169599D01*
X320487D01*
G01X321528D02*
X322153Y1168391D01*
G01X323712Y1168683D02*
X324003Y1168474D01*
X324337Y1168391D01*
X324670Y1168474D01*
X324962Y1168724D01*
X325170Y1169099D01*
X325253Y1169474D01*
Y1169933D01*
X325170Y1170308D01*
X324962Y1170641D01*
X324712Y1170808D01*
X324420Y1170891D01*
X324087Y1170808D01*
X323837Y1170641D01*
X323670Y1170391D01*
X323587Y1170058D01*
X323670Y1169766D01*
X323878Y1169474D01*
X324128Y1169308D01*
X324420Y1169266D01*
X324753Y1169349D01*
X325003Y1169558D01*
X325253Y1169933D01*
G01X327520Y1170891D02*
X327187Y1170808D01*
X326937Y1170599D01*
X326770Y1170349D01*
X326645Y1170016D01*
X326603Y1169641D01*
X326645Y1169266D01*
X326770Y1168933D01*
X326937Y1168683D01*
X327187Y1168474D01*
X327520Y1168391D01*
X327853Y1168474D01*
X328103Y1168683D01*
X328270Y1168933D01*
X328395Y1169266D01*
X328437Y1169641D01*
X328395Y1170016D01*
X328270Y1170349D01*
X328103Y1170599D01*
X327853Y1170808D01*
X327520Y1170891D01*
G01X329912Y1168683D02*
X330203Y1168474D01*
X330537Y1168391D01*
X330870Y1168474D01*
X331162Y1168724D01*
X331370Y1169099D01*
X331453Y1169474D01*
Y1169933D01*
X331370Y1170308D01*
X331162Y1170641D01*
X330912Y1170808D01*
X330620Y1170891D01*
X330287Y1170808D01*
X330037Y1170641D01*
X329870Y1170391D01*
X329787Y1170058D01*
X329870Y1169766D01*
X330078Y1169474D01*
X330328Y1169308D01*
X330620Y1169266D01*
X330953Y1169349D01*
X331203Y1169558D01*
X331453Y1169933D01*
G01X332803Y1168891D02*
X333053Y1168599D01*
X333387Y1168433D01*
X333762Y1168391D01*
X334095Y1168433D01*
X334428Y1168641D01*
X334637Y1168891D01*
X334678Y1169141D01*
X334595Y1169433D01*
X334303Y1169641D01*
X334012Y1169724D01*
X333637D01*
G01X334012D02*
X334262Y1169849D01*
X334470Y1170058D01*
X334553Y1170308D01*
X334470Y1170558D01*
X334262Y1170766D01*
X333887Y1170891D01*
X333512Y1170849D01*
X333137Y1170683D01*
G01X322800Y1212000D02*
Y1208000D01*
X330200D01*
G01X277167Y1208800D02*
Y1211300D01*
X278208D01*
X278542Y1211175D01*
X278750Y1211008D01*
X278833Y1210675D01*
X278750Y1210342D01*
X278500Y1210133D01*
X278208Y1210008D01*
X277167D01*
G01X278208D02*
X278833Y1208800D01*
G01X280392Y1209092D02*
X280683Y1208883D01*
X281017Y1208800D01*
X281350Y1208883D01*
X281642Y1209133D01*
X281850Y1209508D01*
X281933Y1209883D01*
Y1210342D01*
X281850Y1210717D01*
X281642Y1211050D01*
X281392Y1211217D01*
X281100Y1211300D01*
X280767Y1211217D01*
X280517Y1211050D01*
X280350Y1210800D01*
X280267Y1210467D01*
X280350Y1210175D01*
X280558Y1209883D01*
X280808Y1209717D01*
X281100Y1209675D01*
X281433Y1209758D01*
X281683Y1209967D01*
X281933Y1210342D01*
G01X283283Y1209300D02*
X283533Y1209008D01*
X283867Y1208842D01*
X284242Y1208800D01*
X284575Y1208842D01*
X284908Y1209050D01*
X285117Y1209300D01*
X285158Y1209550D01*
X285075Y1209842D01*
X284783Y1210050D01*
X284492Y1210133D01*
X284117D01*
G01X284492D02*
X284742Y1210258D01*
X284950Y1210467D01*
X285033Y1210717D01*
X284950Y1210967D01*
X284742Y1211175D01*
X284367Y1211300D01*
X283992Y1211258D01*
X283617Y1211092D01*
G01X286383Y1209175D02*
X286633Y1208967D01*
X286925Y1208842D01*
X287300Y1208800D01*
X287675Y1208883D01*
X287967Y1209050D01*
X288175Y1209342D01*
X288217Y1209675D01*
X288133Y1210008D01*
X287925Y1210217D01*
X287633Y1210383D01*
X287342Y1210425D01*
X287050Y1210383D01*
X286675Y1210217D01*
X286800Y1211300D01*
X287925D01*
G01X290400Y1208800D02*
Y1211300D01*
X289900Y1210800D01*
G01Y1208800D02*
X290900D01*
G01X322800Y1207800D02*
Y1203800D01*
X330200D01*
G01X326537Y1154891D02*
Y1157391D01*
X327578D01*
X327912Y1157266D01*
X328120Y1157099D01*
X328203Y1156766D01*
X328120Y1156433D01*
X327870Y1156224D01*
X327578Y1156099D01*
X326537D01*
G01X327578D02*
X328203Y1154891D01*
G01X330970D02*
Y1157391D01*
X329428Y1155599D01*
X331512D01*
G01X332778Y1156974D02*
X333028Y1157224D01*
X333320Y1157349D01*
X333653Y1157391D01*
X334070Y1157308D01*
X334362Y1157099D01*
X334445Y1156849D01*
X334403Y1156599D01*
X334237Y1156391D01*
X333403Y1155974D01*
X333028Y1155683D01*
X332778Y1155266D01*
X332695Y1154891D01*
X334445D01*
G01X336670D02*
Y1157391D01*
X336170Y1156891D01*
G01Y1154891D02*
X337170D01*
G01X328800Y1184500D02*
Y1180500D01*
X336200D01*
G01X324017Y1159500D02*
Y1162000D01*
X325058D01*
X325392Y1161875D01*
X325600Y1161708D01*
X325683Y1161375D01*
X325600Y1161042D01*
X325350Y1160833D01*
X325058Y1160708D01*
X324017D01*
G01X325058D02*
X325683Y1159500D01*
G01X328450D02*
Y1162000D01*
X326908Y1160208D01*
X328992D01*
G01X330258Y1161583D02*
X330508Y1161833D01*
X330800Y1161958D01*
X331133Y1162000D01*
X331550Y1161917D01*
X331842Y1161708D01*
X331925Y1161458D01*
X331883Y1161208D01*
X331717Y1161000D01*
X330883Y1160583D01*
X330508Y1160292D01*
X330258Y1159875D01*
X330175Y1159500D01*
X331925D01*
G01X333358Y1161583D02*
X333608Y1161833D01*
X333900Y1161958D01*
X334233Y1162000D01*
X334650Y1161917D01*
X334942Y1161708D01*
X335025Y1161458D01*
X334983Y1161208D01*
X334817Y1161000D01*
X333983Y1160583D01*
X333608Y1160292D01*
X333358Y1159875D01*
X333275Y1159500D01*
X335025D01*
G01X328800Y1188500D02*
Y1184500D01*
X336200D01*
G01X301826Y1157319D02*
X299326D01*
Y1158360D01*
X299451Y1158694D01*
X299618Y1158902D01*
X299951Y1158985D01*
X300284Y1158902D01*
X300493Y1158652D01*
X300618Y1158360D01*
Y1157319D01*
G01Y1158360D02*
X301826Y1158985D01*
G01X301534Y1160544D02*
X301743Y1160835D01*
X301826Y1161169D01*
X301743Y1161502D01*
X301493Y1161794D01*
X301118Y1162002D01*
X300743Y1162085D01*
X300284D01*
X299909Y1162002D01*
X299576Y1161794D01*
X299409Y1161544D01*
X299326Y1161252D01*
X299409Y1160919D01*
X299576Y1160669D01*
X299826Y1160502D01*
X300159Y1160419D01*
X300451Y1160502D01*
X300743Y1160710D01*
X300909Y1160960D01*
X300951Y1161252D01*
X300868Y1161585D01*
X300659Y1161835D01*
X300284Y1162085D01*
G01X301534Y1163644D02*
X301743Y1163935D01*
X301826Y1164269D01*
X301743Y1164602D01*
X301493Y1164894D01*
X301118Y1165102D01*
X300743Y1165185D01*
X300284D01*
X299909Y1165102D01*
X299576Y1164894D01*
X299409Y1164644D01*
X299326Y1164352D01*
X299409Y1164019D01*
X299576Y1163769D01*
X299826Y1163602D01*
X300159Y1163519D01*
X300451Y1163602D01*
X300743Y1163810D01*
X300909Y1164060D01*
X300951Y1164352D01*
X300868Y1164685D01*
X300659Y1164935D01*
X300284Y1165185D01*
G01X300784Y1166660D02*
X300493Y1166952D01*
X300326Y1167202D01*
X300243Y1167535D01*
X300326Y1167827D01*
X300493Y1168035D01*
X300743Y1168202D01*
X301034Y1168244D01*
X301284Y1168202D01*
X301534Y1168035D01*
X301743Y1167785D01*
X301826Y1167494D01*
X301743Y1167160D01*
X301493Y1166869D01*
X301118Y1166702D01*
X300701Y1166660D01*
X300159Y1166744D01*
X299868Y1166869D01*
X299576Y1167077D01*
X299368Y1167369D01*
X299326Y1167660D01*
X299409Y1167952D01*
X299618Y1168160D01*
G01X300784Y1169760D02*
X300493Y1170052D01*
X300326Y1170302D01*
X300243Y1170635D01*
X300326Y1170927D01*
X300493Y1171135D01*
X300743Y1171302D01*
X301034Y1171344D01*
X301284Y1171302D01*
X301534Y1171135D01*
X301743Y1170885D01*
X301826Y1170594D01*
X301743Y1170260D01*
X301493Y1169969D01*
X301118Y1169802D01*
X300701Y1169760D01*
X300159Y1169844D01*
X299868Y1169969D01*
X299576Y1170177D01*
X299368Y1170469D01*
X299326Y1170760D01*
X299409Y1171052D01*
X299618Y1171260D01*
G01X307200Y1199450D02*
X303200D01*
Y1192050D01*
G01X302226Y1174419D02*
X299726D01*
Y1175460D01*
X299851Y1175794D01*
X300018Y1176002D01*
X300351Y1176085D01*
X300684Y1176002D01*
X300893Y1175752D01*
X301018Y1175460D01*
Y1174419D01*
G01Y1175460D02*
X302226Y1176085D01*
G01X301934Y1177644D02*
X302143Y1177935D01*
X302226Y1178269D01*
X302143Y1178602D01*
X301893Y1178894D01*
X301518Y1179102D01*
X301143Y1179185D01*
X300684D01*
X300309Y1179102D01*
X299976Y1178894D01*
X299809Y1178644D01*
X299726Y1178352D01*
X299809Y1178019D01*
X299976Y1177769D01*
X300226Y1177602D01*
X300559Y1177519D01*
X300851Y1177602D01*
X301143Y1177810D01*
X301309Y1178060D01*
X301351Y1178352D01*
X301268Y1178685D01*
X301059Y1178935D01*
X300684Y1179185D01*
G01X301934Y1180744D02*
X302143Y1181035D01*
X302226Y1181369D01*
X302143Y1181702D01*
X301893Y1181994D01*
X301518Y1182202D01*
X301143Y1182285D01*
X300684D01*
X300309Y1182202D01*
X299976Y1181994D01*
X299809Y1181744D01*
X299726Y1181452D01*
X299809Y1181119D01*
X299976Y1180869D01*
X300226Y1180702D01*
X300559Y1180619D01*
X300851Y1180702D01*
X301143Y1180910D01*
X301309Y1181160D01*
X301351Y1181452D01*
X301268Y1181785D01*
X301059Y1182035D01*
X300684Y1182285D01*
G01X301184Y1183760D02*
X300893Y1184052D01*
X300726Y1184302D01*
X300643Y1184635D01*
X300726Y1184927D01*
X300893Y1185135D01*
X301143Y1185302D01*
X301434Y1185344D01*
X301684Y1185302D01*
X301934Y1185135D01*
X302143Y1184885D01*
X302226Y1184594D01*
X302143Y1184260D01*
X301893Y1183969D01*
X301518Y1183802D01*
X301101Y1183760D01*
X300559Y1183844D01*
X300268Y1183969D01*
X299976Y1184177D01*
X299768Y1184469D01*
X299726Y1184760D01*
X299809Y1185052D01*
X300018Y1185260D01*
G01X301851Y1186735D02*
X302059Y1186985D01*
X302184Y1187277D01*
X302226Y1187652D01*
X302143Y1188027D01*
X301976Y1188319D01*
X301684Y1188527D01*
X301351Y1188569D01*
X301018Y1188485D01*
X300809Y1188277D01*
X300643Y1187985D01*
X300601Y1187694D01*
X300643Y1187402D01*
X300809Y1187027D01*
X299726Y1187152D01*
Y1188277D01*
G01X303200Y1199550D02*
X307200D01*
Y1206950D01*
G01X306726Y1174019D02*
X304226D01*
Y1175060D01*
X304351Y1175394D01*
X304518Y1175602D01*
X304851Y1175685D01*
X305184Y1175602D01*
X305393Y1175352D01*
X305518Y1175060D01*
Y1174019D01*
G01Y1175060D02*
X306726Y1175685D01*
G01X306434Y1177244D02*
X306643Y1177535D01*
X306726Y1177869D01*
X306643Y1178202D01*
X306393Y1178494D01*
X306018Y1178702D01*
X305643Y1178785D01*
X305184D01*
X304809Y1178702D01*
X304476Y1178494D01*
X304309Y1178244D01*
X304226Y1177952D01*
X304309Y1177619D01*
X304476Y1177369D01*
X304726Y1177202D01*
X305059Y1177119D01*
X305351Y1177202D01*
X305643Y1177410D01*
X305809Y1177660D01*
X305851Y1177952D01*
X305768Y1178285D01*
X305559Y1178535D01*
X305184Y1178785D01*
G01X306434Y1180344D02*
X306643Y1180635D01*
X306726Y1180969D01*
X306643Y1181302D01*
X306393Y1181594D01*
X306018Y1181802D01*
X305643Y1181885D01*
X305184D01*
X304809Y1181802D01*
X304476Y1181594D01*
X304309Y1181344D01*
X304226Y1181052D01*
X304309Y1180719D01*
X304476Y1180469D01*
X304726Y1180302D01*
X305059Y1180219D01*
X305351Y1180302D01*
X305643Y1180510D01*
X305809Y1180760D01*
X305851Y1181052D01*
X305768Y1181385D01*
X305559Y1181635D01*
X305184Y1181885D01*
G01X305684Y1183360D02*
X305393Y1183652D01*
X305226Y1183902D01*
X305143Y1184235D01*
X305226Y1184527D01*
X305393Y1184735D01*
X305643Y1184902D01*
X305934Y1184944D01*
X306184Y1184902D01*
X306434Y1184735D01*
X306643Y1184485D01*
X306726Y1184194D01*
X306643Y1183860D01*
X306393Y1183569D01*
X306018Y1183402D01*
X305601Y1183360D01*
X305059Y1183444D01*
X304768Y1183569D01*
X304476Y1183777D01*
X304268Y1184069D01*
X304226Y1184360D01*
X304309Y1184652D01*
X304518Y1184860D01*
G01X306226Y1186335D02*
X306518Y1186585D01*
X306684Y1186919D01*
X306726Y1187294D01*
X306684Y1187627D01*
X306476Y1187960D01*
X306226Y1188169D01*
X305976Y1188210D01*
X305684Y1188127D01*
X305476Y1187835D01*
X305393Y1187544D01*
Y1187169D01*
G01Y1187544D02*
X305268Y1187794D01*
X305059Y1188002D01*
X304809Y1188085D01*
X304559Y1188002D01*
X304351Y1187794D01*
X304226Y1187419D01*
X304268Y1187044D01*
X304434Y1186669D01*
G01X311300Y1206950D02*
X307300D01*
Y1199550D01*
G01X306226Y1157319D02*
X303726D01*
Y1158360D01*
X303851Y1158694D01*
X304018Y1158902D01*
X304351Y1158985D01*
X304684Y1158902D01*
X304893Y1158652D01*
X305018Y1158360D01*
Y1157319D01*
G01Y1158360D02*
X306226Y1158985D01*
G01X305934Y1160544D02*
X306143Y1160835D01*
X306226Y1161169D01*
X306143Y1161502D01*
X305893Y1161794D01*
X305518Y1162002D01*
X305143Y1162085D01*
X304684D01*
X304309Y1162002D01*
X303976Y1161794D01*
X303809Y1161544D01*
X303726Y1161252D01*
X303809Y1160919D01*
X303976Y1160669D01*
X304226Y1160502D01*
X304559Y1160419D01*
X304851Y1160502D01*
X305143Y1160710D01*
X305309Y1160960D01*
X305351Y1161252D01*
X305268Y1161585D01*
X305059Y1161835D01*
X304684Y1162085D01*
G01X305934Y1163644D02*
X306143Y1163935D01*
X306226Y1164269D01*
X306143Y1164602D01*
X305893Y1164894D01*
X305518Y1165102D01*
X305143Y1165185D01*
X304684D01*
X304309Y1165102D01*
X303976Y1164894D01*
X303809Y1164644D01*
X303726Y1164352D01*
X303809Y1164019D01*
X303976Y1163769D01*
X304226Y1163602D01*
X304559Y1163519D01*
X304851Y1163602D01*
X305143Y1163810D01*
X305309Y1164060D01*
X305351Y1164352D01*
X305268Y1164685D01*
X305059Y1164935D01*
X304684Y1165185D01*
G01X305184Y1166660D02*
X304893Y1166952D01*
X304726Y1167202D01*
X304643Y1167535D01*
X304726Y1167827D01*
X304893Y1168035D01*
X305143Y1168202D01*
X305434Y1168244D01*
X305684Y1168202D01*
X305934Y1168035D01*
X306143Y1167785D01*
X306226Y1167494D01*
X306143Y1167160D01*
X305893Y1166869D01*
X305518Y1166702D01*
X305101Y1166660D01*
X304559Y1166744D01*
X304268Y1166869D01*
X303976Y1167077D01*
X303768Y1167369D01*
X303726Y1167660D01*
X303809Y1167952D01*
X304018Y1168160D01*
G01X304143Y1169760D02*
X303893Y1170010D01*
X303768Y1170302D01*
X303726Y1170635D01*
X303809Y1171052D01*
X304018Y1171344D01*
X304268Y1171427D01*
X304518Y1171385D01*
X304726Y1171219D01*
X305143Y1170385D01*
X305434Y1170010D01*
X305851Y1169760D01*
X306226Y1169677D01*
Y1171427D01*
G01X307300Y1192050D02*
X311300D01*
Y1199450D01*
G01X318600Y1172867D02*
X316100D01*
Y1173908D01*
X316225Y1174242D01*
X316392Y1174450D01*
X316725Y1174533D01*
X317058Y1174450D01*
X317267Y1174200D01*
X317392Y1173908D01*
Y1172867D01*
G01Y1173908D02*
X318600Y1174533D01*
G01X318308Y1176092D02*
X318517Y1176383D01*
X318600Y1176717D01*
X318517Y1177050D01*
X318267Y1177342D01*
X317892Y1177550D01*
X317517Y1177633D01*
X317058D01*
X316683Y1177550D01*
X316350Y1177342D01*
X316183Y1177092D01*
X316100Y1176800D01*
X316183Y1176467D01*
X316350Y1176217D01*
X316600Y1176050D01*
X316933Y1175967D01*
X317225Y1176050D01*
X317517Y1176258D01*
X317683Y1176508D01*
X317725Y1176800D01*
X317642Y1177133D01*
X317433Y1177383D01*
X317058Y1177633D01*
G01X318308Y1179192D02*
X318517Y1179483D01*
X318600Y1179817D01*
X318517Y1180150D01*
X318267Y1180442D01*
X317892Y1180650D01*
X317517Y1180733D01*
X317058D01*
X316683Y1180650D01*
X316350Y1180442D01*
X316183Y1180192D01*
X316100Y1179900D01*
X316183Y1179567D01*
X316350Y1179317D01*
X316600Y1179150D01*
X316933Y1179067D01*
X317225Y1179150D01*
X317517Y1179358D01*
X317683Y1179608D01*
X317725Y1179900D01*
X317642Y1180233D01*
X317433Y1180483D01*
X317058Y1180733D01*
G01X317558Y1182208D02*
X317267Y1182500D01*
X317100Y1182750D01*
X317017Y1183083D01*
X317100Y1183375D01*
X317267Y1183583D01*
X317517Y1183750D01*
X317808Y1183792D01*
X318058Y1183750D01*
X318308Y1183583D01*
X318517Y1183333D01*
X318600Y1183042D01*
X318517Y1182708D01*
X318267Y1182417D01*
X317892Y1182250D01*
X317475Y1182208D01*
X316933Y1182292D01*
X316642Y1182417D01*
X316350Y1182625D01*
X316142Y1182917D01*
X316100Y1183208D01*
X316183Y1183500D01*
X316392Y1183708D01*
G01X318600Y1186600D02*
X316100D01*
X317892Y1185058D01*
Y1187142D01*
G01X316917Y1266392D02*
X316667Y1266517D01*
X316375Y1266600D01*
X316042D01*
X315667Y1266475D01*
X315375Y1266267D01*
X315167Y1266017D01*
X315000Y1265600D01*
X314958Y1265225D01*
X315042Y1264850D01*
X315167Y1264600D01*
X315417Y1264350D01*
X315708Y1264183D01*
X316000Y1264100D01*
X316292D01*
X316583Y1264183D01*
X316833Y1264308D01*
X317042Y1264475D01*
G01X318392Y1264392D02*
X318683Y1264183D01*
X319017Y1264100D01*
X319350Y1264183D01*
X319642Y1264433D01*
X319850Y1264808D01*
X319933Y1265183D01*
Y1265642D01*
X319850Y1266017D01*
X319642Y1266350D01*
X319392Y1266517D01*
X319100Y1266600D01*
X318767Y1266517D01*
X318517Y1266350D01*
X318350Y1266100D01*
X318267Y1265767D01*
X318350Y1265475D01*
X318558Y1265183D01*
X318808Y1265017D01*
X319100Y1264975D01*
X319433Y1265058D01*
X319683Y1265267D01*
X319933Y1265642D01*
G01X321283Y1264600D02*
X321533Y1264308D01*
X321867Y1264142D01*
X322242Y1264100D01*
X322575Y1264142D01*
X322908Y1264350D01*
X323117Y1264600D01*
X323158Y1264850D01*
X323075Y1265142D01*
X322783Y1265350D01*
X322492Y1265433D01*
X322117D01*
G01X322492D02*
X322742Y1265558D01*
X322950Y1265767D01*
X323033Y1266017D01*
X322950Y1266267D01*
X322742Y1266475D01*
X322367Y1266600D01*
X321992Y1266558D01*
X321617Y1266392D01*
G01X325800Y1264100D02*
Y1266600D01*
X324258Y1264808D01*
X326342D01*
G01X327692Y1264392D02*
X327983Y1264183D01*
X328317Y1264100D01*
X328650Y1264183D01*
X328942Y1264433D01*
X329150Y1264808D01*
X329233Y1265183D01*
Y1265642D01*
X329150Y1266017D01*
X328942Y1266350D01*
X328692Y1266517D01*
X328400Y1266600D01*
X328067Y1266517D01*
X327817Y1266350D01*
X327650Y1266100D01*
X327567Y1265767D01*
X327650Y1265475D01*
X327858Y1265183D01*
X328108Y1265017D01*
X328400Y1264975D01*
X328733Y1265058D01*
X328983Y1265267D01*
X329233Y1265642D01*
G01X318008Y1245167D02*
X317883Y1244917D01*
X317800Y1244625D01*
Y1244292D01*
X317925Y1243917D01*
X318133Y1243625D01*
X318383Y1243417D01*
X318800Y1243250D01*
X319175Y1243208D01*
X319550Y1243292D01*
X319800Y1243417D01*
X320050Y1243667D01*
X320217Y1243958D01*
X320300Y1244250D01*
Y1244542D01*
X320217Y1244833D01*
X320092Y1245083D01*
X319925Y1245292D01*
G01X320008Y1246642D02*
X320217Y1246933D01*
X320300Y1247267D01*
X320217Y1247600D01*
X319967Y1247892D01*
X319592Y1248100D01*
X319217Y1248183D01*
X318758D01*
X318383Y1248100D01*
X318050Y1247892D01*
X317883Y1247642D01*
X317800Y1247350D01*
X317883Y1247017D01*
X318050Y1246767D01*
X318300Y1246600D01*
X318633Y1246517D01*
X318925Y1246600D01*
X319217Y1246808D01*
X319383Y1247058D01*
X319425Y1247350D01*
X319342Y1247683D01*
X319133Y1247933D01*
X318758Y1248183D01*
G01X320300Y1250950D02*
X317800D01*
X319592Y1249408D01*
Y1251492D01*
G01X318217Y1252758D02*
X317967Y1253008D01*
X317842Y1253300D01*
X317800Y1253633D01*
X317883Y1254050D01*
X318092Y1254342D01*
X318342Y1254425D01*
X318592Y1254383D01*
X318800Y1254217D01*
X319217Y1253383D01*
X319508Y1253008D01*
X319925Y1252758D01*
X320300Y1252675D01*
Y1254425D01*
G01X319925Y1255733D02*
X320133Y1255983D01*
X320258Y1256275D01*
X320300Y1256650D01*
X320217Y1257025D01*
X320050Y1257317D01*
X319758Y1257525D01*
X319425Y1257567D01*
X319092Y1257483D01*
X318883Y1257275D01*
X318717Y1256983D01*
X318675Y1256692D01*
X318717Y1256400D01*
X318883Y1256025D01*
X317800Y1256150D01*
Y1257275D01*
G01X300717Y1266492D02*
X300467Y1266617D01*
X300175Y1266700D01*
X299842D01*
X299467Y1266575D01*
X299175Y1266367D01*
X298967Y1266117D01*
X298800Y1265700D01*
X298758Y1265325D01*
X298842Y1264950D01*
X298967Y1264700D01*
X299217Y1264450D01*
X299508Y1264283D01*
X299800Y1264200D01*
X300092D01*
X300383Y1264283D01*
X300633Y1264408D01*
X300842Y1264575D01*
G01X302192Y1264492D02*
X302483Y1264283D01*
X302817Y1264200D01*
X303150Y1264283D01*
X303442Y1264533D01*
X303650Y1264908D01*
X303733Y1265283D01*
Y1265742D01*
X303650Y1266117D01*
X303442Y1266450D01*
X303192Y1266617D01*
X302900Y1266700D01*
X302567Y1266617D01*
X302317Y1266450D01*
X302150Y1266200D01*
X302067Y1265867D01*
X302150Y1265575D01*
X302358Y1265283D01*
X302608Y1265117D01*
X302900Y1265075D01*
X303233Y1265158D01*
X303483Y1265367D01*
X303733Y1265742D01*
G01X305083Y1264700D02*
X305333Y1264408D01*
X305667Y1264242D01*
X306042Y1264200D01*
X306375Y1264242D01*
X306708Y1264450D01*
X306917Y1264700D01*
X306958Y1264950D01*
X306875Y1265242D01*
X306583Y1265450D01*
X306292Y1265533D01*
X305917D01*
G01X306292D02*
X306542Y1265658D01*
X306750Y1265867D01*
X306833Y1266117D01*
X306750Y1266367D01*
X306542Y1266575D01*
X306167Y1266700D01*
X305792Y1266658D01*
X305417Y1266492D01*
G01X309017Y1264200D02*
X309100Y1264742D01*
X309225Y1265200D01*
X309392Y1265617D01*
X309600Y1266075D01*
X309933Y1266700D01*
X308267D01*
G01X312200Y1264200D02*
Y1266700D01*
X311700Y1266200D01*
G01Y1264200D02*
X312700D01*
G01X322008Y1245167D02*
X321883Y1244917D01*
X321800Y1244625D01*
Y1244292D01*
X321925Y1243917D01*
X322133Y1243625D01*
X322383Y1243417D01*
X322800Y1243250D01*
X323175Y1243208D01*
X323550Y1243292D01*
X323800Y1243417D01*
X324050Y1243667D01*
X324217Y1243958D01*
X324300Y1244250D01*
Y1244542D01*
X324217Y1244833D01*
X324092Y1245083D01*
X323925Y1245292D01*
G01X324300Y1247350D02*
X324258Y1247642D01*
X324133Y1247975D01*
X323925Y1248183D01*
X323633Y1248267D01*
X323342Y1248183D01*
X323092Y1247933D01*
X322967Y1247558D01*
Y1247142D01*
X322883Y1246892D01*
X322675Y1246683D01*
X322383Y1246600D01*
X322092Y1246725D01*
X321883Y1247017D01*
X321800Y1247350D01*
X321883Y1247683D01*
X322092Y1247975D01*
X322383Y1248100D01*
X322675Y1248017D01*
X322883Y1247808D01*
X322967Y1247558D01*
Y1247142D01*
X323092Y1246767D01*
X323342Y1246517D01*
X323633Y1246433D01*
X323925Y1246517D01*
X324133Y1246725D01*
X324258Y1247058D01*
X324300Y1247350D01*
G01Y1250450D02*
X324258Y1250742D01*
X324133Y1251075D01*
X323925Y1251283D01*
X323633Y1251367D01*
X323342Y1251283D01*
X323092Y1251033D01*
X322967Y1250658D01*
Y1250242D01*
X322883Y1249992D01*
X322675Y1249783D01*
X322383Y1249700D01*
X322092Y1249825D01*
X321883Y1250117D01*
X321800Y1250450D01*
X321883Y1250783D01*
X322092Y1251075D01*
X322383Y1251200D01*
X322675Y1251117D01*
X322883Y1250908D01*
X322967Y1250658D01*
Y1250242D01*
X323092Y1249867D01*
X323342Y1249617D01*
X323633Y1249533D01*
X323925Y1249617D01*
X324133Y1249825D01*
X324258Y1250158D01*
X324300Y1250450D01*
G01X323925Y1252633D02*
X324133Y1252883D01*
X324258Y1253175D01*
X324300Y1253550D01*
X324217Y1253925D01*
X324050Y1254217D01*
X323758Y1254425D01*
X323425Y1254467D01*
X323092Y1254383D01*
X322883Y1254175D01*
X322717Y1253883D01*
X322675Y1253592D01*
X322717Y1253300D01*
X322883Y1252925D01*
X321800Y1253050D01*
Y1254175D01*
G01X324300Y1256650D02*
X321800D01*
X322300Y1256150D01*
G01X324300D02*
Y1257150D01*
G01X309097Y1231797D02*
X308972Y1231547D01*
X308889Y1231255D01*
Y1230922D01*
X309014Y1230547D01*
X309222Y1230255D01*
X309472Y1230047D01*
X309889Y1229880D01*
X310264Y1229838D01*
X310639Y1229922D01*
X310889Y1230047D01*
X311139Y1230297D01*
X311306Y1230588D01*
X311389Y1230880D01*
Y1231172D01*
X311306Y1231463D01*
X311181Y1231713D01*
X311014Y1231922D01*
G01X311389Y1233980D02*
X311347Y1234272D01*
X311222Y1234605D01*
X311014Y1234813D01*
X310722Y1234897D01*
X310431Y1234813D01*
X310181Y1234563D01*
X310056Y1234188D01*
Y1233772D01*
X309972Y1233522D01*
X309764Y1233313D01*
X309472Y1233230D01*
X309181Y1233355D01*
X308972Y1233647D01*
X308889Y1233980D01*
X308972Y1234313D01*
X309181Y1234605D01*
X309472Y1234730D01*
X309764Y1234647D01*
X309972Y1234438D01*
X310056Y1234188D01*
Y1233772D01*
X310181Y1233397D01*
X310431Y1233147D01*
X310722Y1233063D01*
X311014Y1233147D01*
X311222Y1233355D01*
X311347Y1233688D01*
X311389Y1233980D01*
G01X311097Y1236372D02*
X311306Y1236663D01*
X311389Y1236997D01*
X311306Y1237330D01*
X311056Y1237622D01*
X310681Y1237830D01*
X310306Y1237913D01*
X309847D01*
X309472Y1237830D01*
X309139Y1237622D01*
X308972Y1237372D01*
X308889Y1237080D01*
X308972Y1236747D01*
X309139Y1236497D01*
X309389Y1236330D01*
X309722Y1236247D01*
X310014Y1236330D01*
X310306Y1236538D01*
X310472Y1236788D01*
X310514Y1237080D01*
X310431Y1237413D01*
X310222Y1237663D01*
X309847Y1237913D01*
G01X308889Y1240180D02*
X308972Y1239847D01*
X309181Y1239597D01*
X309431Y1239430D01*
X309764Y1239305D01*
X310139Y1239263D01*
X310514Y1239305D01*
X310847Y1239430D01*
X311097Y1239597D01*
X311306Y1239847D01*
X311389Y1240180D01*
X311306Y1240513D01*
X311097Y1240763D01*
X310847Y1240930D01*
X310514Y1241055D01*
X310139Y1241097D01*
X309764Y1241055D01*
X309431Y1240930D01*
X309181Y1240763D01*
X308972Y1240513D01*
X308889Y1240180D01*
G01X311097Y1242572D02*
X311306Y1242863D01*
X311389Y1243197D01*
X311306Y1243530D01*
X311056Y1243822D01*
X310681Y1244030D01*
X310306Y1244113D01*
X309847D01*
X309472Y1244030D01*
X309139Y1243822D01*
X308972Y1243572D01*
X308889Y1243280D01*
X308972Y1242947D01*
X309139Y1242697D01*
X309389Y1242530D01*
X309722Y1242447D01*
X310014Y1242530D01*
X310306Y1242738D01*
X310472Y1242988D01*
X310514Y1243280D01*
X310431Y1243613D01*
X310222Y1243863D01*
X309847Y1244113D01*
G01X313527Y1231797D02*
X313402Y1231547D01*
X313319Y1231255D01*
Y1230922D01*
X313444Y1230547D01*
X313652Y1230255D01*
X313902Y1230047D01*
X314319Y1229880D01*
X314694Y1229838D01*
X315069Y1229922D01*
X315319Y1230047D01*
X315569Y1230297D01*
X315736Y1230588D01*
X315819Y1230880D01*
Y1231172D01*
X315736Y1231463D01*
X315611Y1231713D01*
X315444Y1231922D01*
G01X315819Y1233980D02*
X315777Y1234272D01*
X315652Y1234605D01*
X315444Y1234813D01*
X315152Y1234897D01*
X314861Y1234813D01*
X314611Y1234563D01*
X314486Y1234188D01*
Y1233772D01*
X314402Y1233522D01*
X314194Y1233313D01*
X313902Y1233230D01*
X313611Y1233355D01*
X313402Y1233647D01*
X313319Y1233980D01*
X313402Y1234313D01*
X313611Y1234605D01*
X313902Y1234730D01*
X314194Y1234647D01*
X314402Y1234438D01*
X314486Y1234188D01*
Y1233772D01*
X314611Y1233397D01*
X314861Y1233147D01*
X315152Y1233063D01*
X315444Y1233147D01*
X315652Y1233355D01*
X315777Y1233688D01*
X315819Y1233980D01*
G01X315527Y1236372D02*
X315736Y1236663D01*
X315819Y1236997D01*
X315736Y1237330D01*
X315486Y1237622D01*
X315111Y1237830D01*
X314736Y1237913D01*
X314277D01*
X313902Y1237830D01*
X313569Y1237622D01*
X313402Y1237372D01*
X313319Y1237080D01*
X313402Y1236747D01*
X313569Y1236497D01*
X313819Y1236330D01*
X314152Y1236247D01*
X314444Y1236330D01*
X314736Y1236538D01*
X314902Y1236788D01*
X314944Y1237080D01*
X314861Y1237413D01*
X314652Y1237663D01*
X314277Y1237913D01*
G01X315819Y1240180D02*
X313319D01*
X313819Y1239680D01*
G01X315819D02*
Y1240680D01*
G01X313319Y1243280D02*
X313402Y1242947D01*
X313611Y1242697D01*
X313861Y1242530D01*
X314194Y1242405D01*
X314569Y1242363D01*
X314944Y1242405D01*
X315277Y1242530D01*
X315527Y1242697D01*
X315736Y1242947D01*
X315819Y1243280D01*
X315736Y1243613D01*
X315527Y1243863D01*
X315277Y1244030D01*
X314944Y1244155D01*
X314569Y1244197D01*
X314194Y1244155D01*
X313861Y1244030D01*
X313611Y1243863D01*
X313402Y1243613D01*
X313319Y1243280D01*
G01X315167Y1272100D02*
Y1274600D01*
X316208D01*
X316542Y1274475D01*
X316750Y1274308D01*
X316833Y1273975D01*
X316750Y1273642D01*
X316500Y1273433D01*
X316208Y1273308D01*
X315167D01*
G01X316208D02*
X316833Y1272100D01*
G01X318392Y1272392D02*
X318683Y1272183D01*
X319017Y1272100D01*
X319350Y1272183D01*
X319642Y1272433D01*
X319850Y1272808D01*
X319933Y1273183D01*
Y1273642D01*
X319850Y1274017D01*
X319642Y1274350D01*
X319392Y1274517D01*
X319100Y1274600D01*
X318767Y1274517D01*
X318517Y1274350D01*
X318350Y1274100D01*
X318267Y1273767D01*
X318350Y1273475D01*
X318558Y1273183D01*
X318808Y1273017D01*
X319100Y1272975D01*
X319433Y1273058D01*
X319683Y1273267D01*
X319933Y1273642D01*
G01X322700Y1272100D02*
Y1274600D01*
X321158Y1272808D01*
X323242D01*
G01X324383Y1272600D02*
X324633Y1272308D01*
X324967Y1272142D01*
X325342Y1272100D01*
X325675Y1272142D01*
X326008Y1272350D01*
X326217Y1272600D01*
X326258Y1272850D01*
X326175Y1273142D01*
X325883Y1273350D01*
X325592Y1273433D01*
X325217D01*
G01X325592D02*
X325842Y1273558D01*
X326050Y1273767D01*
X326133Y1274017D01*
X326050Y1274267D01*
X325842Y1274475D01*
X325467Y1274600D01*
X325092Y1274558D01*
X324717Y1274392D01*
G01X328317Y1272100D02*
X328400Y1272642D01*
X328525Y1273100D01*
X328692Y1273517D01*
X328900Y1273975D01*
X329233Y1274600D01*
X327567D01*
G01X277167Y1216800D02*
Y1219300D01*
X278167D01*
X278500Y1219175D01*
X278750Y1218883D01*
X278833Y1218550D01*
X278750Y1218217D01*
X278542Y1217967D01*
X278167Y1217842D01*
X277167D01*
G01X280267Y1216800D02*
Y1219300D01*
X281308D01*
X281642Y1219175D01*
X281850Y1219008D01*
X281933Y1218675D01*
X281850Y1218342D01*
X281600Y1218133D01*
X281308Y1218008D01*
X280267D01*
G01X281308D02*
X281933Y1216800D01*
G01X283492Y1217092D02*
X283783Y1216883D01*
X284117Y1216800D01*
X284450Y1216883D01*
X284742Y1217133D01*
X284950Y1217508D01*
X285033Y1217883D01*
Y1218342D01*
X284950Y1218717D01*
X284742Y1219050D01*
X284492Y1219217D01*
X284200Y1219300D01*
X283867Y1219217D01*
X283617Y1219050D01*
X283450Y1218800D01*
X283367Y1218467D01*
X283450Y1218175D01*
X283658Y1217883D01*
X283908Y1217717D01*
X284200Y1217675D01*
X284533Y1217758D01*
X284783Y1217967D01*
X285033Y1218342D01*
G01X287300Y1219300D02*
X286967Y1219217D01*
X286717Y1219008D01*
X286550Y1218758D01*
X286425Y1218425D01*
X286383Y1218050D01*
X286425Y1217675D01*
X286550Y1217342D01*
X286717Y1217092D01*
X286967Y1216883D01*
X287300Y1216800D01*
X287633Y1216883D01*
X287883Y1217092D01*
X288050Y1217342D01*
X288175Y1217675D01*
X288217Y1218050D01*
X288175Y1218425D01*
X288050Y1218758D01*
X287883Y1219008D01*
X287633Y1219217D01*
X287300Y1219300D01*
G01X289608Y1217842D02*
X289900Y1218133D01*
X290150Y1218300D01*
X290483Y1218383D01*
X290775Y1218300D01*
X290983Y1218133D01*
X291150Y1217883D01*
X291192Y1217592D01*
X291150Y1217342D01*
X290983Y1217092D01*
X290733Y1216883D01*
X290442Y1216800D01*
X290108Y1216883D01*
X289817Y1217133D01*
X289650Y1217508D01*
X289608Y1217925D01*
X289692Y1218467D01*
X289817Y1218758D01*
X290025Y1219050D01*
X290317Y1219258D01*
X290608Y1219300D01*
X290900Y1219217D01*
X291108Y1219008D01*
G01X292708Y1218883D02*
X292958Y1219133D01*
X293250Y1219258D01*
X293583Y1219300D01*
X294000Y1219217D01*
X294292Y1219008D01*
X294375Y1218758D01*
X294333Y1218508D01*
X294167Y1218300D01*
X293333Y1217883D01*
X292958Y1217592D01*
X292708Y1217175D01*
X292625Y1216800D01*
X294375D01*
G01X330200Y1212500D02*
Y1216500D01*
X322800D01*
G01X311800Y1246917D02*
X309300D01*
Y1247958D01*
X309425Y1248292D01*
X309592Y1248500D01*
X309925Y1248583D01*
X310258Y1248500D01*
X310467Y1248250D01*
X310592Y1247958D01*
Y1246917D01*
G01Y1247958D02*
X311800Y1248583D01*
G01X311508Y1250142D02*
X311717Y1250433D01*
X311800Y1250767D01*
X311717Y1251100D01*
X311467Y1251392D01*
X311092Y1251600D01*
X310717Y1251683D01*
X310258D01*
X309883Y1251600D01*
X309550Y1251392D01*
X309383Y1251142D01*
X309300Y1250850D01*
X309383Y1250517D01*
X309550Y1250267D01*
X309800Y1250100D01*
X310133Y1250017D01*
X310425Y1250100D01*
X310717Y1250308D01*
X310883Y1250558D01*
X310925Y1250850D01*
X310842Y1251183D01*
X310633Y1251433D01*
X310258Y1251683D01*
G01X309300Y1253950D02*
X309383Y1253617D01*
X309592Y1253367D01*
X309842Y1253200D01*
X310175Y1253075D01*
X310550Y1253033D01*
X310925Y1253075D01*
X311258Y1253200D01*
X311508Y1253367D01*
X311717Y1253617D01*
X311800Y1253950D01*
X311717Y1254283D01*
X311508Y1254533D01*
X311258Y1254700D01*
X310925Y1254825D01*
X310550Y1254867D01*
X310175Y1254825D01*
X309842Y1254700D01*
X309592Y1254533D01*
X309383Y1254283D01*
X309300Y1253950D01*
G01X311800Y1256967D02*
X311258Y1257050D01*
X310800Y1257175D01*
X310383Y1257342D01*
X309925Y1257550D01*
X309300Y1257883D01*
Y1256217D01*
G01X311508Y1259442D02*
X311717Y1259733D01*
X311800Y1260067D01*
X311717Y1260400D01*
X311467Y1260692D01*
X311092Y1260900D01*
X310717Y1260983D01*
X310258D01*
X309883Y1260900D01*
X309550Y1260692D01*
X309383Y1260442D01*
X309300Y1260150D01*
X309383Y1259817D01*
X309550Y1259567D01*
X309800Y1259400D01*
X310133Y1259317D01*
X310425Y1259400D01*
X310717Y1259608D01*
X310883Y1259858D01*
X310925Y1260150D01*
X310842Y1260483D01*
X310633Y1260733D01*
X310258Y1260983D01*
G01X328800Y1244917D02*
X326300D01*
Y1245958D01*
X326425Y1246292D01*
X326592Y1246500D01*
X326925Y1246583D01*
X327258Y1246500D01*
X327467Y1246250D01*
X327592Y1245958D01*
Y1244917D01*
G01Y1245958D02*
X328800Y1246583D01*
G01X328508Y1248142D02*
X328717Y1248433D01*
X328800Y1248767D01*
X328717Y1249100D01*
X328467Y1249392D01*
X328092Y1249600D01*
X327717Y1249683D01*
X327258D01*
X326883Y1249600D01*
X326550Y1249392D01*
X326383Y1249142D01*
X326300Y1248850D01*
X326383Y1248517D01*
X326550Y1248267D01*
X326800Y1248100D01*
X327133Y1248017D01*
X327425Y1248100D01*
X327717Y1248308D01*
X327883Y1248558D01*
X327925Y1248850D01*
X327842Y1249183D01*
X327633Y1249433D01*
X327258Y1249683D01*
G01X326300Y1251950D02*
X326383Y1251617D01*
X326592Y1251367D01*
X326842Y1251200D01*
X327175Y1251075D01*
X327550Y1251033D01*
X327925Y1251075D01*
X328258Y1251200D01*
X328508Y1251367D01*
X328717Y1251617D01*
X328800Y1251950D01*
X328717Y1252283D01*
X328508Y1252533D01*
X328258Y1252700D01*
X327925Y1252825D01*
X327550Y1252867D01*
X327175Y1252825D01*
X326842Y1252700D01*
X326592Y1252533D01*
X326383Y1252283D01*
X326300Y1251950D01*
G01X328508Y1254342D02*
X328717Y1254633D01*
X328800Y1254967D01*
X328717Y1255300D01*
X328467Y1255592D01*
X328092Y1255800D01*
X327717Y1255883D01*
X327258D01*
X326883Y1255800D01*
X326550Y1255592D01*
X326383Y1255342D01*
X326300Y1255050D01*
X326383Y1254717D01*
X326550Y1254467D01*
X326800Y1254300D01*
X327133Y1254217D01*
X327425Y1254300D01*
X327717Y1254508D01*
X327883Y1254758D01*
X327925Y1255050D01*
X327842Y1255383D01*
X327633Y1255633D01*
X327258Y1255883D01*
G01X328508Y1257442D02*
X328717Y1257733D01*
X328800Y1258067D01*
X328717Y1258400D01*
X328467Y1258692D01*
X328092Y1258900D01*
X327717Y1258983D01*
X327258D01*
X326883Y1258900D01*
X326550Y1258692D01*
X326383Y1258442D01*
X326300Y1258150D01*
X326383Y1257817D01*
X326550Y1257567D01*
X326800Y1257400D01*
X327133Y1257317D01*
X327425Y1257400D01*
X327717Y1257608D01*
X327883Y1257858D01*
X327925Y1258150D01*
X327842Y1258483D01*
X327633Y1258733D01*
X327258Y1258983D01*
G01X307800Y1246917D02*
X305300D01*
Y1247958D01*
X305425Y1248292D01*
X305592Y1248500D01*
X305925Y1248583D01*
X306258Y1248500D01*
X306467Y1248250D01*
X306592Y1247958D01*
Y1246917D01*
G01Y1247958D02*
X307800Y1248583D01*
G01X307508Y1250142D02*
X307717Y1250433D01*
X307800Y1250767D01*
X307717Y1251100D01*
X307467Y1251392D01*
X307092Y1251600D01*
X306717Y1251683D01*
X306258D01*
X305883Y1251600D01*
X305550Y1251392D01*
X305383Y1251142D01*
X305300Y1250850D01*
X305383Y1250517D01*
X305550Y1250267D01*
X305800Y1250100D01*
X306133Y1250017D01*
X306425Y1250100D01*
X306717Y1250308D01*
X306883Y1250558D01*
X306925Y1250850D01*
X306842Y1251183D01*
X306633Y1251433D01*
X306258Y1251683D01*
G01X307800Y1253950D02*
X305300D01*
X305800Y1253450D01*
G01X307800D02*
Y1254450D01*
G01X305300Y1257050D02*
X305383Y1256717D01*
X305592Y1256467D01*
X305842Y1256300D01*
X306175Y1256175D01*
X306550Y1256133D01*
X306925Y1256175D01*
X307258Y1256300D01*
X307508Y1256467D01*
X307717Y1256717D01*
X307800Y1257050D01*
X307717Y1257383D01*
X307508Y1257633D01*
X307258Y1257800D01*
X306925Y1257925D01*
X306550Y1257967D01*
X306175Y1257925D01*
X305842Y1257800D01*
X305592Y1257633D01*
X305383Y1257383D01*
X305300Y1257050D01*
G01X305717Y1259358D02*
X305467Y1259608D01*
X305342Y1259900D01*
X305300Y1260233D01*
X305383Y1260650D01*
X305592Y1260942D01*
X305842Y1261025D01*
X306092Y1260983D01*
X306300Y1260817D01*
X306717Y1259983D01*
X307008Y1259608D01*
X307425Y1259358D01*
X307800Y1259275D01*
Y1261025D01*
G01X303800Y1246917D02*
X301300D01*
Y1247958D01*
X301425Y1248292D01*
X301592Y1248500D01*
X301925Y1248583D01*
X302258Y1248500D01*
X302467Y1248250D01*
X302592Y1247958D01*
Y1246917D01*
G01Y1247958D02*
X303800Y1248583D01*
G01X303508Y1250142D02*
X303717Y1250433D01*
X303800Y1250767D01*
X303717Y1251100D01*
X303467Y1251392D01*
X303092Y1251600D01*
X302717Y1251683D01*
X302258D01*
X301883Y1251600D01*
X301550Y1251392D01*
X301383Y1251142D01*
X301300Y1250850D01*
X301383Y1250517D01*
X301550Y1250267D01*
X301800Y1250100D01*
X302133Y1250017D01*
X302425Y1250100D01*
X302717Y1250308D01*
X302883Y1250558D01*
X302925Y1250850D01*
X302842Y1251183D01*
X302633Y1251433D01*
X302258Y1251683D01*
G01X303800Y1253950D02*
X301300D01*
X301800Y1253450D01*
G01X303800D02*
Y1254450D01*
G01X301300Y1257050D02*
X301383Y1256717D01*
X301592Y1256467D01*
X301842Y1256300D01*
X302175Y1256175D01*
X302550Y1256133D01*
X302925Y1256175D01*
X303258Y1256300D01*
X303508Y1256467D01*
X303717Y1256717D01*
X303800Y1257050D01*
X303717Y1257383D01*
X303508Y1257633D01*
X303258Y1257800D01*
X302925Y1257925D01*
X302550Y1257967D01*
X302175Y1257925D01*
X301842Y1257800D01*
X301592Y1257633D01*
X301383Y1257383D01*
X301300Y1257050D01*
G01X303300Y1259233D02*
X303592Y1259483D01*
X303758Y1259817D01*
X303800Y1260192D01*
X303758Y1260525D01*
X303550Y1260858D01*
X303300Y1261067D01*
X303050Y1261108D01*
X302758Y1261025D01*
X302550Y1260733D01*
X302467Y1260442D01*
Y1260067D01*
G01Y1260442D02*
X302342Y1260692D01*
X302133Y1260900D01*
X301883Y1260983D01*
X301633Y1260900D01*
X301425Y1260692D01*
X301300Y1260317D01*
X301342Y1259942D01*
X301508Y1259567D01*
G01X315800Y1246917D02*
X313300D01*
Y1247958D01*
X313425Y1248292D01*
X313592Y1248500D01*
X313925Y1248583D01*
X314258Y1248500D01*
X314467Y1248250D01*
X314592Y1247958D01*
Y1246917D01*
G01Y1247958D02*
X315800Y1248583D01*
G01X315508Y1250142D02*
X315717Y1250433D01*
X315800Y1250767D01*
X315717Y1251100D01*
X315467Y1251392D01*
X315092Y1251600D01*
X314717Y1251683D01*
X314258D01*
X313883Y1251600D01*
X313550Y1251392D01*
X313383Y1251142D01*
X313300Y1250850D01*
X313383Y1250517D01*
X313550Y1250267D01*
X313800Y1250100D01*
X314133Y1250017D01*
X314425Y1250100D01*
X314717Y1250308D01*
X314883Y1250558D01*
X314925Y1250850D01*
X314842Y1251183D01*
X314633Y1251433D01*
X314258Y1251683D01*
G01X315800Y1253950D02*
X313300D01*
X313800Y1253450D01*
G01X315800D02*
Y1254450D01*
G01X313300Y1257050D02*
X313383Y1256717D01*
X313592Y1256467D01*
X313842Y1256300D01*
X314175Y1256175D01*
X314550Y1256133D01*
X314925Y1256175D01*
X315258Y1256300D01*
X315508Y1256467D01*
X315717Y1256717D01*
X315800Y1257050D01*
X315717Y1257383D01*
X315508Y1257633D01*
X315258Y1257800D01*
X314925Y1257925D01*
X314550Y1257967D01*
X314175Y1257925D01*
X313842Y1257800D01*
X313592Y1257633D01*
X313383Y1257383D01*
X313300Y1257050D01*
G01X315800Y1260650D02*
X313300D01*
X315092Y1259108D01*
Y1261192D01*
G01X277125Y1225133D02*
X277458Y1224925D01*
X277833Y1224800D01*
X278167D01*
X278500Y1224925D01*
X278750Y1225133D01*
X278875Y1225425D01*
X278792Y1225717D01*
X278583Y1225967D01*
X278208Y1226133D01*
X277708Y1226217D01*
X277417Y1226383D01*
X277292Y1226675D01*
X277375Y1226967D01*
X277583Y1227175D01*
X277875Y1227300D01*
X278167D01*
X278458Y1227217D01*
X278708Y1227008D01*
G01X280267Y1224800D02*
Y1227300D01*
X281308D01*
X281642Y1227175D01*
X281850Y1227008D01*
X281933Y1226675D01*
X281850Y1226342D01*
X281600Y1226133D01*
X281308Y1226008D01*
X280267D01*
G01X281308D02*
X281933Y1224800D01*
G01X283492Y1225092D02*
X283783Y1224883D01*
X284117Y1224800D01*
X284450Y1224883D01*
X284742Y1225133D01*
X284950Y1225508D01*
X285033Y1225883D01*
Y1226342D01*
X284950Y1226717D01*
X284742Y1227050D01*
X284492Y1227217D01*
X284200Y1227300D01*
X283867Y1227217D01*
X283617Y1227050D01*
X283450Y1226800D01*
X283367Y1226467D01*
X283450Y1226175D01*
X283658Y1225883D01*
X283908Y1225717D01*
X284200Y1225675D01*
X284533Y1225758D01*
X284783Y1225967D01*
X285033Y1226342D01*
G01X287800Y1224800D02*
Y1227300D01*
X286258Y1225508D01*
X288342D01*
G01X290400Y1224800D02*
X290692Y1224842D01*
X291025Y1224967D01*
X291233Y1225175D01*
X291317Y1225467D01*
X291233Y1225758D01*
X290983Y1226008D01*
X290608Y1226133D01*
X290192D01*
X289942Y1226217D01*
X289733Y1226425D01*
X289650Y1226717D01*
X289775Y1227008D01*
X290067Y1227217D01*
X290400Y1227300D01*
X290733Y1227217D01*
X291025Y1227008D01*
X291150Y1226717D01*
X291067Y1226425D01*
X290858Y1226217D01*
X290608Y1226133D01*
X290192D01*
X289817Y1226008D01*
X289567Y1225758D01*
X289483Y1225467D01*
X289567Y1225175D01*
X289775Y1224967D01*
X290108Y1224842D01*
X290400Y1224800D01*
G01X322800Y1224500D02*
Y1220500D01*
X330200D01*
G01X277125Y1213133D02*
X277458Y1212925D01*
X277833Y1212800D01*
X278167D01*
X278500Y1212925D01*
X278750Y1213133D01*
X278875Y1213425D01*
X278792Y1213717D01*
X278583Y1213967D01*
X278208Y1214133D01*
X277708Y1214217D01*
X277417Y1214383D01*
X277292Y1214675D01*
X277375Y1214967D01*
X277583Y1215175D01*
X277875Y1215300D01*
X278167D01*
X278458Y1215217D01*
X278708Y1215008D01*
G01X280267Y1212800D02*
Y1215300D01*
X281308D01*
X281642Y1215175D01*
X281850Y1215008D01*
X281933Y1214675D01*
X281850Y1214342D01*
X281600Y1214133D01*
X281308Y1214008D01*
X280267D01*
G01X281308D02*
X281933Y1212800D01*
G01X283492Y1213092D02*
X283783Y1212883D01*
X284117Y1212800D01*
X284450Y1212883D01*
X284742Y1213133D01*
X284950Y1213508D01*
X285033Y1213883D01*
Y1214342D01*
X284950Y1214717D01*
X284742Y1215050D01*
X284492Y1215217D01*
X284200Y1215300D01*
X283867Y1215217D01*
X283617Y1215050D01*
X283450Y1214800D01*
X283367Y1214467D01*
X283450Y1214175D01*
X283658Y1213883D01*
X283908Y1213717D01*
X284200Y1213675D01*
X284533Y1213758D01*
X284783Y1213967D01*
X285033Y1214342D01*
G01X287800Y1212800D02*
Y1215300D01*
X286258Y1213508D01*
X288342D01*
G01X289692Y1213092D02*
X289983Y1212883D01*
X290317Y1212800D01*
X290650Y1212883D01*
X290942Y1213133D01*
X291150Y1213508D01*
X291233Y1213883D01*
Y1214342D01*
X291150Y1214717D01*
X290942Y1215050D01*
X290692Y1215217D01*
X290400Y1215300D01*
X290067Y1215217D01*
X289817Y1215050D01*
X289650Y1214800D01*
X289567Y1214467D01*
X289650Y1214175D01*
X289858Y1213883D01*
X290108Y1213717D01*
X290400Y1213675D01*
X290733Y1213758D01*
X290983Y1213967D01*
X291233Y1214342D01*
G01X277125Y1221133D02*
X277458Y1220925D01*
X277833Y1220800D01*
X278167D01*
X278500Y1220925D01*
X278750Y1221133D01*
X278875Y1221425D01*
X278792Y1221717D01*
X278583Y1221967D01*
X278208Y1222133D01*
X277708Y1222217D01*
X277417Y1222383D01*
X277292Y1222675D01*
X277375Y1222967D01*
X277583Y1223175D01*
X277875Y1223300D01*
X278167D01*
X278458Y1223217D01*
X278708Y1223008D01*
G01X280267Y1220800D02*
Y1223300D01*
X281308D01*
X281642Y1223175D01*
X281850Y1223008D01*
X281933Y1222675D01*
X281850Y1222342D01*
X281600Y1222133D01*
X281308Y1222008D01*
X280267D01*
G01X281308D02*
X281933Y1220800D01*
G01X283492Y1221092D02*
X283783Y1220883D01*
X284117Y1220800D01*
X284450Y1220883D01*
X284742Y1221133D01*
X284950Y1221508D01*
X285033Y1221883D01*
Y1222342D01*
X284950Y1222717D01*
X284742Y1223050D01*
X284492Y1223217D01*
X284200Y1223300D01*
X283867Y1223217D01*
X283617Y1223050D01*
X283450Y1222800D01*
X283367Y1222467D01*
X283450Y1222175D01*
X283658Y1221883D01*
X283908Y1221717D01*
X284200Y1221675D01*
X284533Y1221758D01*
X284783Y1221967D01*
X285033Y1222342D01*
G01X286383Y1221175D02*
X286633Y1220967D01*
X286925Y1220842D01*
X287300Y1220800D01*
X287675Y1220883D01*
X287967Y1221050D01*
X288175Y1221342D01*
X288217Y1221675D01*
X288133Y1222008D01*
X287925Y1222217D01*
X287633Y1222383D01*
X287342Y1222425D01*
X287050Y1222383D01*
X286675Y1222217D01*
X286800Y1223300D01*
X287925D01*
G01X290400D02*
X290067Y1223217D01*
X289817Y1223008D01*
X289650Y1222758D01*
X289525Y1222425D01*
X289483Y1222050D01*
X289525Y1221675D01*
X289650Y1221342D01*
X289817Y1221092D01*
X290067Y1220883D01*
X290400Y1220800D01*
X290733Y1220883D01*
X290983Y1221092D01*
X291150Y1221342D01*
X291275Y1221675D01*
X291317Y1222050D01*
X291275Y1222425D01*
X291150Y1222758D01*
X290983Y1223008D01*
X290733Y1223217D01*
X290400Y1223300D01*
G01X322800Y1220500D02*
Y1216500D01*
X330200D01*
G01X298967Y1272200D02*
Y1274700D01*
X300008D01*
X300342Y1274575D01*
X300550Y1274408D01*
X300633Y1274075D01*
X300550Y1273742D01*
X300300Y1273533D01*
X300008Y1273408D01*
X298967D01*
G01X300008D02*
X300633Y1272200D01*
G01X302192Y1272492D02*
X302483Y1272283D01*
X302817Y1272200D01*
X303150Y1272283D01*
X303442Y1272533D01*
X303650Y1272908D01*
X303733Y1273283D01*
Y1273742D01*
X303650Y1274117D01*
X303442Y1274450D01*
X303192Y1274617D01*
X302900Y1274700D01*
X302567Y1274617D01*
X302317Y1274450D01*
X302150Y1274200D01*
X302067Y1273867D01*
X302150Y1273575D01*
X302358Y1273283D01*
X302608Y1273117D01*
X302900Y1273075D01*
X303233Y1273158D01*
X303483Y1273367D01*
X303733Y1273742D01*
G01X305083Y1272575D02*
X305333Y1272367D01*
X305625Y1272242D01*
X306000Y1272200D01*
X306375Y1272283D01*
X306667Y1272450D01*
X306875Y1272742D01*
X306917Y1273075D01*
X306833Y1273408D01*
X306625Y1273617D01*
X306333Y1273783D01*
X306042Y1273825D01*
X305750Y1273783D01*
X305375Y1273617D01*
X305500Y1274700D01*
X306625D01*
G01X309100Y1272200D02*
Y1274700D01*
X308600Y1274200D01*
G01Y1272200D02*
X309600D01*
G01X311283Y1272575D02*
X311533Y1272367D01*
X311825Y1272242D01*
X312200Y1272200D01*
X312575Y1272283D01*
X312867Y1272450D01*
X313075Y1272742D01*
X313117Y1273075D01*
X313033Y1273408D01*
X312825Y1273617D01*
X312533Y1273783D01*
X312242Y1273825D01*
X311950Y1273783D01*
X311575Y1273617D01*
X311700Y1274700D01*
X312825D01*
G01X277167Y1228800D02*
Y1231300D01*
X278208D01*
X278542Y1231175D01*
X278750Y1231008D01*
X278833Y1230675D01*
X278750Y1230342D01*
X278500Y1230133D01*
X278208Y1230008D01*
X277167D01*
G01X278208D02*
X278833Y1228800D01*
G01X280392Y1229092D02*
X280683Y1228883D01*
X281017Y1228800D01*
X281350Y1228883D01*
X281642Y1229133D01*
X281850Y1229508D01*
X281933Y1229883D01*
Y1230342D01*
X281850Y1230717D01*
X281642Y1231050D01*
X281392Y1231217D01*
X281100Y1231300D01*
X280767Y1231217D01*
X280517Y1231050D01*
X280350Y1230800D01*
X280267Y1230467D01*
X280350Y1230175D01*
X280558Y1229883D01*
X280808Y1229717D01*
X281100Y1229675D01*
X281433Y1229758D01*
X281683Y1229967D01*
X281933Y1230342D01*
G01X283283Y1229300D02*
X283533Y1229008D01*
X283867Y1228842D01*
X284242Y1228800D01*
X284575Y1228842D01*
X284908Y1229050D01*
X285117Y1229300D01*
X285158Y1229550D01*
X285075Y1229842D01*
X284783Y1230050D01*
X284492Y1230133D01*
X284117D01*
G01X284492D02*
X284742Y1230258D01*
X284950Y1230467D01*
X285033Y1230717D01*
X284950Y1230967D01*
X284742Y1231175D01*
X284367Y1231300D01*
X283992Y1231258D01*
X283617Y1231092D01*
G01X286383Y1229175D02*
X286633Y1228967D01*
X286925Y1228842D01*
X287300Y1228800D01*
X287675Y1228883D01*
X287967Y1229050D01*
X288175Y1229342D01*
X288217Y1229675D01*
X288133Y1230008D01*
X287925Y1230217D01*
X287633Y1230383D01*
X287342Y1230425D01*
X287050Y1230383D01*
X286675Y1230217D01*
X286800Y1231300D01*
X287925D01*
G01X289608Y1230883D02*
X289858Y1231133D01*
X290150Y1231258D01*
X290483Y1231300D01*
X290900Y1231217D01*
X291192Y1231008D01*
X291275Y1230758D01*
X291233Y1230508D01*
X291067Y1230300D01*
X290233Y1229883D01*
X289858Y1229592D01*
X289608Y1229175D01*
X289525Y1228800D01*
X291275D01*
G01X322800Y1228500D02*
Y1224500D01*
X330200D01*
G01X298967Y1268167D02*
Y1270667D01*
X300008D01*
X300342Y1270542D01*
X300550Y1270375D01*
X300633Y1270042D01*
X300550Y1269709D01*
X300300Y1269500D01*
X300008Y1269375D01*
X298967D01*
G01X300008D02*
X300633Y1268167D01*
G01X302192Y1268459D02*
X302483Y1268250D01*
X302817Y1268167D01*
X303150Y1268250D01*
X303442Y1268500D01*
X303650Y1268875D01*
X303733Y1269250D01*
Y1269709D01*
X303650Y1270084D01*
X303442Y1270417D01*
X303192Y1270584D01*
X302900Y1270667D01*
X302567Y1270584D01*
X302317Y1270417D01*
X302150Y1270167D01*
X302067Y1269834D01*
X302150Y1269542D01*
X302358Y1269250D01*
X302608Y1269084D01*
X302900Y1269042D01*
X303233Y1269125D01*
X303483Y1269334D01*
X303733Y1269709D01*
G01X305208Y1269209D02*
X305500Y1269500D01*
X305750Y1269667D01*
X306083Y1269750D01*
X306375Y1269667D01*
X306583Y1269500D01*
X306750Y1269250D01*
X306792Y1268959D01*
X306750Y1268709D01*
X306583Y1268459D01*
X306333Y1268250D01*
X306042Y1268167D01*
X305708Y1268250D01*
X305417Y1268500D01*
X305250Y1268875D01*
X305208Y1269292D01*
X305292Y1269834D01*
X305417Y1270125D01*
X305625Y1270417D01*
X305917Y1270625D01*
X306208Y1270667D01*
X306500Y1270584D01*
X306708Y1270375D01*
G01X309100Y1268167D02*
Y1270667D01*
X308600Y1270167D01*
G01Y1268167D02*
X309600D01*
G01X312200D02*
Y1270667D01*
X311700Y1270167D01*
G01Y1268167D02*
X312700D01*
G01X315167Y1268100D02*
Y1270600D01*
X316208D01*
X316542Y1270475D01*
X316750Y1270308D01*
X316833Y1269975D01*
X316750Y1269642D01*
X316500Y1269433D01*
X316208Y1269308D01*
X315167D01*
G01X316208D02*
X316833Y1268100D01*
G01X318392Y1268392D02*
X318683Y1268183D01*
X319017Y1268100D01*
X319350Y1268183D01*
X319642Y1268433D01*
X319850Y1268808D01*
X319933Y1269183D01*
Y1269642D01*
X319850Y1270017D01*
X319642Y1270350D01*
X319392Y1270517D01*
X319100Y1270600D01*
X318767Y1270517D01*
X318517Y1270350D01*
X318350Y1270100D01*
X318267Y1269767D01*
X318350Y1269475D01*
X318558Y1269183D01*
X318808Y1269017D01*
X319100Y1268975D01*
X319433Y1269058D01*
X319683Y1269267D01*
X319933Y1269642D01*
G01X321408Y1269142D02*
X321700Y1269433D01*
X321950Y1269600D01*
X322283Y1269683D01*
X322575Y1269600D01*
X322783Y1269433D01*
X322950Y1269183D01*
X322992Y1268892D01*
X322950Y1268642D01*
X322783Y1268392D01*
X322533Y1268183D01*
X322242Y1268100D01*
X321908Y1268183D01*
X321617Y1268433D01*
X321450Y1268808D01*
X321408Y1269225D01*
X321492Y1269767D01*
X321617Y1270058D01*
X321825Y1270350D01*
X322117Y1270558D01*
X322408Y1270600D01*
X322700Y1270517D01*
X322908Y1270308D01*
G01X325300Y1268100D02*
Y1270600D01*
X324800Y1270100D01*
G01Y1268100D02*
X325800D01*
G01X328400Y1270600D02*
X328067Y1270517D01*
X327817Y1270308D01*
X327650Y1270058D01*
X327525Y1269725D01*
X327483Y1269350D01*
X327525Y1268975D01*
X327650Y1268642D01*
X327817Y1268392D01*
X328067Y1268183D01*
X328400Y1268100D01*
X328733Y1268183D01*
X328983Y1268392D01*
X329150Y1268642D01*
X329275Y1268975D01*
X329317Y1269350D01*
X329275Y1269725D01*
X329150Y1270058D01*
X328983Y1270308D01*
X328733Y1270517D01*
X328400Y1270600D01*
G01X261108Y1228800D02*
Y1231300D01*
X262692D01*
G01X262108Y1230092D02*
X261108D01*
G01X265333Y1230133D02*
X265500Y1230258D01*
X265625Y1230467D01*
X265708Y1230758D01*
X265625Y1231008D01*
X265458Y1231175D01*
X265167Y1231300D01*
X264042D01*
Y1228800D01*
X265417D01*
X265708Y1228967D01*
X265875Y1229217D01*
X265958Y1229508D01*
X265875Y1229800D01*
X265625Y1230050D01*
X265333Y1230133D01*
X264042D01*
G01X268017Y1228800D02*
X268100Y1229342D01*
X268225Y1229800D01*
X268392Y1230217D01*
X268600Y1230675D01*
X268933Y1231300D01*
X267267D01*
G01X304300Y1220500D02*
Y1227500D01*
X317700D01*
Y1220500D01*
X304300D01*
G01X262817Y1227092D02*
X262567Y1227217D01*
X262275Y1227300D01*
X261942D01*
X261567Y1227175D01*
X261275Y1226967D01*
X261067Y1226717D01*
X260900Y1226300D01*
X260858Y1225925D01*
X260942Y1225550D01*
X261067Y1225300D01*
X261317Y1225050D01*
X261608Y1224883D01*
X261900Y1224800D01*
X262192D01*
X262483Y1224883D01*
X262733Y1225008D01*
X262942Y1225175D01*
G01X265000Y1224800D02*
X265292Y1224842D01*
X265625Y1224967D01*
X265833Y1225175D01*
X265917Y1225467D01*
X265833Y1225758D01*
X265583Y1226008D01*
X265208Y1226133D01*
X264792D01*
X264542Y1226217D01*
X264333Y1226425D01*
X264250Y1226717D01*
X264375Y1227008D01*
X264667Y1227217D01*
X265000Y1227300D01*
X265333Y1227217D01*
X265625Y1227008D01*
X265750Y1226717D01*
X265667Y1226425D01*
X265458Y1226217D01*
X265208Y1226133D01*
X264792D01*
X264417Y1226008D01*
X264167Y1225758D01*
X264083Y1225467D01*
X264167Y1225175D01*
X264375Y1224967D01*
X264708Y1224842D01*
X265000Y1224800D01*
G01X267392Y1225092D02*
X267683Y1224883D01*
X268017Y1224800D01*
X268350Y1224883D01*
X268642Y1225133D01*
X268850Y1225508D01*
X268933Y1225883D01*
Y1226342D01*
X268850Y1226717D01*
X268642Y1227050D01*
X268392Y1227217D01*
X268100Y1227300D01*
X267767Y1227217D01*
X267517Y1227050D01*
X267350Y1226800D01*
X267267Y1226467D01*
X267350Y1226175D01*
X267558Y1225883D01*
X267808Y1225717D01*
X268100Y1225675D01*
X268433Y1225758D01*
X268683Y1225967D01*
X268933Y1226342D01*
G01X271200Y1224800D02*
Y1227300D01*
X270700Y1226800D01*
G01Y1224800D02*
X271700D01*
G01X274800D02*
Y1227300D01*
X273258Y1225508D01*
X275342D01*
G01X296708Y1378217D02*
X296583Y1377967D01*
X296500Y1377675D01*
Y1377342D01*
X296625Y1376967D01*
X296833Y1376675D01*
X297083Y1376467D01*
X297500Y1376300D01*
X297875Y1376258D01*
X298250Y1376342D01*
X298500Y1376467D01*
X298750Y1376717D01*
X298917Y1377008D01*
X299000Y1377300D01*
Y1377592D01*
X298917Y1377883D01*
X298792Y1378133D01*
X298625Y1378342D01*
G01X298708Y1379692D02*
X298917Y1379983D01*
X299000Y1380317D01*
X298917Y1380650D01*
X298667Y1380942D01*
X298292Y1381150D01*
X297917Y1381233D01*
X297458D01*
X297083Y1381150D01*
X296750Y1380942D01*
X296583Y1380692D01*
X296500Y1380400D01*
X296583Y1380067D01*
X296750Y1379817D01*
X297000Y1379650D01*
X297333Y1379567D01*
X297625Y1379650D01*
X297917Y1379858D01*
X298083Y1380108D01*
X298125Y1380400D01*
X298042Y1380733D01*
X297833Y1380983D01*
X297458Y1381233D01*
G01X298500Y1382583D02*
X298792Y1382833D01*
X298958Y1383167D01*
X299000Y1383542D01*
X298958Y1383875D01*
X298750Y1384208D01*
X298500Y1384417D01*
X298250Y1384458D01*
X297958Y1384375D01*
X297750Y1384083D01*
X297667Y1383792D01*
Y1383417D01*
G01Y1383792D02*
X297542Y1384042D01*
X297333Y1384250D01*
X297083Y1384333D01*
X296833Y1384250D01*
X296625Y1384042D01*
X296500Y1383667D01*
X296542Y1383292D01*
X296708Y1382917D01*
G01X296917Y1385808D02*
X296667Y1386058D01*
X296542Y1386350D01*
X296500Y1386683D01*
X296583Y1387100D01*
X296792Y1387392D01*
X297042Y1387475D01*
X297292Y1387433D01*
X297500Y1387267D01*
X297917Y1386433D01*
X298208Y1386058D01*
X298625Y1385808D01*
X299000Y1385725D01*
Y1387475D01*
G01Y1389700D02*
X296500D01*
X297000Y1389200D01*
G01X299000D02*
Y1390200D01*
G01X295500Y1370517D02*
X293000D01*
Y1371558D01*
X293125Y1371892D01*
X293292Y1372100D01*
X293625Y1372183D01*
X293958Y1372100D01*
X294167Y1371850D01*
X294292Y1371558D01*
Y1370517D01*
G01Y1371558D02*
X295500Y1372183D01*
G01X295000Y1373533D02*
X295292Y1373783D01*
X295458Y1374117D01*
X295500Y1374492D01*
X295458Y1374825D01*
X295250Y1375158D01*
X295000Y1375367D01*
X294750Y1375408D01*
X294458Y1375325D01*
X294250Y1375033D01*
X294167Y1374742D01*
Y1374367D01*
G01Y1374742D02*
X294042Y1374992D01*
X293833Y1375200D01*
X293583Y1375283D01*
X293333Y1375200D01*
X293125Y1374992D01*
X293000Y1374617D01*
X293042Y1374242D01*
X293208Y1373867D01*
G01X295500Y1377467D02*
X294958Y1377550D01*
X294500Y1377675D01*
X294083Y1377842D01*
X293625Y1378050D01*
X293000Y1378383D01*
Y1376717D01*
G01X295500Y1381150D02*
X293000D01*
X294792Y1379608D01*
Y1381692D01*
G01X291100Y1384800D02*
X295100D01*
Y1392200D01*
G01X285000Y1370517D02*
X282500D01*
Y1371558D01*
X282625Y1371892D01*
X282792Y1372100D01*
X283125Y1372183D01*
X283458Y1372100D01*
X283667Y1371850D01*
X283792Y1371558D01*
Y1370517D01*
G01Y1371558D02*
X285000Y1372183D01*
G01X284500Y1373533D02*
X284792Y1373783D01*
X284958Y1374117D01*
X285000Y1374492D01*
X284958Y1374825D01*
X284750Y1375158D01*
X284500Y1375367D01*
X284250Y1375408D01*
X283958Y1375325D01*
X283750Y1375033D01*
X283667Y1374742D01*
Y1374367D01*
G01Y1374742D02*
X283542Y1374992D01*
X283333Y1375200D01*
X283083Y1375283D01*
X282833Y1375200D01*
X282625Y1374992D01*
X282500Y1374617D01*
X282542Y1374242D01*
X282708Y1373867D01*
G01X285000Y1377467D02*
X284458Y1377550D01*
X284000Y1377675D01*
X283583Y1377842D01*
X283125Y1378050D01*
X282500Y1378383D01*
Y1376717D01*
G01X284625Y1379733D02*
X284833Y1379983D01*
X284958Y1380275D01*
X285000Y1380650D01*
X284917Y1381025D01*
X284750Y1381317D01*
X284458Y1381525D01*
X284125Y1381567D01*
X283792Y1381483D01*
X283583Y1381275D01*
X283417Y1380983D01*
X283375Y1380692D01*
X283417Y1380400D01*
X283583Y1380025D01*
X282500Y1380150D01*
Y1381275D01*
G01X282900Y1384800D02*
X286900D01*
Y1392200D01*
G01X321000Y1369917D02*
X318500D01*
Y1370917D01*
X318625Y1371250D01*
X318917Y1371500D01*
X319250Y1371583D01*
X319583Y1371500D01*
X319833Y1371292D01*
X319958Y1370917D01*
Y1369917D01*
G01X321000Y1373017D02*
X318500D01*
Y1374058D01*
X318625Y1374392D01*
X318792Y1374600D01*
X319125Y1374683D01*
X319458Y1374600D01*
X319667Y1374350D01*
X319792Y1374058D01*
Y1373017D01*
G01Y1374058D02*
X321000Y1374683D01*
G01X320708Y1376242D02*
X320917Y1376533D01*
X321000Y1376867D01*
X320917Y1377200D01*
X320667Y1377492D01*
X320292Y1377700D01*
X319917Y1377783D01*
X319458D01*
X319083Y1377700D01*
X318750Y1377492D01*
X318583Y1377242D01*
X318500Y1376950D01*
X318583Y1376617D01*
X318750Y1376367D01*
X319000Y1376200D01*
X319333Y1376117D01*
X319625Y1376200D01*
X319917Y1376408D01*
X320083Y1376658D01*
X320125Y1376950D01*
X320042Y1377283D01*
X319833Y1377533D01*
X319458Y1377783D01*
G01X318500Y1380050D02*
X318583Y1379717D01*
X318792Y1379467D01*
X319042Y1379300D01*
X319375Y1379175D01*
X319750Y1379133D01*
X320125Y1379175D01*
X320458Y1379300D01*
X320708Y1379467D01*
X320917Y1379717D01*
X321000Y1380050D01*
X320917Y1380383D01*
X320708Y1380633D01*
X320458Y1380800D01*
X320125Y1380925D01*
X319750Y1380967D01*
X319375Y1380925D01*
X319042Y1380800D01*
X318792Y1380633D01*
X318583Y1380383D01*
X318500Y1380050D01*
G01X321000Y1383650D02*
X318500D01*
X320292Y1382108D01*
Y1384192D01*
G01X321000Y1386167D02*
X320458Y1386250D01*
X320000Y1386375D01*
X319583Y1386542D01*
X319125Y1386750D01*
X318500Y1387083D01*
Y1385417D01*
G01X317500Y1390300D02*
X321500D01*
Y1397700D01*
G01X304667Y1369375D02*
X304875Y1369708D01*
X305000Y1370083D01*
Y1370417D01*
X304875Y1370750D01*
X304667Y1371000D01*
X304375Y1371125D01*
X304083Y1371042D01*
X303833Y1370833D01*
X303667Y1370458D01*
X303583Y1369958D01*
X303417Y1369667D01*
X303125Y1369542D01*
X302833Y1369625D01*
X302625Y1369833D01*
X302500Y1370125D01*
Y1370417D01*
X302583Y1370708D01*
X302792Y1370958D01*
G01X305000Y1372517D02*
X302500D01*
Y1373558D01*
X302625Y1373892D01*
X302792Y1374100D01*
X303125Y1374183D01*
X303458Y1374100D01*
X303667Y1373850D01*
X303792Y1373558D01*
Y1372517D01*
G01Y1373558D02*
X305000Y1374183D01*
G01Y1376450D02*
X302500D01*
X303000Y1375950D01*
G01X305000D02*
Y1376950D01*
G01X302500Y1379550D02*
X302583Y1379217D01*
X302792Y1378967D01*
X303042Y1378800D01*
X303375Y1378675D01*
X303750Y1378633D01*
X304125Y1378675D01*
X304458Y1378800D01*
X304708Y1378967D01*
X304917Y1379217D01*
X305000Y1379550D01*
X304917Y1379883D01*
X304708Y1380133D01*
X304458Y1380300D01*
X304125Y1380425D01*
X303750Y1380467D01*
X303375Y1380425D01*
X303042Y1380300D01*
X302792Y1380133D01*
X302583Y1379883D01*
X302500Y1379550D01*
G01X304625Y1381733D02*
X304833Y1381983D01*
X304958Y1382275D01*
X305000Y1382650D01*
X304917Y1383025D01*
X304750Y1383317D01*
X304458Y1383525D01*
X304125Y1383567D01*
X303792Y1383483D01*
X303583Y1383275D01*
X303417Y1382983D01*
X303375Y1382692D01*
X303417Y1382400D01*
X303583Y1382025D01*
X302500Y1382150D01*
Y1383275D01*
G01Y1385750D02*
X302583Y1385417D01*
X302792Y1385167D01*
X303042Y1385000D01*
X303375Y1384875D01*
X303750Y1384833D01*
X304125Y1384875D01*
X304458Y1385000D01*
X304708Y1385167D01*
X304917Y1385417D01*
X305000Y1385750D01*
X304917Y1386083D01*
X304708Y1386333D01*
X304458Y1386500D01*
X304125Y1386625D01*
X303750Y1386667D01*
X303375Y1386625D01*
X303042Y1386500D01*
X302792Y1386333D01*
X302583Y1386083D01*
X302500Y1385750D01*
G01X305500Y1397700D02*
X301500D01*
Y1390300D01*
G01X282200Y1405500D02*
Y1409500D01*
X274800D01*
G01X316667Y1369375D02*
X316875Y1369708D01*
X317000Y1370083D01*
Y1370417D01*
X316875Y1370750D01*
X316667Y1371000D01*
X316375Y1371125D01*
X316083Y1371042D01*
X315833Y1370833D01*
X315667Y1370458D01*
X315583Y1369958D01*
X315417Y1369667D01*
X315125Y1369542D01*
X314833Y1369625D01*
X314625Y1369833D01*
X314500Y1370125D01*
Y1370417D01*
X314583Y1370708D01*
X314792Y1370958D01*
G01X317000Y1372517D02*
X314500D01*
Y1373558D01*
X314625Y1373892D01*
X314792Y1374100D01*
X315125Y1374183D01*
X315458Y1374100D01*
X315667Y1373850D01*
X315792Y1373558D01*
Y1372517D01*
G01Y1373558D02*
X317000Y1374183D01*
G01Y1376450D02*
X314500D01*
X315000Y1375950D01*
G01X317000D02*
Y1376950D01*
G01X314500Y1379550D02*
X314583Y1379217D01*
X314792Y1378967D01*
X315042Y1378800D01*
X315375Y1378675D01*
X315750Y1378633D01*
X316125Y1378675D01*
X316458Y1378800D01*
X316708Y1378967D01*
X316917Y1379217D01*
X317000Y1379550D01*
X316917Y1379883D01*
X316708Y1380133D01*
X316458Y1380300D01*
X316125Y1380425D01*
X315750Y1380467D01*
X315375Y1380425D01*
X315042Y1380300D01*
X314792Y1380133D01*
X314583Y1379883D01*
X314500Y1379550D01*
G01X316625Y1381733D02*
X316833Y1381983D01*
X316958Y1382275D01*
X317000Y1382650D01*
X316917Y1383025D01*
X316750Y1383317D01*
X316458Y1383525D01*
X316125Y1383567D01*
X315792Y1383483D01*
X315583Y1383275D01*
X315417Y1382983D01*
X315375Y1382692D01*
X315417Y1382400D01*
X315583Y1382025D01*
X314500Y1382150D01*
Y1383275D01*
G01X314917Y1384958D02*
X314667Y1385208D01*
X314542Y1385500D01*
X314500Y1385833D01*
X314583Y1386250D01*
X314792Y1386542D01*
X315042Y1386625D01*
X315292Y1386583D01*
X315500Y1386417D01*
X315917Y1385583D01*
X316208Y1385208D01*
X316625Y1384958D01*
X317000Y1384875D01*
Y1386625D01*
G01X313500Y1390300D02*
X317500D01*
Y1397700D01*
G01X274800Y1421500D02*
Y1417500D01*
X282200D01*
G01X274800Y1433500D02*
Y1429500D01*
X282200D01*
G01X274800Y1413500D02*
Y1409500D01*
X282200D01*
G01X274800Y1425500D02*
Y1421500D01*
X282200D01*
G01X325200Y1427700D02*
Y1431700D01*
X317800D01*
G01X325200Y1415500D02*
Y1419500D01*
X317800D01*
G01X325200Y1423700D02*
Y1427700D01*
X317800D01*
G01X325200Y1403400D02*
Y1407400D01*
X317800D01*
G01X325200Y1411500D02*
Y1415500D01*
X317800D01*
G01X278300Y1389117D02*
X275800D01*
Y1390158D01*
X275925Y1390492D01*
X276092Y1390700D01*
X276425Y1390783D01*
X276758Y1390700D01*
X276967Y1390450D01*
X277092Y1390158D01*
Y1389117D01*
G01Y1390158D02*
X278300Y1390783D01*
G01Y1393550D02*
X275800D01*
X277592Y1392008D01*
Y1394092D01*
G01X276217Y1395358D02*
X275967Y1395608D01*
X275842Y1395900D01*
X275800Y1396233D01*
X275883Y1396650D01*
X276092Y1396942D01*
X276342Y1397025D01*
X276592Y1396983D01*
X276800Y1396817D01*
X277217Y1395983D01*
X277508Y1395608D01*
X277925Y1395358D01*
X278300Y1395275D01*
Y1397025D01*
G01X278008Y1398542D02*
X278217Y1398833D01*
X278300Y1399167D01*
X278217Y1399500D01*
X277967Y1399792D01*
X277592Y1400000D01*
X277217Y1400083D01*
X276758D01*
X276383Y1400000D01*
X276050Y1399792D01*
X275883Y1399542D01*
X275800Y1399250D01*
X275883Y1398917D01*
X276050Y1398667D01*
X276300Y1398500D01*
X276633Y1398417D01*
X276925Y1398500D01*
X277217Y1398708D01*
X277383Y1398958D01*
X277425Y1399250D01*
X277342Y1399583D01*
X277133Y1399833D01*
X276758Y1400083D01*
G01X285000Y1393800D02*
X289000D01*
Y1401200D01*
G01X282300Y1389117D02*
X279800D01*
Y1390158D01*
X279925Y1390492D01*
X280092Y1390700D01*
X280425Y1390783D01*
X280758Y1390700D01*
X280967Y1390450D01*
X281092Y1390158D01*
Y1389117D01*
G01Y1390158D02*
X282300Y1390783D01*
G01Y1393550D02*
X279800D01*
X281592Y1392008D01*
Y1394092D01*
G01X281800Y1395233D02*
X282092Y1395483D01*
X282258Y1395817D01*
X282300Y1396192D01*
X282258Y1396525D01*
X282050Y1396858D01*
X281800Y1397067D01*
X281550Y1397108D01*
X281258Y1397025D01*
X281050Y1396733D01*
X280967Y1396442D01*
Y1396067D01*
G01Y1396442D02*
X280842Y1396692D01*
X280633Y1396900D01*
X280383Y1396983D01*
X280133Y1396900D01*
X279925Y1396692D01*
X279800Y1396317D01*
X279842Y1395942D01*
X280008Y1395567D01*
G01X279800Y1399250D02*
X279883Y1398917D01*
X280092Y1398667D01*
X280342Y1398500D01*
X280675Y1398375D01*
X281050Y1398333D01*
X281425Y1398375D01*
X281758Y1398500D01*
X282008Y1398667D01*
X282217Y1398917D01*
X282300Y1399250D01*
X282217Y1399583D01*
X282008Y1399833D01*
X281758Y1400000D01*
X281425Y1400125D01*
X281050Y1400167D01*
X280675Y1400125D01*
X280342Y1400000D01*
X280092Y1399833D01*
X279883Y1399583D01*
X279800Y1399250D01*
G01X289000Y1393800D02*
X293000D01*
Y1401200D01*
G01X312667Y1369375D02*
X312875Y1369708D01*
X313000Y1370083D01*
Y1370417D01*
X312875Y1370750D01*
X312667Y1371000D01*
X312375Y1371125D01*
X312083Y1371042D01*
X311833Y1370833D01*
X311667Y1370458D01*
X311583Y1369958D01*
X311417Y1369667D01*
X311125Y1369542D01*
X310833Y1369625D01*
X310625Y1369833D01*
X310500Y1370125D01*
Y1370417D01*
X310583Y1370708D01*
X310792Y1370958D01*
G01X313000Y1372517D02*
X310500D01*
Y1373558D01*
X310625Y1373892D01*
X310792Y1374100D01*
X311125Y1374183D01*
X311458Y1374100D01*
X311667Y1373850D01*
X311792Y1373558D01*
Y1372517D01*
G01Y1373558D02*
X313000Y1374183D01*
G01Y1376450D02*
X310500D01*
X311000Y1375950D01*
G01X313000D02*
Y1376950D01*
G01Y1379550D02*
X310500D01*
X311000Y1379050D01*
G01X313000D02*
Y1380050D01*
G01X312625Y1381733D02*
X312833Y1381983D01*
X312958Y1382275D01*
X313000Y1382650D01*
X312917Y1383025D01*
X312750Y1383317D01*
X312458Y1383525D01*
X312125Y1383567D01*
X311792Y1383483D01*
X311583Y1383275D01*
X311417Y1382983D01*
X311375Y1382692D01*
X311417Y1382400D01*
X311583Y1382025D01*
X310500Y1382150D01*
Y1383275D01*
G01X311958Y1384958D02*
X311667Y1385250D01*
X311500Y1385500D01*
X311417Y1385833D01*
X311500Y1386125D01*
X311667Y1386333D01*
X311917Y1386500D01*
X312208Y1386542D01*
X312458Y1386500D01*
X312708Y1386333D01*
X312917Y1386083D01*
X313000Y1385792D01*
X312917Y1385458D01*
X312667Y1385167D01*
X312292Y1385000D01*
X311875Y1384958D01*
X311333Y1385042D01*
X311042Y1385167D01*
X310750Y1385375D01*
X310542Y1385667D01*
X310500Y1385958D01*
X310583Y1386250D01*
X310792Y1386458D01*
G01X313500Y1397700D02*
X309500D01*
Y1390300D01*
G01X274800Y1405500D02*
Y1401500D01*
X282200D01*
G01X308667Y1369375D02*
X308875Y1369708D01*
X309000Y1370083D01*
Y1370417D01*
X308875Y1370750D01*
X308667Y1371000D01*
X308375Y1371125D01*
X308083Y1371042D01*
X307833Y1370833D01*
X307667Y1370458D01*
X307583Y1369958D01*
X307417Y1369667D01*
X307125Y1369542D01*
X306833Y1369625D01*
X306625Y1369833D01*
X306500Y1370125D01*
Y1370417D01*
X306583Y1370708D01*
X306792Y1370958D01*
G01X309000Y1372517D02*
X306500D01*
Y1373558D01*
X306625Y1373892D01*
X306792Y1374100D01*
X307125Y1374183D01*
X307458Y1374100D01*
X307667Y1373850D01*
X307792Y1373558D01*
Y1372517D01*
G01Y1373558D02*
X309000Y1374183D01*
G01Y1376450D02*
X306500D01*
X307000Y1375950D01*
G01X309000D02*
Y1376950D01*
G01Y1379550D02*
X306500D01*
X307000Y1379050D01*
G01X309000D02*
Y1380050D01*
G01X308625Y1381733D02*
X308833Y1381983D01*
X308958Y1382275D01*
X309000Y1382650D01*
X308917Y1383025D01*
X308750Y1383317D01*
X308458Y1383525D01*
X308125Y1383567D01*
X307792Y1383483D01*
X307583Y1383275D01*
X307417Y1382983D01*
X307375Y1382692D01*
X307417Y1382400D01*
X307583Y1382025D01*
X306500Y1382150D01*
Y1383275D01*
G01X309000Y1386250D02*
X306500D01*
X308292Y1384708D01*
Y1386792D01*
G01X305500Y1390300D02*
X309500D01*
Y1397700D01*
G01X312653Y1400290D02*
X310987D01*
Y1402790D01*
X312653D01*
G01X311987Y1401582D02*
X310987D01*
G01X314003Y1402790D02*
Y1400998D01*
X314170Y1400623D01*
X314503Y1400373D01*
X314920Y1400290D01*
X315337Y1400373D01*
X315670Y1400623D01*
X315837Y1400998D01*
Y1402790D01*
G01X318020Y1400290D02*
Y1402790D01*
X317520Y1402290D01*
G01Y1400290D02*
X318520D01*
G01X321037D02*
X321120Y1400832D01*
X321245Y1401290D01*
X321412Y1401707D01*
X321620Y1402165D01*
X321953Y1402790D01*
X320287D01*
G01X297000Y1410400D02*
Y1407400D01*
G01X287000Y1422500D02*
X289000D01*
G01X311000Y1424400D02*
X313000D01*
G01X288100Y1414600D02*
Y1409600D01*
X293100D01*
G01Y1433400D02*
X288100D01*
Y1428400D01*
G01X306900Y1433400D02*
X311900D01*
Y1428400D01*
G01X261925Y1435833D02*
X262258Y1435625D01*
X262633Y1435500D01*
X262967D01*
X263300Y1435625D01*
X263550Y1435833D01*
X263675Y1436125D01*
X263592Y1436417D01*
X263383Y1436667D01*
X263008Y1436833D01*
X262508Y1436917D01*
X262217Y1437083D01*
X262092Y1437375D01*
X262175Y1437667D01*
X262383Y1437875D01*
X262675Y1438000D01*
X262967D01*
X263258Y1437917D01*
X263508Y1437708D01*
G01X265067Y1435500D02*
Y1438000D01*
X266108D01*
X266442Y1437875D01*
X266650Y1437708D01*
X266733Y1437375D01*
X266650Y1437042D01*
X266400Y1436833D01*
X266108Y1436708D01*
X265067D01*
G01X266108D02*
X266733Y1435500D01*
G01X268292Y1435792D02*
X268583Y1435583D01*
X268917Y1435500D01*
X269250Y1435583D01*
X269542Y1435833D01*
X269750Y1436208D01*
X269833Y1436583D01*
Y1437042D01*
X269750Y1437417D01*
X269542Y1437750D01*
X269292Y1437917D01*
X269000Y1438000D01*
X268667Y1437917D01*
X268417Y1437750D01*
X268250Y1437500D01*
X268167Y1437167D01*
X268250Y1436875D01*
X268458Y1436583D01*
X268708Y1436417D01*
X269000Y1436375D01*
X269333Y1436458D01*
X269583Y1436667D01*
X269833Y1437042D01*
G01X272017Y1435500D02*
X272100Y1436042D01*
X272225Y1436500D01*
X272392Y1436917D01*
X272600Y1437375D01*
X272933Y1438000D01*
X271267D01*
G01X274492Y1435792D02*
X274783Y1435583D01*
X275117Y1435500D01*
X275450Y1435583D01*
X275742Y1435833D01*
X275950Y1436208D01*
X276033Y1436583D01*
Y1437042D01*
X275950Y1437417D01*
X275742Y1437750D01*
X275492Y1437917D01*
X275200Y1438000D01*
X274867Y1437917D01*
X274617Y1437750D01*
X274450Y1437500D01*
X274367Y1437167D01*
X274450Y1436875D01*
X274658Y1436583D01*
X274908Y1436417D01*
X275200Y1436375D01*
X275533Y1436458D01*
X275783Y1436667D01*
X276033Y1437042D01*
G01X288716Y1453385D02*
X288924Y1453718D01*
X289049Y1454093D01*
Y1454427D01*
X288924Y1454760D01*
X288716Y1455010D01*
X288424Y1455135D01*
X288132Y1455052D01*
X287882Y1454843D01*
X287716Y1454468D01*
X287632Y1453968D01*
X287466Y1453677D01*
X287174Y1453552D01*
X286882Y1453635D01*
X286674Y1453843D01*
X286549Y1454135D01*
Y1454427D01*
X286632Y1454718D01*
X286841Y1454968D01*
G01X289049Y1456527D02*
X286549D01*
Y1457568D01*
X286674Y1457902D01*
X286841Y1458110D01*
X287174Y1458193D01*
X287507Y1458110D01*
X287716Y1457860D01*
X287841Y1457568D01*
Y1456527D01*
G01Y1457568D02*
X289049Y1458193D01*
G01X288757Y1459752D02*
X288966Y1460043D01*
X289049Y1460377D01*
X288966Y1460710D01*
X288716Y1461002D01*
X288341Y1461210D01*
X287966Y1461293D01*
X287507D01*
X287132Y1461210D01*
X286799Y1461002D01*
X286632Y1460752D01*
X286549Y1460460D01*
X286632Y1460127D01*
X286799Y1459877D01*
X287049Y1459710D01*
X287382Y1459627D01*
X287674Y1459710D01*
X287966Y1459918D01*
X288132Y1460168D01*
X288174Y1460460D01*
X288091Y1460793D01*
X287882Y1461043D01*
X287507Y1461293D01*
G01X289049Y1463560D02*
X289007Y1463852D01*
X288882Y1464185D01*
X288674Y1464393D01*
X288382Y1464477D01*
X288091Y1464393D01*
X287841Y1464143D01*
X287716Y1463768D01*
Y1463352D01*
X287632Y1463102D01*
X287424Y1462893D01*
X287132Y1462810D01*
X286841Y1462935D01*
X286632Y1463227D01*
X286549Y1463560D01*
X286632Y1463893D01*
X286841Y1464185D01*
X287132Y1464310D01*
X287424Y1464227D01*
X287632Y1464018D01*
X287716Y1463768D01*
Y1463352D01*
X287841Y1462977D01*
X288091Y1462727D01*
X288382Y1462643D01*
X288674Y1462727D01*
X288882Y1462935D01*
X289007Y1463268D01*
X289049Y1463560D01*
G01X286966Y1465868D02*
X286716Y1466118D01*
X286591Y1466410D01*
X286549Y1466743D01*
X286632Y1467160D01*
X286841Y1467452D01*
X287091Y1467535D01*
X287341Y1467493D01*
X287549Y1467327D01*
X287966Y1466493D01*
X288257Y1466118D01*
X288674Y1465868D01*
X289049Y1465785D01*
Y1467535D01*
G01X289600Y1446700D02*
X285600D01*
Y1439300D01*
G01X275667Y1440925D02*
X275875Y1441258D01*
X276000Y1441633D01*
Y1441967D01*
X275875Y1442300D01*
X275667Y1442550D01*
X275375Y1442675D01*
X275083Y1442592D01*
X274833Y1442383D01*
X274667Y1442008D01*
X274583Y1441508D01*
X274417Y1441217D01*
X274125Y1441092D01*
X273833Y1441175D01*
X273625Y1441383D01*
X273500Y1441675D01*
Y1441967D01*
X273583Y1442258D01*
X273792Y1442508D01*
G01X276000Y1444067D02*
X273500D01*
Y1445108D01*
X273625Y1445442D01*
X273792Y1445650D01*
X274125Y1445733D01*
X274458Y1445650D01*
X274667Y1445400D01*
X274792Y1445108D01*
Y1444067D01*
G01Y1445108D02*
X276000Y1445733D01*
G01X275708Y1447292D02*
X275917Y1447583D01*
X276000Y1447917D01*
X275917Y1448250D01*
X275667Y1448542D01*
X275292Y1448750D01*
X274917Y1448833D01*
X274458D01*
X274083Y1448750D01*
X273750Y1448542D01*
X273583Y1448292D01*
X273500Y1448000D01*
X273583Y1447667D01*
X273750Y1447417D01*
X274000Y1447250D01*
X274333Y1447167D01*
X274625Y1447250D01*
X274917Y1447458D01*
X275083Y1447708D01*
X275125Y1448000D01*
X275042Y1448333D01*
X274833Y1448583D01*
X274458Y1448833D01*
G01X276000Y1451100D02*
X275958Y1451392D01*
X275833Y1451725D01*
X275625Y1451933D01*
X275333Y1452017D01*
X275042Y1451933D01*
X274792Y1451683D01*
X274667Y1451308D01*
Y1450892D01*
X274583Y1450642D01*
X274375Y1450433D01*
X274083Y1450350D01*
X273792Y1450475D01*
X273583Y1450767D01*
X273500Y1451100D01*
X273583Y1451433D01*
X273792Y1451725D01*
X274083Y1451850D01*
X274375Y1451767D01*
X274583Y1451558D01*
X274667Y1451308D01*
Y1450892D01*
X274792Y1450517D01*
X275042Y1450267D01*
X275333Y1450183D01*
X275625Y1450267D01*
X275833Y1450475D01*
X275958Y1450808D01*
X276000Y1451100D01*
G01X275500Y1453283D02*
X275792Y1453533D01*
X275958Y1453867D01*
X276000Y1454242D01*
X275958Y1454575D01*
X275750Y1454908D01*
X275500Y1455117D01*
X275250Y1455158D01*
X274958Y1455075D01*
X274750Y1454783D01*
X274667Y1454492D01*
Y1454117D01*
G01Y1454492D02*
X274542Y1454742D01*
X274333Y1454950D01*
X274083Y1455033D01*
X273833Y1454950D01*
X273625Y1454742D01*
X273500Y1454367D01*
X273542Y1453992D01*
X273708Y1453617D01*
G01X281650Y1446700D02*
X277650D01*
Y1439300D01*
G01X300716Y1452885D02*
X300924Y1453218D01*
X301049Y1453593D01*
Y1453927D01*
X300924Y1454260D01*
X300716Y1454510D01*
X300424Y1454635D01*
X300132Y1454552D01*
X299882Y1454343D01*
X299716Y1453968D01*
X299632Y1453468D01*
X299466Y1453177D01*
X299174Y1453052D01*
X298882Y1453135D01*
X298674Y1453343D01*
X298549Y1453635D01*
Y1453927D01*
X298632Y1454218D01*
X298841Y1454468D01*
G01X301049Y1456027D02*
X298549D01*
Y1457068D01*
X298674Y1457402D01*
X298841Y1457610D01*
X299174Y1457693D01*
X299507Y1457610D01*
X299716Y1457360D01*
X299841Y1457068D01*
Y1456027D01*
G01Y1457068D02*
X301049Y1457693D01*
G01X300757Y1459252D02*
X300966Y1459543D01*
X301049Y1459877D01*
X300966Y1460210D01*
X300716Y1460502D01*
X300341Y1460710D01*
X299966Y1460793D01*
X299507D01*
X299132Y1460710D01*
X298799Y1460502D01*
X298632Y1460252D01*
X298549Y1459960D01*
X298632Y1459627D01*
X298799Y1459377D01*
X299049Y1459210D01*
X299382Y1459127D01*
X299674Y1459210D01*
X299966Y1459418D01*
X300132Y1459668D01*
X300174Y1459960D01*
X300091Y1460293D01*
X299882Y1460543D01*
X299507Y1460793D01*
G01X301049Y1463060D02*
X301007Y1463352D01*
X300882Y1463685D01*
X300674Y1463893D01*
X300382Y1463977D01*
X300091Y1463893D01*
X299841Y1463643D01*
X299716Y1463268D01*
Y1462852D01*
X299632Y1462602D01*
X299424Y1462393D01*
X299132Y1462310D01*
X298841Y1462435D01*
X298632Y1462727D01*
X298549Y1463060D01*
X298632Y1463393D01*
X298841Y1463685D01*
X299132Y1463810D01*
X299424Y1463727D01*
X299632Y1463518D01*
X299716Y1463268D01*
Y1462852D01*
X299841Y1462477D01*
X300091Y1462227D01*
X300382Y1462143D01*
X300674Y1462227D01*
X300882Y1462435D01*
X301007Y1462768D01*
X301049Y1463060D01*
G01Y1466660D02*
X298549D01*
X300341Y1465118D01*
Y1467202D01*
G01X301600Y1446700D02*
X297600D01*
Y1439300D01*
G01X292716Y1453385D02*
X292924Y1453718D01*
X293049Y1454093D01*
Y1454427D01*
X292924Y1454760D01*
X292716Y1455010D01*
X292424Y1455135D01*
X292132Y1455052D01*
X291882Y1454843D01*
X291716Y1454468D01*
X291632Y1453968D01*
X291466Y1453677D01*
X291174Y1453552D01*
X290882Y1453635D01*
X290674Y1453843D01*
X290549Y1454135D01*
Y1454427D01*
X290632Y1454718D01*
X290841Y1454968D01*
G01X293049Y1456527D02*
X290549D01*
Y1457568D01*
X290674Y1457902D01*
X290841Y1458110D01*
X291174Y1458193D01*
X291507Y1458110D01*
X291716Y1457860D01*
X291841Y1457568D01*
Y1456527D01*
G01Y1457568D02*
X293049Y1458193D01*
G01X292757Y1459752D02*
X292966Y1460043D01*
X293049Y1460377D01*
X292966Y1460710D01*
X292716Y1461002D01*
X292341Y1461210D01*
X291966Y1461293D01*
X291507D01*
X291132Y1461210D01*
X290799Y1461002D01*
X290632Y1460752D01*
X290549Y1460460D01*
X290632Y1460127D01*
X290799Y1459877D01*
X291049Y1459710D01*
X291382Y1459627D01*
X291674Y1459710D01*
X291966Y1459918D01*
X292132Y1460168D01*
X292174Y1460460D01*
X292091Y1460793D01*
X291882Y1461043D01*
X291507Y1461293D01*
G01X293049Y1463560D02*
X293007Y1463852D01*
X292882Y1464185D01*
X292674Y1464393D01*
X292382Y1464477D01*
X292091Y1464393D01*
X291841Y1464143D01*
X291716Y1463768D01*
Y1463352D01*
X291632Y1463102D01*
X291424Y1462893D01*
X291132Y1462810D01*
X290841Y1462935D01*
X290632Y1463227D01*
X290549Y1463560D01*
X290632Y1463893D01*
X290841Y1464185D01*
X291132Y1464310D01*
X291424Y1464227D01*
X291632Y1464018D01*
X291716Y1463768D01*
Y1463352D01*
X291841Y1462977D01*
X292091Y1462727D01*
X292382Y1462643D01*
X292674Y1462727D01*
X292882Y1462935D01*
X293007Y1463268D01*
X293049Y1463560D01*
G01X292674Y1465743D02*
X292882Y1465993D01*
X293007Y1466285D01*
X293049Y1466660D01*
X292966Y1467035D01*
X292799Y1467327D01*
X292507Y1467535D01*
X292174Y1467577D01*
X291841Y1467493D01*
X291632Y1467285D01*
X291466Y1466993D01*
X291424Y1466702D01*
X291466Y1466410D01*
X291632Y1466035D01*
X290549Y1466160D01*
Y1467285D01*
G01X293600Y1446700D02*
X289600D01*
Y1439300D01*
G01X317667Y1441925D02*
X317875Y1442258D01*
X318000Y1442633D01*
Y1442967D01*
X317875Y1443300D01*
X317667Y1443550D01*
X317375Y1443675D01*
X317083Y1443592D01*
X316833Y1443383D01*
X316667Y1443008D01*
X316583Y1442508D01*
X316417Y1442217D01*
X316125Y1442092D01*
X315833Y1442175D01*
X315625Y1442383D01*
X315500Y1442675D01*
Y1442967D01*
X315583Y1443258D01*
X315792Y1443508D01*
G01X318000Y1445067D02*
X315500D01*
Y1446108D01*
X315625Y1446442D01*
X315792Y1446650D01*
X316125Y1446733D01*
X316458Y1446650D01*
X316667Y1446400D01*
X316792Y1446108D01*
Y1445067D01*
G01Y1446108D02*
X318000Y1446733D01*
G01X317708Y1448292D02*
X317917Y1448583D01*
X318000Y1448917D01*
X317917Y1449250D01*
X317667Y1449542D01*
X317292Y1449750D01*
X316917Y1449833D01*
X316458D01*
X316083Y1449750D01*
X315750Y1449542D01*
X315583Y1449292D01*
X315500Y1449000D01*
X315583Y1448667D01*
X315750Y1448417D01*
X316000Y1448250D01*
X316333Y1448167D01*
X316625Y1448250D01*
X316917Y1448458D01*
X317083Y1448708D01*
X317125Y1449000D01*
X317042Y1449333D01*
X316833Y1449583D01*
X316458Y1449833D01*
G01X318000Y1452100D02*
X317958Y1452392D01*
X317833Y1452725D01*
X317625Y1452933D01*
X317333Y1453017D01*
X317042Y1452933D01*
X316792Y1452683D01*
X316667Y1452308D01*
Y1451892D01*
X316583Y1451642D01*
X316375Y1451433D01*
X316083Y1451350D01*
X315792Y1451475D01*
X315583Y1451767D01*
X315500Y1452100D01*
X315583Y1452433D01*
X315792Y1452725D01*
X316083Y1452850D01*
X316375Y1452767D01*
X316583Y1452558D01*
X316667Y1452308D01*
Y1451892D01*
X316792Y1451517D01*
X317042Y1451267D01*
X317333Y1451183D01*
X317625Y1451267D01*
X317833Y1451475D01*
X317958Y1451808D01*
X318000Y1452100D01*
G01X316958Y1454408D02*
X316667Y1454700D01*
X316500Y1454950D01*
X316417Y1455283D01*
X316500Y1455575D01*
X316667Y1455783D01*
X316917Y1455950D01*
X317208Y1455992D01*
X317458Y1455950D01*
X317708Y1455783D01*
X317917Y1455533D01*
X318000Y1455242D01*
X317917Y1454908D01*
X317667Y1454617D01*
X317292Y1454450D01*
X316875Y1454408D01*
X316333Y1454492D01*
X316042Y1454617D01*
X315750Y1454825D01*
X315542Y1455117D01*
X315500Y1455408D01*
X315583Y1455700D01*
X315792Y1455908D01*
G01X313600Y1446700D02*
X309600D01*
Y1439300D01*
G01X304716Y1452885D02*
X304924Y1453218D01*
X305049Y1453593D01*
Y1453927D01*
X304924Y1454260D01*
X304716Y1454510D01*
X304424Y1454635D01*
X304132Y1454552D01*
X303882Y1454343D01*
X303716Y1453968D01*
X303632Y1453468D01*
X303466Y1453177D01*
X303174Y1453052D01*
X302882Y1453135D01*
X302674Y1453343D01*
X302549Y1453635D01*
Y1453927D01*
X302632Y1454218D01*
X302841Y1454468D01*
G01X305049Y1456027D02*
X302549D01*
Y1457068D01*
X302674Y1457402D01*
X302841Y1457610D01*
X303174Y1457693D01*
X303507Y1457610D01*
X303716Y1457360D01*
X303841Y1457068D01*
Y1456027D01*
G01Y1457068D02*
X305049Y1457693D01*
G01X304757Y1459252D02*
X304966Y1459543D01*
X305049Y1459877D01*
X304966Y1460210D01*
X304716Y1460502D01*
X304341Y1460710D01*
X303966Y1460793D01*
X303507D01*
X303132Y1460710D01*
X302799Y1460502D01*
X302632Y1460252D01*
X302549Y1459960D01*
X302632Y1459627D01*
X302799Y1459377D01*
X303049Y1459210D01*
X303382Y1459127D01*
X303674Y1459210D01*
X303966Y1459418D01*
X304132Y1459668D01*
X304174Y1459960D01*
X304091Y1460293D01*
X303882Y1460543D01*
X303507Y1460793D01*
G01X305049Y1463060D02*
X305007Y1463352D01*
X304882Y1463685D01*
X304674Y1463893D01*
X304382Y1463977D01*
X304091Y1463893D01*
X303841Y1463643D01*
X303716Y1463268D01*
Y1462852D01*
X303632Y1462602D01*
X303424Y1462393D01*
X303132Y1462310D01*
X302841Y1462435D01*
X302632Y1462727D01*
X302549Y1463060D01*
X302632Y1463393D01*
X302841Y1463685D01*
X303132Y1463810D01*
X303424Y1463727D01*
X303632Y1463518D01*
X303716Y1463268D01*
Y1462852D01*
X303841Y1462477D01*
X304091Y1462227D01*
X304382Y1462143D01*
X304674Y1462227D01*
X304882Y1462435D01*
X305007Y1462768D01*
X305049Y1463060D01*
G01Y1466160D02*
X305007Y1466452D01*
X304882Y1466785D01*
X304674Y1466993D01*
X304382Y1467077D01*
X304091Y1466993D01*
X303841Y1466743D01*
X303716Y1466368D01*
Y1465952D01*
X303632Y1465702D01*
X303424Y1465493D01*
X303132Y1465410D01*
X302841Y1465535D01*
X302632Y1465827D01*
X302549Y1466160D01*
X302632Y1466493D01*
X302841Y1466785D01*
X303132Y1466910D01*
X303424Y1466827D01*
X303632Y1466618D01*
X303716Y1466368D01*
Y1465952D01*
X303841Y1465577D01*
X304091Y1465327D01*
X304382Y1465243D01*
X304674Y1465327D01*
X304882Y1465535D01*
X305007Y1465868D01*
X305049Y1466160D01*
G01X305600Y1446700D02*
X301600D01*
Y1439300D01*
G01X325200Y1435700D02*
Y1439700D01*
X317800D01*
G01X299000Y1435400D02*
Y1432400D01*
G01X267000Y1511065D02*
Y1513565D01*
G01X268750D02*
Y1511065D01*
G01Y1512315D02*
X267000D01*
G01X270058Y1511565D02*
X270308Y1511273D01*
X270642Y1511107D01*
X271017Y1511065D01*
X271350Y1511107D01*
X271683Y1511315D01*
X271892Y1511565D01*
X271933Y1511815D01*
X271850Y1512107D01*
X271558Y1512315D01*
X271267Y1512398D01*
X270892D01*
G01X271267D02*
X271517Y1512523D01*
X271725Y1512732D01*
X271808Y1512982D01*
X271725Y1513232D01*
X271517Y1513440D01*
X271142Y1513565D01*
X270767Y1513523D01*
X270392Y1513357D01*
G01X315948Y1646434D02*
X313448D01*
Y1647475D01*
X313573Y1647809D01*
X313740Y1648017D01*
X314073Y1648100D01*
X314406Y1648017D01*
X314615Y1647767D01*
X314740Y1647475D01*
Y1646434D01*
G01Y1647475D02*
X315948Y1648100D01*
G01X315656Y1649659D02*
X315865Y1649950D01*
X315948Y1650284D01*
X315865Y1650617D01*
X315615Y1650909D01*
X315240Y1651117D01*
X314865Y1651200D01*
X314406D01*
X314031Y1651117D01*
X313698Y1650909D01*
X313531Y1650659D01*
X313448Y1650367D01*
X313531Y1650034D01*
X313698Y1649784D01*
X313948Y1649617D01*
X314281Y1649534D01*
X314573Y1649617D01*
X314865Y1649825D01*
X315031Y1650075D01*
X315073Y1650367D01*
X314990Y1650700D01*
X314781Y1650950D01*
X314406Y1651200D01*
G01X313448Y1653467D02*
X313531Y1653134D01*
X313740Y1652884D01*
X313990Y1652717D01*
X314323Y1652592D01*
X314698Y1652550D01*
X315073Y1652592D01*
X315406Y1652717D01*
X315656Y1652884D01*
X315865Y1653134D01*
X315948Y1653467D01*
X315865Y1653800D01*
X315656Y1654050D01*
X315406Y1654217D01*
X315073Y1654342D01*
X314698Y1654384D01*
X314323Y1654342D01*
X313990Y1654217D01*
X313740Y1654050D01*
X313531Y1653800D01*
X313448Y1653467D01*
G01X314906Y1655775D02*
X314615Y1656067D01*
X314448Y1656317D01*
X314365Y1656650D01*
X314448Y1656942D01*
X314615Y1657150D01*
X314865Y1657317D01*
X315156Y1657359D01*
X315406Y1657317D01*
X315656Y1657150D01*
X315865Y1656900D01*
X315948Y1656609D01*
X315865Y1656275D01*
X315615Y1655984D01*
X315240Y1655817D01*
X314823Y1655775D01*
X314281Y1655859D01*
X313990Y1655984D01*
X313698Y1656192D01*
X313490Y1656484D01*
X313448Y1656775D01*
X313531Y1657067D01*
X313740Y1657275D01*
G01X315656Y1658959D02*
X315865Y1659250D01*
X315948Y1659584D01*
X315865Y1659917D01*
X315615Y1660209D01*
X315240Y1660417D01*
X314865Y1660500D01*
X314406D01*
X314031Y1660417D01*
X313698Y1660209D01*
X313531Y1659959D01*
X313448Y1659667D01*
X313531Y1659334D01*
X313698Y1659084D01*
X313948Y1658917D01*
X314281Y1658834D01*
X314573Y1658917D01*
X314865Y1659125D01*
X315031Y1659375D01*
X315073Y1659667D01*
X314990Y1660000D01*
X314781Y1660250D01*
X314406Y1660500D01*
G01X319948Y1646434D02*
X317448D01*
Y1647475D01*
X317573Y1647809D01*
X317740Y1648017D01*
X318073Y1648100D01*
X318406Y1648017D01*
X318615Y1647767D01*
X318740Y1647475D01*
Y1646434D01*
G01Y1647475D02*
X319948Y1648100D01*
G01X319656Y1649659D02*
X319865Y1649950D01*
X319948Y1650284D01*
X319865Y1650617D01*
X319615Y1650909D01*
X319240Y1651117D01*
X318865Y1651200D01*
X318406D01*
X318031Y1651117D01*
X317698Y1650909D01*
X317531Y1650659D01*
X317448Y1650367D01*
X317531Y1650034D01*
X317698Y1649784D01*
X317948Y1649617D01*
X318281Y1649534D01*
X318573Y1649617D01*
X318865Y1649825D01*
X319031Y1650075D01*
X319073Y1650367D01*
X318990Y1650700D01*
X318781Y1650950D01*
X318406Y1651200D01*
G01X317448Y1653467D02*
X317531Y1653134D01*
X317740Y1652884D01*
X317990Y1652717D01*
X318323Y1652592D01*
X318698Y1652550D01*
X319073Y1652592D01*
X319406Y1652717D01*
X319656Y1652884D01*
X319865Y1653134D01*
X319948Y1653467D01*
X319865Y1653800D01*
X319656Y1654050D01*
X319406Y1654217D01*
X319073Y1654342D01*
X318698Y1654384D01*
X318323Y1654342D01*
X317990Y1654217D01*
X317740Y1654050D01*
X317531Y1653800D01*
X317448Y1653467D01*
G01X319948Y1656484D02*
X319406Y1656567D01*
X318948Y1656692D01*
X318531Y1656859D01*
X318073Y1657067D01*
X317448Y1657400D01*
Y1655734D01*
G01X317865Y1658875D02*
X317615Y1659125D01*
X317490Y1659417D01*
X317448Y1659750D01*
X317531Y1660167D01*
X317740Y1660459D01*
X317990Y1660542D01*
X318240Y1660500D01*
X318448Y1660334D01*
X318865Y1659500D01*
X319156Y1659125D01*
X319573Y1658875D01*
X319948Y1658792D01*
Y1660542D01*
G01X297534Y1702656D02*
X297409Y1702406D01*
X297326Y1702114D01*
Y1701781D01*
X297451Y1701406D01*
X297659Y1701114D01*
X297909Y1700906D01*
X298326Y1700739D01*
X298701Y1700697D01*
X299076Y1700781D01*
X299326Y1700906D01*
X299576Y1701156D01*
X299743Y1701447D01*
X299826Y1701739D01*
Y1702031D01*
X299743Y1702322D01*
X299618Y1702572D01*
X299451Y1702781D01*
G01X299826Y1704839D02*
X299784Y1705131D01*
X299659Y1705464D01*
X299451Y1705672D01*
X299159Y1705756D01*
X298868Y1705672D01*
X298618Y1705422D01*
X298493Y1705047D01*
Y1704631D01*
X298409Y1704381D01*
X298201Y1704172D01*
X297909Y1704089D01*
X297618Y1704214D01*
X297409Y1704506D01*
X297326Y1704839D01*
X297409Y1705172D01*
X297618Y1705464D01*
X297909Y1705589D01*
X298201Y1705506D01*
X298409Y1705297D01*
X298493Y1705047D01*
Y1704631D01*
X298618Y1704256D01*
X298868Y1704006D01*
X299159Y1703922D01*
X299451Y1704006D01*
X299659Y1704214D01*
X299784Y1704547D01*
X299826Y1704839D01*
G01Y1707939D02*
X299784Y1708231D01*
X299659Y1708564D01*
X299451Y1708772D01*
X299159Y1708856D01*
X298868Y1708772D01*
X298618Y1708522D01*
X298493Y1708147D01*
Y1707731D01*
X298409Y1707481D01*
X298201Y1707272D01*
X297909Y1707189D01*
X297618Y1707314D01*
X297409Y1707606D01*
X297326Y1707939D01*
X297409Y1708272D01*
X297618Y1708564D01*
X297909Y1708689D01*
X298201Y1708606D01*
X298409Y1708397D01*
X298493Y1708147D01*
Y1707731D01*
X298618Y1707356D01*
X298868Y1707106D01*
X299159Y1707022D01*
X299451Y1707106D01*
X299659Y1707314D01*
X299784Y1707647D01*
X299826Y1707939D01*
G01X299534Y1710331D02*
X299743Y1710622D01*
X299826Y1710956D01*
X299743Y1711289D01*
X299493Y1711581D01*
X299118Y1711789D01*
X298743Y1711872D01*
X298284D01*
X297909Y1711789D01*
X297576Y1711581D01*
X297409Y1711331D01*
X297326Y1711039D01*
X297409Y1710706D01*
X297576Y1710456D01*
X297826Y1710289D01*
X298159Y1710206D01*
X298451Y1710289D01*
X298743Y1710497D01*
X298909Y1710747D01*
X298951Y1711039D01*
X298868Y1711372D01*
X298659Y1711622D01*
X298284Y1711872D01*
G01X299451Y1713222D02*
X299659Y1713472D01*
X299784Y1713764D01*
X299826Y1714139D01*
X299743Y1714514D01*
X299576Y1714806D01*
X299284Y1715014D01*
X298951Y1715056D01*
X298618Y1714972D01*
X298409Y1714764D01*
X298243Y1714472D01*
X298201Y1714181D01*
X298243Y1713889D01*
X298409Y1713514D01*
X297326Y1713639D01*
Y1714764D01*
G01X301534Y1702656D02*
X301409Y1702406D01*
X301326Y1702114D01*
Y1701781D01*
X301451Y1701406D01*
X301659Y1701114D01*
X301909Y1700906D01*
X302326Y1700739D01*
X302701Y1700697D01*
X303076Y1700781D01*
X303326Y1700906D01*
X303576Y1701156D01*
X303743Y1701447D01*
X303826Y1701739D01*
Y1702031D01*
X303743Y1702322D01*
X303618Y1702572D01*
X303451Y1702781D01*
G01X303826Y1704839D02*
X303784Y1705131D01*
X303659Y1705464D01*
X303451Y1705672D01*
X303159Y1705756D01*
X302868Y1705672D01*
X302618Y1705422D01*
X302493Y1705047D01*
Y1704631D01*
X302409Y1704381D01*
X302201Y1704172D01*
X301909Y1704089D01*
X301618Y1704214D01*
X301409Y1704506D01*
X301326Y1704839D01*
X301409Y1705172D01*
X301618Y1705464D01*
X301909Y1705589D01*
X302201Y1705506D01*
X302409Y1705297D01*
X302493Y1705047D01*
Y1704631D01*
X302618Y1704256D01*
X302868Y1704006D01*
X303159Y1703922D01*
X303451Y1704006D01*
X303659Y1704214D01*
X303784Y1704547D01*
X303826Y1704839D01*
G01Y1707939D02*
X303784Y1708231D01*
X303659Y1708564D01*
X303451Y1708772D01*
X303159Y1708856D01*
X302868Y1708772D01*
X302618Y1708522D01*
X302493Y1708147D01*
Y1707731D01*
X302409Y1707481D01*
X302201Y1707272D01*
X301909Y1707189D01*
X301618Y1707314D01*
X301409Y1707606D01*
X301326Y1707939D01*
X301409Y1708272D01*
X301618Y1708564D01*
X301909Y1708689D01*
X302201Y1708606D01*
X302409Y1708397D01*
X302493Y1708147D01*
Y1707731D01*
X302618Y1707356D01*
X302868Y1707106D01*
X303159Y1707022D01*
X303451Y1707106D01*
X303659Y1707314D01*
X303784Y1707647D01*
X303826Y1707939D01*
G01X303534Y1710331D02*
X303743Y1710622D01*
X303826Y1710956D01*
X303743Y1711289D01*
X303493Y1711581D01*
X303118Y1711789D01*
X302743Y1711872D01*
X302284D01*
X301909Y1711789D01*
X301576Y1711581D01*
X301409Y1711331D01*
X301326Y1711039D01*
X301409Y1710706D01*
X301576Y1710456D01*
X301826Y1710289D01*
X302159Y1710206D01*
X302451Y1710289D01*
X302743Y1710497D01*
X302909Y1710747D01*
X302951Y1711039D01*
X302868Y1711372D01*
X302659Y1711622D01*
X302284Y1711872D01*
G01X302784Y1713347D02*
X302493Y1713639D01*
X302326Y1713889D01*
X302243Y1714222D01*
X302326Y1714514D01*
X302493Y1714722D01*
X302743Y1714889D01*
X303034Y1714931D01*
X303284Y1714889D01*
X303534Y1714722D01*
X303743Y1714472D01*
X303826Y1714181D01*
X303743Y1713847D01*
X303493Y1713556D01*
X303118Y1713389D01*
X302701Y1713347D01*
X302159Y1713431D01*
X301868Y1713556D01*
X301576Y1713764D01*
X301368Y1714056D01*
X301326Y1714347D01*
X301409Y1714639D01*
X301618Y1714847D01*
G01X266448Y1701155D02*
X263948D01*
Y1702155D01*
X264073Y1702488D01*
X264365Y1702738D01*
X264698Y1702821D01*
X265031Y1702738D01*
X265281Y1702530D01*
X265406Y1702155D01*
Y1701155D01*
G01X266448Y1704255D02*
X263948D01*
Y1705296D01*
X264073Y1705630D01*
X264240Y1705838D01*
X264573Y1705921D01*
X264906Y1705838D01*
X265115Y1705588D01*
X265240Y1705296D01*
Y1704255D01*
G01Y1705296D02*
X266448Y1705921D01*
G01X266156Y1707480D02*
X266365Y1707771D01*
X266448Y1708105D01*
X266365Y1708438D01*
X266115Y1708730D01*
X265740Y1708938D01*
X265365Y1709021D01*
X264906D01*
X264531Y1708938D01*
X264198Y1708730D01*
X264031Y1708480D01*
X263948Y1708188D01*
X264031Y1707855D01*
X264198Y1707605D01*
X264448Y1707438D01*
X264781Y1707355D01*
X265073Y1707438D01*
X265365Y1707646D01*
X265531Y1707896D01*
X265573Y1708188D01*
X265490Y1708521D01*
X265281Y1708771D01*
X264906Y1709021D01*
G01X263948Y1711288D02*
X264031Y1710955D01*
X264240Y1710705D01*
X264490Y1710538D01*
X264823Y1710413D01*
X265198Y1710371D01*
X265573Y1710413D01*
X265906Y1710538D01*
X266156Y1710705D01*
X266365Y1710955D01*
X266448Y1711288D01*
X266365Y1711621D01*
X266156Y1711871D01*
X265906Y1712038D01*
X265573Y1712163D01*
X265198Y1712205D01*
X264823Y1712163D01*
X264490Y1712038D01*
X264240Y1711871D01*
X264031Y1711621D01*
X263948Y1711288D01*
G01X266073Y1713471D02*
X266281Y1713721D01*
X266406Y1714013D01*
X266448Y1714388D01*
X266365Y1714763D01*
X266198Y1715055D01*
X265906Y1715263D01*
X265573Y1715305D01*
X265240Y1715221D01*
X265031Y1715013D01*
X264865Y1714721D01*
X264823Y1714430D01*
X264865Y1714138D01*
X265031Y1713763D01*
X263948Y1713888D01*
Y1715013D01*
G01X266448Y1717405D02*
X265906Y1717488D01*
X265448Y1717613D01*
X265031Y1717780D01*
X264573Y1717988D01*
X263948Y1718321D01*
Y1716655D01*
G01X274500Y1712300D02*
X278500D01*
Y1719700D01*
G01X262448Y1701155D02*
X259948D01*
Y1702155D01*
X260073Y1702488D01*
X260365Y1702738D01*
X260698Y1702821D01*
X261031Y1702738D01*
X261281Y1702530D01*
X261406Y1702155D01*
Y1701155D01*
G01X262448Y1704255D02*
X259948D01*
Y1705296D01*
X260073Y1705630D01*
X260240Y1705838D01*
X260573Y1705921D01*
X260906Y1705838D01*
X261115Y1705588D01*
X261240Y1705296D01*
Y1704255D01*
G01Y1705296D02*
X262448Y1705921D01*
G01X262156Y1707480D02*
X262365Y1707771D01*
X262448Y1708105D01*
X262365Y1708438D01*
X262115Y1708730D01*
X261740Y1708938D01*
X261365Y1709021D01*
X260906D01*
X260531Y1708938D01*
X260198Y1708730D01*
X260031Y1708480D01*
X259948Y1708188D01*
X260031Y1707855D01*
X260198Y1707605D01*
X260448Y1707438D01*
X260781Y1707355D01*
X261073Y1707438D01*
X261365Y1707646D01*
X261531Y1707896D01*
X261573Y1708188D01*
X261490Y1708521D01*
X261281Y1708771D01*
X260906Y1709021D01*
G01X259948Y1711288D02*
X260031Y1710955D01*
X260240Y1710705D01*
X260490Y1710538D01*
X260823Y1710413D01*
X261198Y1710371D01*
X261573Y1710413D01*
X261906Y1710538D01*
X262156Y1710705D01*
X262365Y1710955D01*
X262448Y1711288D01*
X262365Y1711621D01*
X262156Y1711871D01*
X261906Y1712038D01*
X261573Y1712163D01*
X261198Y1712205D01*
X260823Y1712163D01*
X260490Y1712038D01*
X260240Y1711871D01*
X260031Y1711621D01*
X259948Y1711288D01*
G01X262073Y1713471D02*
X262281Y1713721D01*
X262406Y1714013D01*
X262448Y1714388D01*
X262365Y1714763D01*
X262198Y1715055D01*
X261906Y1715263D01*
X261573Y1715305D01*
X261240Y1715221D01*
X261031Y1715013D01*
X260865Y1714721D01*
X260823Y1714430D01*
X260865Y1714138D01*
X261031Y1713763D01*
X259948Y1713888D01*
Y1715013D01*
G01X262448Y1717488D02*
X262406Y1717780D01*
X262281Y1718113D01*
X262073Y1718321D01*
X261781Y1718405D01*
X261490Y1718321D01*
X261240Y1718071D01*
X261115Y1717696D01*
Y1717280D01*
X261031Y1717030D01*
X260823Y1716821D01*
X260531Y1716738D01*
X260240Y1716863D01*
X260031Y1717155D01*
X259948Y1717488D01*
X260031Y1717821D01*
X260240Y1718113D01*
X260531Y1718238D01*
X260823Y1718155D01*
X261031Y1717946D01*
X261115Y1717696D01*
Y1717280D01*
X261240Y1716905D01*
X261490Y1716655D01*
X261781Y1716571D01*
X262073Y1716655D01*
X262281Y1716863D01*
X262406Y1717196D01*
X262448Y1717488D01*
G01X270500Y1712300D02*
X274500D01*
Y1719700D01*
G01X282200Y1720000D02*
Y1724000D01*
X274800D01*
G01X266800D02*
Y1720000D01*
X274200D01*
G01X299175Y1665420D02*
Y1667920D01*
X300175D01*
X300508Y1667795D01*
X300758Y1667503D01*
X300841Y1667170D01*
X300758Y1666837D01*
X300550Y1666587D01*
X300175Y1666462D01*
X299175D01*
G01X302275Y1665420D02*
Y1667920D01*
X303316D01*
X303650Y1667795D01*
X303858Y1667628D01*
X303941Y1667295D01*
X303858Y1666962D01*
X303608Y1666753D01*
X303316Y1666628D01*
X302275D01*
G01X303316D02*
X303941Y1665420D01*
G01X305500Y1665712D02*
X305791Y1665503D01*
X306125Y1665420D01*
X306458Y1665503D01*
X306750Y1665753D01*
X306958Y1666128D01*
X307041Y1666503D01*
Y1666962D01*
X306958Y1667337D01*
X306750Y1667670D01*
X306500Y1667837D01*
X306208Y1667920D01*
X305875Y1667837D01*
X305625Y1667670D01*
X305458Y1667420D01*
X305375Y1667087D01*
X305458Y1666795D01*
X305666Y1666503D01*
X305916Y1666337D01*
X306208Y1666295D01*
X306541Y1666378D01*
X306791Y1666587D01*
X307041Y1666962D01*
G01X309308Y1667920D02*
X308975Y1667837D01*
X308725Y1667628D01*
X308558Y1667378D01*
X308433Y1667045D01*
X308391Y1666670D01*
X308433Y1666295D01*
X308558Y1665962D01*
X308725Y1665712D01*
X308975Y1665503D01*
X309308Y1665420D01*
X309641Y1665503D01*
X309891Y1665712D01*
X310058Y1665962D01*
X310183Y1666295D01*
X310225Y1666670D01*
X310183Y1667045D01*
X310058Y1667378D01*
X309891Y1667628D01*
X309641Y1667837D01*
X309308Y1667920D01*
G01X312408D02*
X312075Y1667837D01*
X311825Y1667628D01*
X311658Y1667378D01*
X311533Y1667045D01*
X311491Y1666670D01*
X311533Y1666295D01*
X311658Y1665962D01*
X311825Y1665712D01*
X312075Y1665503D01*
X312408Y1665420D01*
X312741Y1665503D01*
X312991Y1665712D01*
X313158Y1665962D01*
X313283Y1666295D01*
X313325Y1666670D01*
X313283Y1667045D01*
X313158Y1667378D01*
X312991Y1667628D01*
X312741Y1667837D01*
X312408Y1667920D01*
G01X315508Y1665420D02*
X315800Y1665462D01*
X316133Y1665587D01*
X316341Y1665795D01*
X316425Y1666087D01*
X316341Y1666378D01*
X316091Y1666628D01*
X315716Y1666753D01*
X315300D01*
X315050Y1666837D01*
X314841Y1667045D01*
X314758Y1667337D01*
X314883Y1667628D01*
X315175Y1667837D01*
X315508Y1667920D01*
X315841Y1667837D01*
X316133Y1667628D01*
X316258Y1667337D01*
X316175Y1667045D01*
X315966Y1666837D01*
X315716Y1666753D01*
X315300D01*
X314925Y1666628D01*
X314675Y1666378D01*
X314591Y1666087D01*
X314675Y1665795D01*
X314883Y1665587D01*
X315216Y1665462D01*
X315508Y1665420D01*
G01X328800Y1679000D02*
Y1675000D01*
X336200D01*
G01X305641Y1677545D02*
Y1680045D01*
X306641D01*
X306974Y1679920D01*
X307224Y1679628D01*
X307307Y1679295D01*
X307224Y1678962D01*
X307016Y1678712D01*
X306641Y1678587D01*
X305641D01*
G01X308741Y1677545D02*
Y1680045D01*
X309782D01*
X310116Y1679920D01*
X310324Y1679753D01*
X310407Y1679420D01*
X310324Y1679087D01*
X310074Y1678878D01*
X309782Y1678753D01*
X308741D01*
G01X309782D02*
X310407Y1677545D01*
G01X311966Y1677837D02*
X312257Y1677628D01*
X312591Y1677545D01*
X312924Y1677628D01*
X313216Y1677878D01*
X313424Y1678253D01*
X313507Y1678628D01*
Y1679087D01*
X313424Y1679462D01*
X313216Y1679795D01*
X312966Y1679962D01*
X312674Y1680045D01*
X312341Y1679962D01*
X312091Y1679795D01*
X311924Y1679545D01*
X311841Y1679212D01*
X311924Y1678920D01*
X312132Y1678628D01*
X312382Y1678462D01*
X312674Y1678420D01*
X313007Y1678503D01*
X313257Y1678712D01*
X313507Y1679087D01*
G01X315774Y1680045D02*
X315441Y1679962D01*
X315191Y1679753D01*
X315024Y1679503D01*
X314899Y1679170D01*
X314857Y1678795D01*
X314899Y1678420D01*
X315024Y1678087D01*
X315191Y1677837D01*
X315441Y1677628D01*
X315774Y1677545D01*
X316107Y1677628D01*
X316357Y1677837D01*
X316524Y1678087D01*
X316649Y1678420D01*
X316691Y1678795D01*
X316649Y1679170D01*
X316524Y1679503D01*
X316357Y1679753D01*
X316107Y1679962D01*
X315774Y1680045D01*
G01X318874D02*
X318541Y1679962D01*
X318291Y1679753D01*
X318124Y1679503D01*
X317999Y1679170D01*
X317957Y1678795D01*
X317999Y1678420D01*
X318124Y1678087D01*
X318291Y1677837D01*
X318541Y1677628D01*
X318874Y1677545D01*
X319207Y1677628D01*
X319457Y1677837D01*
X319624Y1678087D01*
X319749Y1678420D01*
X319791Y1678795D01*
X319749Y1679170D01*
X319624Y1679503D01*
X319457Y1679753D01*
X319207Y1679962D01*
X318874Y1680045D01*
G01X321266Y1677837D02*
X321557Y1677628D01*
X321891Y1677545D01*
X322224Y1677628D01*
X322516Y1677878D01*
X322724Y1678253D01*
X322807Y1678628D01*
Y1679087D01*
X322724Y1679462D01*
X322516Y1679795D01*
X322266Y1679962D01*
X321974Y1680045D01*
X321641Y1679962D01*
X321391Y1679795D01*
X321224Y1679545D01*
X321141Y1679212D01*
X321224Y1678920D01*
X321432Y1678628D01*
X321682Y1678462D01*
X321974Y1678420D01*
X322307Y1678503D01*
X322557Y1678712D01*
X322807Y1679087D01*
G01X330200Y1711000D02*
Y1715000D01*
X322800D01*
G01X299175Y1661420D02*
Y1663920D01*
X300216D01*
X300550Y1663795D01*
X300758Y1663628D01*
X300841Y1663295D01*
X300758Y1662962D01*
X300508Y1662753D01*
X300216Y1662628D01*
X299175D01*
G01X300216D02*
X300841Y1661420D01*
G01X302400Y1661712D02*
X302691Y1661503D01*
X303025Y1661420D01*
X303358Y1661503D01*
X303650Y1661753D01*
X303858Y1662128D01*
X303941Y1662503D01*
Y1662962D01*
X303858Y1663337D01*
X303650Y1663670D01*
X303400Y1663837D01*
X303108Y1663920D01*
X302775Y1663837D01*
X302525Y1663670D01*
X302358Y1663420D01*
X302275Y1663087D01*
X302358Y1662795D01*
X302566Y1662503D01*
X302816Y1662337D01*
X303108Y1662295D01*
X303441Y1662378D01*
X303691Y1662587D01*
X303941Y1662962D01*
G01X306208Y1663920D02*
X305875Y1663837D01*
X305625Y1663628D01*
X305458Y1663378D01*
X305333Y1663045D01*
X305291Y1662670D01*
X305333Y1662295D01*
X305458Y1661962D01*
X305625Y1661712D01*
X305875Y1661503D01*
X306208Y1661420D01*
X306541Y1661503D01*
X306791Y1661712D01*
X306958Y1661962D01*
X307083Y1662295D01*
X307125Y1662670D01*
X307083Y1663045D01*
X306958Y1663378D01*
X306791Y1663628D01*
X306541Y1663837D01*
X306208Y1663920D01*
G01X308391Y1661920D02*
X308641Y1661628D01*
X308975Y1661462D01*
X309350Y1661420D01*
X309683Y1661462D01*
X310016Y1661670D01*
X310225Y1661920D01*
X310266Y1662170D01*
X310183Y1662462D01*
X309891Y1662670D01*
X309600Y1662753D01*
X309225D01*
G01X309600D02*
X309850Y1662878D01*
X310058Y1663087D01*
X310141Y1663337D01*
X310058Y1663587D01*
X309850Y1663795D01*
X309475Y1663920D01*
X309100Y1663878D01*
X308725Y1663712D01*
G01X311491Y1661920D02*
X311741Y1661628D01*
X312075Y1661462D01*
X312450Y1661420D01*
X312783Y1661462D01*
X313116Y1661670D01*
X313325Y1661920D01*
X313366Y1662170D01*
X313283Y1662462D01*
X312991Y1662670D01*
X312700Y1662753D01*
X312325D01*
G01X312700D02*
X312950Y1662878D01*
X313158Y1663087D01*
X313241Y1663337D01*
X313158Y1663587D01*
X312950Y1663795D01*
X312575Y1663920D01*
X312200Y1663878D01*
X311825Y1663712D01*
G01X336200Y1671000D02*
Y1675000D01*
X328800D01*
G01X305641Y1681545D02*
Y1684045D01*
X306682D01*
X307016Y1683920D01*
X307224Y1683753D01*
X307307Y1683420D01*
X307224Y1683087D01*
X306974Y1682878D01*
X306682Y1682753D01*
X305641D01*
G01X306682D02*
X307307Y1681545D01*
G01X308866Y1681837D02*
X309157Y1681628D01*
X309491Y1681545D01*
X309824Y1681628D01*
X310116Y1681878D01*
X310324Y1682253D01*
X310407Y1682628D01*
Y1683087D01*
X310324Y1683462D01*
X310116Y1683795D01*
X309866Y1683962D01*
X309574Y1684045D01*
X309241Y1683962D01*
X308991Y1683795D01*
X308824Y1683545D01*
X308741Y1683212D01*
X308824Y1682920D01*
X309032Y1682628D01*
X309282Y1682462D01*
X309574Y1682420D01*
X309907Y1682503D01*
X310157Y1682712D01*
X310407Y1683087D01*
G01X312674Y1684045D02*
X312341Y1683962D01*
X312091Y1683753D01*
X311924Y1683503D01*
X311799Y1683170D01*
X311757Y1682795D01*
X311799Y1682420D01*
X311924Y1682087D01*
X312091Y1681837D01*
X312341Y1681628D01*
X312674Y1681545D01*
X313007Y1681628D01*
X313257Y1681837D01*
X313424Y1682087D01*
X313549Y1682420D01*
X313591Y1682795D01*
X313549Y1683170D01*
X313424Y1683503D01*
X313257Y1683753D01*
X313007Y1683962D01*
X312674Y1684045D01*
G01X314857Y1682045D02*
X315107Y1681753D01*
X315441Y1681587D01*
X315816Y1681545D01*
X316149Y1681587D01*
X316482Y1681795D01*
X316691Y1682045D01*
X316732Y1682295D01*
X316649Y1682587D01*
X316357Y1682795D01*
X316066Y1682878D01*
X315691D01*
G01X316066D02*
X316316Y1683003D01*
X316524Y1683212D01*
X316607Y1683462D01*
X316524Y1683712D01*
X316316Y1683920D01*
X315941Y1684045D01*
X315566Y1684003D01*
X315191Y1683837D01*
G01X319374Y1681545D02*
Y1684045D01*
X317832Y1682253D01*
X319916D01*
G01X322800Y1723000D02*
Y1719000D01*
X330200D01*
G01X322800Y1710500D02*
Y1706500D01*
X330200D01*
G01X322800Y1719000D02*
Y1715000D01*
X330200D01*
G01X322800Y1706300D02*
Y1702300D01*
X330200D01*
G01X299175Y1669420D02*
Y1671920D01*
X300216D01*
X300550Y1671795D01*
X300758Y1671628D01*
X300841Y1671295D01*
X300758Y1670962D01*
X300508Y1670753D01*
X300216Y1670628D01*
X299175D01*
G01X300216D02*
X300841Y1669420D01*
G01X303608D02*
Y1671920D01*
X302066Y1670128D01*
X304150D01*
G01X306208Y1669420D02*
Y1671920D01*
X305708Y1671420D01*
G01Y1669420D02*
X306708D01*
G01X308600Y1669712D02*
X308891Y1669503D01*
X309225Y1669420D01*
X309558Y1669503D01*
X309850Y1669753D01*
X310058Y1670128D01*
X310141Y1670503D01*
Y1670962D01*
X310058Y1671337D01*
X309850Y1671670D01*
X309600Y1671837D01*
X309308Y1671920D01*
X308975Y1671837D01*
X308725Y1671670D01*
X308558Y1671420D01*
X308475Y1671087D01*
X308558Y1670795D01*
X308766Y1670503D01*
X309016Y1670337D01*
X309308Y1670295D01*
X309641Y1670378D01*
X309891Y1670587D01*
X310141Y1670962D01*
G01X328800Y1683000D02*
Y1679000D01*
X336200D01*
G01X299175Y1673420D02*
Y1675920D01*
X300216D01*
X300550Y1675795D01*
X300758Y1675628D01*
X300841Y1675295D01*
X300758Y1674962D01*
X300508Y1674753D01*
X300216Y1674628D01*
X299175D01*
G01X300216D02*
X300841Y1673420D01*
G01X303608D02*
Y1675920D01*
X302066Y1674128D01*
X304150D01*
G01X305416Y1675503D02*
X305666Y1675753D01*
X305958Y1675878D01*
X306291Y1675920D01*
X306708Y1675837D01*
X307000Y1675628D01*
X307083Y1675378D01*
X307041Y1675128D01*
X306875Y1674920D01*
X306041Y1674503D01*
X305666Y1674212D01*
X305416Y1673795D01*
X305333Y1673420D01*
X307083D01*
G01X309308Y1675920D02*
X308975Y1675837D01*
X308725Y1675628D01*
X308558Y1675378D01*
X308433Y1675045D01*
X308391Y1674670D01*
X308433Y1674295D01*
X308558Y1673962D01*
X308725Y1673712D01*
X308975Y1673503D01*
X309308Y1673420D01*
X309641Y1673503D01*
X309891Y1673712D01*
X310058Y1673962D01*
X310183Y1674295D01*
X310225Y1674670D01*
X310183Y1675045D01*
X310058Y1675378D01*
X309891Y1675628D01*
X309641Y1675837D01*
X309308Y1675920D01*
G01X328800Y1687000D02*
Y1683000D01*
X336200D01*
G01X284726Y1680519D02*
X282226D01*
Y1681560D01*
X282351Y1681894D01*
X282518Y1682102D01*
X282851Y1682185D01*
X283184Y1682102D01*
X283393Y1681852D01*
X283518Y1681560D01*
Y1680519D01*
G01Y1681560D02*
X284726Y1682185D01*
G01X284434Y1683744D02*
X284643Y1684035D01*
X284726Y1684369D01*
X284643Y1684702D01*
X284393Y1684994D01*
X284018Y1685202D01*
X283643Y1685285D01*
X283184D01*
X282809Y1685202D01*
X282476Y1684994D01*
X282309Y1684744D01*
X282226Y1684452D01*
X282309Y1684119D01*
X282476Y1683869D01*
X282726Y1683702D01*
X283059Y1683619D01*
X283351Y1683702D01*
X283643Y1683910D01*
X283809Y1684160D01*
X283851Y1684452D01*
X283768Y1684785D01*
X283559Y1685035D01*
X283184Y1685285D01*
G01X284434Y1686844D02*
X284643Y1687135D01*
X284726Y1687469D01*
X284643Y1687802D01*
X284393Y1688094D01*
X284018Y1688302D01*
X283643Y1688385D01*
X283184D01*
X282809Y1688302D01*
X282476Y1688094D01*
X282309Y1687844D01*
X282226Y1687552D01*
X282309Y1687219D01*
X282476Y1686969D01*
X282726Y1686802D01*
X283059Y1686719D01*
X283351Y1686802D01*
X283643Y1687010D01*
X283809Y1687260D01*
X283851Y1687552D01*
X283768Y1687885D01*
X283559Y1688135D01*
X283184Y1688385D01*
G01X283684Y1689860D02*
X283393Y1690152D01*
X283226Y1690402D01*
X283143Y1690735D01*
X283226Y1691027D01*
X283393Y1691235D01*
X283643Y1691402D01*
X283934Y1691444D01*
X284184Y1691402D01*
X284434Y1691235D01*
X284643Y1690985D01*
X284726Y1690694D01*
X284643Y1690360D01*
X284393Y1690069D01*
X284018Y1689902D01*
X283601Y1689860D01*
X283059Y1689944D01*
X282768Y1690069D01*
X282476Y1690277D01*
X282268Y1690569D01*
X282226Y1690860D01*
X282309Y1691152D01*
X282518Y1691360D01*
G01X284726Y1693752D02*
X282226D01*
X282726Y1693252D01*
G01X284726D02*
Y1694252D01*
G01X304200Y1698050D02*
X308200D01*
Y1705450D01*
G01X284626Y1663019D02*
X282126D01*
Y1664060D01*
X282251Y1664394D01*
X282418Y1664602D01*
X282751Y1664685D01*
X283084Y1664602D01*
X283293Y1664352D01*
X283418Y1664060D01*
Y1663019D01*
G01Y1664060D02*
X284626Y1664685D01*
G01X284334Y1666244D02*
X284543Y1666535D01*
X284626Y1666869D01*
X284543Y1667202D01*
X284293Y1667494D01*
X283918Y1667702D01*
X283543Y1667785D01*
X283084D01*
X282709Y1667702D01*
X282376Y1667494D01*
X282209Y1667244D01*
X282126Y1666952D01*
X282209Y1666619D01*
X282376Y1666369D01*
X282626Y1666202D01*
X282959Y1666119D01*
X283251Y1666202D01*
X283543Y1666410D01*
X283709Y1666660D01*
X283751Y1666952D01*
X283668Y1667285D01*
X283459Y1667535D01*
X283084Y1667785D01*
G01X284334Y1669344D02*
X284543Y1669635D01*
X284626Y1669969D01*
X284543Y1670302D01*
X284293Y1670594D01*
X283918Y1670802D01*
X283543Y1670885D01*
X283084D01*
X282709Y1670802D01*
X282376Y1670594D01*
X282209Y1670344D01*
X282126Y1670052D01*
X282209Y1669719D01*
X282376Y1669469D01*
X282626Y1669302D01*
X282959Y1669219D01*
X283251Y1669302D01*
X283543Y1669510D01*
X283709Y1669760D01*
X283751Y1670052D01*
X283668Y1670385D01*
X283459Y1670635D01*
X283084Y1670885D01*
G01X284251Y1672235D02*
X284459Y1672485D01*
X284584Y1672777D01*
X284626Y1673152D01*
X284543Y1673527D01*
X284376Y1673819D01*
X284084Y1674027D01*
X283751Y1674069D01*
X283418Y1673985D01*
X283209Y1673777D01*
X283043Y1673485D01*
X283001Y1673194D01*
X283043Y1672902D01*
X283209Y1672527D01*
X282126Y1672652D01*
Y1673777D01*
G01X284626Y1676252D02*
X284584Y1676544D01*
X284459Y1676877D01*
X284251Y1677085D01*
X283959Y1677169D01*
X283668Y1677085D01*
X283418Y1676835D01*
X283293Y1676460D01*
Y1676044D01*
X283209Y1675794D01*
X283001Y1675585D01*
X282709Y1675502D01*
X282418Y1675627D01*
X282209Y1675919D01*
X282126Y1676252D01*
X282209Y1676585D01*
X282418Y1676877D01*
X282709Y1677002D01*
X283001Y1676919D01*
X283209Y1676710D01*
X283293Y1676460D01*
Y1676044D01*
X283418Y1675669D01*
X283668Y1675419D01*
X283959Y1675335D01*
X284251Y1675419D01*
X284459Y1675627D01*
X284584Y1675960D01*
X284626Y1676252D01*
G01X308200Y1697950D02*
X304200D01*
Y1690550D01*
G01X289126Y1679919D02*
X286626D01*
Y1680960D01*
X286751Y1681294D01*
X286918Y1681502D01*
X287251Y1681585D01*
X287584Y1681502D01*
X287793Y1681252D01*
X287918Y1680960D01*
Y1679919D01*
G01Y1680960D02*
X289126Y1681585D01*
G01X288834Y1683144D02*
X289043Y1683435D01*
X289126Y1683769D01*
X289043Y1684102D01*
X288793Y1684394D01*
X288418Y1684602D01*
X288043Y1684685D01*
X287584D01*
X287209Y1684602D01*
X286876Y1684394D01*
X286709Y1684144D01*
X286626Y1683852D01*
X286709Y1683519D01*
X286876Y1683269D01*
X287126Y1683102D01*
X287459Y1683019D01*
X287751Y1683102D01*
X288043Y1683310D01*
X288209Y1683560D01*
X288251Y1683852D01*
X288168Y1684185D01*
X287959Y1684435D01*
X287584Y1684685D01*
G01X288834Y1686244D02*
X289043Y1686535D01*
X289126Y1686869D01*
X289043Y1687202D01*
X288793Y1687494D01*
X288418Y1687702D01*
X288043Y1687785D01*
X287584D01*
X287209Y1687702D01*
X286876Y1687494D01*
X286709Y1687244D01*
X286626Y1686952D01*
X286709Y1686619D01*
X286876Y1686369D01*
X287126Y1686202D01*
X287459Y1686119D01*
X287751Y1686202D01*
X288043Y1686410D01*
X288209Y1686660D01*
X288251Y1686952D01*
X288168Y1687285D01*
X287959Y1687535D01*
X287584Y1687785D01*
G01X288084Y1689260D02*
X287793Y1689552D01*
X287626Y1689802D01*
X287543Y1690135D01*
X287626Y1690427D01*
X287793Y1690635D01*
X288043Y1690802D01*
X288334Y1690844D01*
X288584Y1690802D01*
X288834Y1690635D01*
X289043Y1690385D01*
X289126Y1690094D01*
X289043Y1689760D01*
X288793Y1689469D01*
X288418Y1689302D01*
X288001Y1689260D01*
X287459Y1689344D01*
X287168Y1689469D01*
X286876Y1689677D01*
X286668Y1689969D01*
X286626Y1690260D01*
X286709Y1690552D01*
X286918Y1690760D01*
G01X286626Y1693152D02*
X286709Y1692819D01*
X286918Y1692569D01*
X287168Y1692402D01*
X287501Y1692277D01*
X287876Y1692235D01*
X288251Y1692277D01*
X288584Y1692402D01*
X288834Y1692569D01*
X289043Y1692819D01*
X289126Y1693152D01*
X289043Y1693485D01*
X288834Y1693735D01*
X288584Y1693902D01*
X288251Y1694027D01*
X287876Y1694069D01*
X287501Y1694027D01*
X287168Y1693902D01*
X286918Y1693735D01*
X286709Y1693485D01*
X286626Y1693152D01*
G01X312300Y1705450D02*
X308300D01*
Y1698050D01*
G01X289326Y1663319D02*
X286826D01*
Y1664360D01*
X286951Y1664694D01*
X287118Y1664902D01*
X287451Y1664985D01*
X287784Y1664902D01*
X287993Y1664652D01*
X288118Y1664360D01*
Y1663319D01*
G01Y1664360D02*
X289326Y1664985D01*
G01X289034Y1666544D02*
X289243Y1666835D01*
X289326Y1667169D01*
X289243Y1667502D01*
X288993Y1667794D01*
X288618Y1668002D01*
X288243Y1668085D01*
X287784D01*
X287409Y1668002D01*
X287076Y1667794D01*
X286909Y1667544D01*
X286826Y1667252D01*
X286909Y1666919D01*
X287076Y1666669D01*
X287326Y1666502D01*
X287659Y1666419D01*
X287951Y1666502D01*
X288243Y1666710D01*
X288409Y1666960D01*
X288451Y1667252D01*
X288368Y1667585D01*
X288159Y1667835D01*
X287784Y1668085D01*
G01X289034Y1669644D02*
X289243Y1669935D01*
X289326Y1670269D01*
X289243Y1670602D01*
X288993Y1670894D01*
X288618Y1671102D01*
X288243Y1671185D01*
X287784D01*
X287409Y1671102D01*
X287076Y1670894D01*
X286909Y1670644D01*
X286826Y1670352D01*
X286909Y1670019D01*
X287076Y1669769D01*
X287326Y1669602D01*
X287659Y1669519D01*
X287951Y1669602D01*
X288243Y1669810D01*
X288409Y1670060D01*
X288451Y1670352D01*
X288368Y1670685D01*
X288159Y1670935D01*
X287784Y1671185D01*
G01X288951Y1672535D02*
X289159Y1672785D01*
X289284Y1673077D01*
X289326Y1673452D01*
X289243Y1673827D01*
X289076Y1674119D01*
X288784Y1674327D01*
X288451Y1674369D01*
X288118Y1674285D01*
X287909Y1674077D01*
X287743Y1673785D01*
X287701Y1673494D01*
X287743Y1673202D01*
X287909Y1672827D01*
X286826Y1672952D01*
Y1674077D01*
G01X289326Y1676469D02*
X288784Y1676552D01*
X288326Y1676677D01*
X287909Y1676844D01*
X287451Y1677052D01*
X286826Y1677385D01*
Y1675719D01*
G01X308300Y1690550D02*
X312300D01*
Y1697950D01*
G01X288083Y1720504D02*
Y1723004D01*
X289667D01*
G01X289083Y1721796D02*
X288083D01*
G01X292308Y1721837D02*
X292475Y1721962D01*
X292600Y1722171D01*
X292683Y1722462D01*
X292600Y1722712D01*
X292433Y1722879D01*
X292142Y1723004D01*
X291017D01*
Y1720504D01*
X292392D01*
X292683Y1720671D01*
X292850Y1720921D01*
X292933Y1721212D01*
X292850Y1721504D01*
X292600Y1721754D01*
X292308Y1721837D01*
X291017D01*
G01X294283Y1721546D02*
X294575Y1721837D01*
X294825Y1722004D01*
X295158Y1722087D01*
X295450Y1722004D01*
X295658Y1721837D01*
X295825Y1721587D01*
X295867Y1721296D01*
X295825Y1721046D01*
X295658Y1720796D01*
X295408Y1720587D01*
X295117Y1720504D01*
X294783Y1720587D01*
X294492Y1720837D01*
X294325Y1721212D01*
X294283Y1721629D01*
X294367Y1722171D01*
X294492Y1722462D01*
X294700Y1722754D01*
X294992Y1722962D01*
X295283Y1723004D01*
X295575Y1722921D01*
X295783Y1722712D01*
G01X304800Y1718600D02*
Y1725600D01*
X318200D01*
Y1718600D01*
X304800D01*
G01X289792Y1718796D02*
X289542Y1718921D01*
X289250Y1719004D01*
X288917D01*
X288542Y1718879D01*
X288250Y1718671D01*
X288042Y1718421D01*
X287875Y1718004D01*
X287833Y1717629D01*
X287917Y1717254D01*
X288042Y1717004D01*
X288292Y1716754D01*
X288583Y1716587D01*
X288875Y1716504D01*
X289167D01*
X289458Y1716587D01*
X289708Y1716712D01*
X289917Y1716879D01*
G01X291975Y1716504D02*
X292267Y1716546D01*
X292600Y1716671D01*
X292808Y1716879D01*
X292892Y1717171D01*
X292808Y1717462D01*
X292558Y1717712D01*
X292183Y1717837D01*
X291767D01*
X291517Y1717921D01*
X291308Y1718129D01*
X291225Y1718421D01*
X291350Y1718712D01*
X291642Y1718921D01*
X291975Y1719004D01*
X292308Y1718921D01*
X292600Y1718712D01*
X292725Y1718421D01*
X292642Y1718129D01*
X292433Y1717921D01*
X292183Y1717837D01*
X291767D01*
X291392Y1717712D01*
X291142Y1717462D01*
X291058Y1717171D01*
X291142Y1716879D01*
X291350Y1716671D01*
X291683Y1716546D01*
X291975Y1716504D01*
G01X295075D02*
X295367Y1716546D01*
X295700Y1716671D01*
X295908Y1716879D01*
X295992Y1717171D01*
X295908Y1717462D01*
X295658Y1717712D01*
X295283Y1717837D01*
X294867D01*
X294617Y1717921D01*
X294408Y1718129D01*
X294325Y1718421D01*
X294450Y1718712D01*
X294742Y1718921D01*
X295075Y1719004D01*
X295408Y1718921D01*
X295700Y1718712D01*
X295825Y1718421D01*
X295742Y1718129D01*
X295533Y1717921D01*
X295283Y1717837D01*
X294867D01*
X294492Y1717712D01*
X294242Y1717462D01*
X294158Y1717171D01*
X294242Y1716879D01*
X294450Y1716671D01*
X294783Y1716546D01*
X295075Y1716504D01*
G01X297467Y1716796D02*
X297758Y1716587D01*
X298092Y1716504D01*
X298425Y1716587D01*
X298717Y1716837D01*
X298925Y1717212D01*
X299008Y1717587D01*
Y1718046D01*
X298925Y1718421D01*
X298717Y1718754D01*
X298467Y1718921D01*
X298175Y1719004D01*
X297842Y1718921D01*
X297592Y1718754D01*
X297425Y1718504D01*
X297342Y1718171D01*
X297425Y1717879D01*
X297633Y1717587D01*
X297883Y1717421D01*
X298175Y1717379D01*
X298508Y1717462D01*
X298758Y1717671D01*
X299008Y1718046D01*
G01X301192Y1716504D02*
X301275Y1717046D01*
X301400Y1717504D01*
X301567Y1717921D01*
X301775Y1718379D01*
X302108Y1719004D01*
X300442D01*
G01X302400Y1677367D02*
X299900D01*
Y1678408D01*
X300025Y1678742D01*
X300192Y1678950D01*
X300525Y1679033D01*
X300858Y1678950D01*
X301067Y1678700D01*
X301192Y1678408D01*
Y1677367D01*
G01Y1678408D02*
X302400Y1679033D01*
G01X302108Y1680592D02*
X302317Y1680883D01*
X302400Y1681217D01*
X302317Y1681550D01*
X302067Y1681842D01*
X301692Y1682050D01*
X301317Y1682133D01*
X300858D01*
X300483Y1682050D01*
X300150Y1681842D01*
X299983Y1681592D01*
X299900Y1681300D01*
X299983Y1680967D01*
X300150Y1680717D01*
X300400Y1680550D01*
X300733Y1680467D01*
X301025Y1680550D01*
X301317Y1680758D01*
X301483Y1681008D01*
X301525Y1681300D01*
X301442Y1681633D01*
X301233Y1681883D01*
X300858Y1682133D01*
G01X302108Y1683692D02*
X302317Y1683983D01*
X302400Y1684317D01*
X302317Y1684650D01*
X302067Y1684942D01*
X301692Y1685150D01*
X301317Y1685233D01*
X300858D01*
X300483Y1685150D01*
X300150Y1684942D01*
X299983Y1684692D01*
X299900Y1684400D01*
X299983Y1684067D01*
X300150Y1683817D01*
X300400Y1683650D01*
X300733Y1683567D01*
X301025Y1683650D01*
X301317Y1683858D01*
X301483Y1684108D01*
X301525Y1684400D01*
X301442Y1684733D01*
X301233Y1684983D01*
X300858Y1685233D01*
G01X302025Y1686583D02*
X302233Y1686833D01*
X302358Y1687125D01*
X302400Y1687500D01*
X302317Y1687875D01*
X302150Y1688167D01*
X301858Y1688375D01*
X301525Y1688417D01*
X301192Y1688333D01*
X300983Y1688125D01*
X300817Y1687833D01*
X300775Y1687542D01*
X300817Y1687250D01*
X300983Y1686875D01*
X299900Y1687000D01*
Y1688125D01*
G01X302108Y1689892D02*
X302317Y1690183D01*
X302400Y1690517D01*
X302317Y1690850D01*
X302067Y1691142D01*
X301692Y1691350D01*
X301317Y1691433D01*
X300858D01*
X300483Y1691350D01*
X300150Y1691142D01*
X299983Y1690892D01*
X299900Y1690600D01*
X299983Y1690267D01*
X300150Y1690017D01*
X300400Y1689850D01*
X300733Y1689767D01*
X301025Y1689850D01*
X301317Y1690058D01*
X301483Y1690308D01*
X301525Y1690600D01*
X301442Y1690933D01*
X301233Y1691183D01*
X300858Y1691433D01*
G01X324777Y1736917D02*
X324652Y1736667D01*
X324569Y1736375D01*
Y1736042D01*
X324694Y1735667D01*
X324902Y1735375D01*
X325152Y1735167D01*
X325569Y1735000D01*
X325944Y1734958D01*
X326319Y1735042D01*
X326569Y1735167D01*
X326819Y1735417D01*
X326986Y1735708D01*
X327069Y1736000D01*
Y1736292D01*
X326986Y1736583D01*
X326861Y1736833D01*
X326694Y1737042D01*
G01X327069Y1739100D02*
X327027Y1739392D01*
X326902Y1739725D01*
X326694Y1739933D01*
X326402Y1740017D01*
X326111Y1739933D01*
X325861Y1739683D01*
X325736Y1739308D01*
Y1738892D01*
X325652Y1738642D01*
X325444Y1738433D01*
X325152Y1738350D01*
X324861Y1738475D01*
X324652Y1738767D01*
X324569Y1739100D01*
X324652Y1739433D01*
X324861Y1739725D01*
X325152Y1739850D01*
X325444Y1739767D01*
X325652Y1739558D01*
X325736Y1739308D01*
Y1738892D01*
X325861Y1738517D01*
X326111Y1738267D01*
X326402Y1738183D01*
X326694Y1738267D01*
X326902Y1738475D01*
X327027Y1738808D01*
X327069Y1739100D01*
G01Y1742200D02*
X327027Y1742492D01*
X326902Y1742825D01*
X326694Y1743033D01*
X326402Y1743117D01*
X326111Y1743033D01*
X325861Y1742783D01*
X325736Y1742408D01*
Y1741992D01*
X325652Y1741742D01*
X325444Y1741533D01*
X325152Y1741450D01*
X324861Y1741575D01*
X324652Y1741867D01*
X324569Y1742200D01*
X324652Y1742533D01*
X324861Y1742825D01*
X325152Y1742950D01*
X325444Y1742867D01*
X325652Y1742658D01*
X325736Y1742408D01*
Y1741992D01*
X325861Y1741617D01*
X326111Y1741367D01*
X326402Y1741283D01*
X326694Y1741367D01*
X326902Y1741575D01*
X327027Y1741908D01*
X327069Y1742200D01*
G01X326777Y1744592D02*
X326986Y1744883D01*
X327069Y1745217D01*
X326986Y1745550D01*
X326736Y1745842D01*
X326361Y1746050D01*
X325986Y1746133D01*
X325527D01*
X325152Y1746050D01*
X324819Y1745842D01*
X324652Y1745592D01*
X324569Y1745300D01*
X324652Y1744967D01*
X324819Y1744717D01*
X325069Y1744550D01*
X325402Y1744467D01*
X325694Y1744550D01*
X325986Y1744758D01*
X326152Y1745008D01*
X326194Y1745300D01*
X326111Y1745633D01*
X325902Y1745883D01*
X325527Y1746133D01*
G01X326569Y1747483D02*
X326861Y1747733D01*
X327027Y1748067D01*
X327069Y1748442D01*
X327027Y1748775D01*
X326819Y1749108D01*
X326569Y1749317D01*
X326319Y1749358D01*
X326027Y1749275D01*
X325819Y1748983D01*
X325736Y1748692D01*
Y1748317D01*
G01Y1748692D02*
X325611Y1748942D01*
X325402Y1749150D01*
X325152Y1749233D01*
X324902Y1749150D01*
X324694Y1748942D01*
X324569Y1748567D01*
X324611Y1748192D01*
X324777Y1747817D01*
G01X328667Y1736997D02*
X328542Y1736747D01*
X328459Y1736455D01*
Y1736122D01*
X328584Y1735747D01*
X328792Y1735455D01*
X329042Y1735247D01*
X329459Y1735080D01*
X329834Y1735038D01*
X330209Y1735122D01*
X330459Y1735247D01*
X330709Y1735497D01*
X330876Y1735788D01*
X330959Y1736080D01*
Y1736372D01*
X330876Y1736663D01*
X330751Y1736913D01*
X330584Y1737122D01*
G01X330959Y1739180D02*
X330917Y1739472D01*
X330792Y1739805D01*
X330584Y1740013D01*
X330292Y1740097D01*
X330001Y1740013D01*
X329751Y1739763D01*
X329626Y1739388D01*
Y1738972D01*
X329542Y1738722D01*
X329334Y1738513D01*
X329042Y1738430D01*
X328751Y1738555D01*
X328542Y1738847D01*
X328459Y1739180D01*
X328542Y1739513D01*
X328751Y1739805D01*
X329042Y1739930D01*
X329334Y1739847D01*
X329542Y1739638D01*
X329626Y1739388D01*
Y1738972D01*
X329751Y1738597D01*
X330001Y1738347D01*
X330292Y1738263D01*
X330584Y1738347D01*
X330792Y1738555D01*
X330917Y1738888D01*
X330959Y1739180D01*
G01Y1742280D02*
X330917Y1742572D01*
X330792Y1742905D01*
X330584Y1743113D01*
X330292Y1743197D01*
X330001Y1743113D01*
X329751Y1742863D01*
X329626Y1742488D01*
Y1742072D01*
X329542Y1741822D01*
X329334Y1741613D01*
X329042Y1741530D01*
X328751Y1741655D01*
X328542Y1741947D01*
X328459Y1742280D01*
X328542Y1742613D01*
X328751Y1742905D01*
X329042Y1743030D01*
X329334Y1742947D01*
X329542Y1742738D01*
X329626Y1742488D01*
Y1742072D01*
X329751Y1741697D01*
X330001Y1741447D01*
X330292Y1741363D01*
X330584Y1741447D01*
X330792Y1741655D01*
X330917Y1741988D01*
X330959Y1742280D01*
G01X330667Y1744672D02*
X330876Y1744963D01*
X330959Y1745297D01*
X330876Y1745630D01*
X330626Y1745922D01*
X330251Y1746130D01*
X329876Y1746213D01*
X329417D01*
X329042Y1746130D01*
X328709Y1745922D01*
X328542Y1745672D01*
X328459Y1745380D01*
X328542Y1745047D01*
X328709Y1744797D01*
X328959Y1744630D01*
X329292Y1744547D01*
X329584Y1744630D01*
X329876Y1744838D01*
X330042Y1745088D01*
X330084Y1745380D01*
X330001Y1745713D01*
X329792Y1745963D01*
X329417Y1746213D01*
G01X330959Y1748980D02*
X328459D01*
X330251Y1747438D01*
Y1749522D01*
G01X287367Y1757647D02*
X287242Y1757397D01*
X287159Y1757105D01*
Y1756772D01*
X287284Y1756397D01*
X287492Y1756105D01*
X287742Y1755897D01*
X288159Y1755730D01*
X288534Y1755688D01*
X288909Y1755772D01*
X289159Y1755897D01*
X289409Y1756147D01*
X289576Y1756438D01*
X289659Y1756730D01*
Y1757022D01*
X289576Y1757313D01*
X289451Y1757563D01*
X289284Y1757772D01*
G01X289159Y1758913D02*
X289451Y1759163D01*
X289617Y1759497D01*
X289659Y1759872D01*
X289617Y1760205D01*
X289409Y1760538D01*
X289159Y1760747D01*
X288909Y1760788D01*
X288617Y1760705D01*
X288409Y1760413D01*
X288326Y1760122D01*
Y1759747D01*
G01Y1760122D02*
X288201Y1760372D01*
X287992Y1760580D01*
X287742Y1760663D01*
X287492Y1760580D01*
X287284Y1760372D01*
X287159Y1759997D01*
X287201Y1759622D01*
X287367Y1759247D01*
G01X289659Y1763430D02*
X287159D01*
X288951Y1761888D01*
Y1763972D01*
G01X288617Y1765238D02*
X288326Y1765530D01*
X288159Y1765780D01*
X288076Y1766113D01*
X288159Y1766405D01*
X288326Y1766613D01*
X288576Y1766780D01*
X288867Y1766822D01*
X289117Y1766780D01*
X289367Y1766613D01*
X289576Y1766363D01*
X289659Y1766072D01*
X289576Y1765738D01*
X289326Y1765447D01*
X288951Y1765280D01*
X288534Y1765238D01*
X287992Y1765322D01*
X287701Y1765447D01*
X287409Y1765655D01*
X287201Y1765947D01*
X287159Y1766238D01*
X287242Y1766530D01*
X287451Y1766738D01*
G01X292367Y1757647D02*
X292242Y1757397D01*
X292159Y1757105D01*
Y1756772D01*
X292284Y1756397D01*
X292492Y1756105D01*
X292742Y1755897D01*
X293159Y1755730D01*
X293534Y1755688D01*
X293909Y1755772D01*
X294159Y1755897D01*
X294409Y1756147D01*
X294576Y1756438D01*
X294659Y1756730D01*
Y1757022D01*
X294576Y1757313D01*
X294451Y1757563D01*
X294284Y1757772D01*
G01X294159Y1758913D02*
X294451Y1759163D01*
X294617Y1759497D01*
X294659Y1759872D01*
X294617Y1760205D01*
X294409Y1760538D01*
X294159Y1760747D01*
X293909Y1760788D01*
X293617Y1760705D01*
X293409Y1760413D01*
X293326Y1760122D01*
Y1759747D01*
G01Y1760122D02*
X293201Y1760372D01*
X292992Y1760580D01*
X292742Y1760663D01*
X292492Y1760580D01*
X292284Y1760372D01*
X292159Y1759997D01*
X292201Y1759622D01*
X292367Y1759247D01*
G01X294659Y1763430D02*
X292159D01*
X293951Y1761888D01*
Y1763972D01*
G01X294659Y1765947D02*
X294117Y1766030D01*
X293659Y1766155D01*
X293242Y1766322D01*
X292784Y1766530D01*
X292159Y1766863D01*
Y1765197D01*
G01X293500Y1793700D02*
X289500D01*
Y1786300D01*
G01X285500Y1793700D02*
X281500D01*
Y1786300D01*
G01X277500Y1793700D02*
X273500D01*
Y1786300D01*
G01X285500D02*
X289500D01*
Y1793700D01*
G01X277500Y1786300D02*
X281500D01*
Y1793700D01*
G01X269500Y1786300D02*
X273500D01*
Y1793700D01*
G01X268089Y1726747D02*
X265589D01*
Y1727788D01*
X265714Y1728122D01*
X265881Y1728330D01*
X266214Y1728413D01*
X266547Y1728330D01*
X266756Y1728080D01*
X266881Y1727788D01*
Y1726747D01*
G01Y1727788D02*
X268089Y1728413D01*
G01X267589Y1729763D02*
X267881Y1730013D01*
X268047Y1730347D01*
X268089Y1730722D01*
X268047Y1731055D01*
X267839Y1731388D01*
X267589Y1731597D01*
X267339Y1731638D01*
X267047Y1731555D01*
X266839Y1731263D01*
X266756Y1730972D01*
Y1730597D01*
G01Y1730972D02*
X266631Y1731222D01*
X266422Y1731430D01*
X266172Y1731513D01*
X265922Y1731430D01*
X265714Y1731222D01*
X265589Y1730847D01*
X265631Y1730472D01*
X265797Y1730097D01*
G01X267714Y1732863D02*
X267922Y1733113D01*
X268047Y1733405D01*
X268089Y1733780D01*
X268006Y1734155D01*
X267839Y1734447D01*
X267547Y1734655D01*
X267214Y1734697D01*
X266881Y1734613D01*
X266672Y1734405D01*
X266506Y1734113D01*
X266464Y1733822D01*
X266506Y1733530D01*
X266672Y1733155D01*
X265589Y1733280D01*
Y1734405D01*
G01X268089Y1736880D02*
X265589D01*
X266089Y1736380D01*
G01X268089D02*
Y1737380D01*
G01X282500Y1736700D02*
X278500D01*
Y1729300D01*
G01X264089Y1726747D02*
X261589D01*
Y1727788D01*
X261714Y1728122D01*
X261881Y1728330D01*
X262214Y1728413D01*
X262547Y1728330D01*
X262756Y1728080D01*
X262881Y1727788D01*
Y1726747D01*
G01Y1727788D02*
X264089Y1728413D01*
G01X263589Y1729763D02*
X263881Y1730013D01*
X264047Y1730347D01*
X264089Y1730722D01*
X264047Y1731055D01*
X263839Y1731388D01*
X263589Y1731597D01*
X263339Y1731638D01*
X263047Y1731555D01*
X262839Y1731263D01*
X262756Y1730972D01*
Y1730597D01*
G01Y1730972D02*
X262631Y1731222D01*
X262422Y1731430D01*
X262172Y1731513D01*
X261922Y1731430D01*
X261714Y1731222D01*
X261589Y1730847D01*
X261631Y1730472D01*
X261797Y1730097D01*
G01X263714Y1732863D02*
X263922Y1733113D01*
X264047Y1733405D01*
X264089Y1733780D01*
X264006Y1734155D01*
X263839Y1734447D01*
X263547Y1734655D01*
X263214Y1734697D01*
X262881Y1734613D01*
X262672Y1734405D01*
X262506Y1734113D01*
X262464Y1733822D01*
X262506Y1733530D01*
X262672Y1733155D01*
X261589Y1733280D01*
Y1734405D01*
G01X262006Y1736088D02*
X261756Y1736338D01*
X261631Y1736630D01*
X261589Y1736963D01*
X261672Y1737380D01*
X261881Y1737672D01*
X262131Y1737755D01*
X262381Y1737713D01*
X262589Y1737547D01*
X263006Y1736713D01*
X263297Y1736338D01*
X263714Y1736088D01*
X264089Y1736005D01*
Y1737755D01*
G01X278500Y1736700D02*
X274500D01*
Y1729300D01*
G01X260089Y1726747D02*
X257589D01*
Y1727788D01*
X257714Y1728122D01*
X257881Y1728330D01*
X258214Y1728413D01*
X258547Y1728330D01*
X258756Y1728080D01*
X258881Y1727788D01*
Y1726747D01*
G01Y1727788D02*
X260089Y1728413D01*
G01X259589Y1729763D02*
X259881Y1730013D01*
X260047Y1730347D01*
X260089Y1730722D01*
X260047Y1731055D01*
X259839Y1731388D01*
X259589Y1731597D01*
X259339Y1731638D01*
X259047Y1731555D01*
X258839Y1731263D01*
X258756Y1730972D01*
Y1730597D01*
G01Y1730972D02*
X258631Y1731222D01*
X258422Y1731430D01*
X258172Y1731513D01*
X257922Y1731430D01*
X257714Y1731222D01*
X257589Y1730847D01*
X257631Y1730472D01*
X257797Y1730097D01*
G01X259714Y1732863D02*
X259922Y1733113D01*
X260047Y1733405D01*
X260089Y1733780D01*
X260006Y1734155D01*
X259839Y1734447D01*
X259547Y1734655D01*
X259214Y1734697D01*
X258881Y1734613D01*
X258672Y1734405D01*
X258506Y1734113D01*
X258464Y1733822D01*
X258506Y1733530D01*
X258672Y1733155D01*
X257589Y1733280D01*
Y1734405D01*
G01X260089Y1737380D02*
X257589D01*
X259381Y1735838D01*
Y1737922D01*
G01X274500Y1736700D02*
X270500D01*
Y1729300D01*
G01X279317Y1725100D02*
Y1727600D01*
X280358D01*
X280692Y1727475D01*
X280900Y1727308D01*
X280983Y1726975D01*
X280900Y1726642D01*
X280650Y1726433D01*
X280358Y1726308D01*
X279317D01*
G01X280358D02*
X280983Y1725100D01*
G01X282333Y1725600D02*
X282583Y1725308D01*
X282917Y1725142D01*
X283292Y1725100D01*
X283625Y1725142D01*
X283958Y1725350D01*
X284167Y1725600D01*
X284208Y1725850D01*
X284125Y1726142D01*
X283833Y1726350D01*
X283542Y1726433D01*
X283167D01*
G01X283542D02*
X283792Y1726558D01*
X284000Y1726767D01*
X284083Y1727017D01*
X284000Y1727267D01*
X283792Y1727475D01*
X283417Y1727600D01*
X283042Y1727558D01*
X282667Y1727392D01*
G01X285558Y1726142D02*
X285850Y1726433D01*
X286100Y1726600D01*
X286433Y1726683D01*
X286725Y1726600D01*
X286933Y1726433D01*
X287100Y1726183D01*
X287142Y1725892D01*
X287100Y1725642D01*
X286933Y1725392D01*
X286683Y1725183D01*
X286392Y1725100D01*
X286058Y1725183D01*
X285767Y1725433D01*
X285600Y1725808D01*
X285558Y1726225D01*
X285642Y1726767D01*
X285767Y1727058D01*
X285975Y1727350D01*
X286267Y1727558D01*
X286558Y1727600D01*
X286850Y1727517D01*
X287058Y1727308D01*
G01X289367Y1725100D02*
X289450Y1725642D01*
X289575Y1726100D01*
X289742Y1726517D01*
X289950Y1726975D01*
X290283Y1727600D01*
X288617D01*
G01X304667Y1737600D02*
Y1740100D01*
X305667D01*
X306000Y1739975D01*
X306250Y1739683D01*
X306333Y1739350D01*
X306250Y1739017D01*
X306042Y1738767D01*
X305667Y1738642D01*
X304667D01*
G01X307767Y1737600D02*
Y1740100D01*
X308808D01*
X309142Y1739975D01*
X309350Y1739808D01*
X309433Y1739475D01*
X309350Y1739142D01*
X309100Y1738933D01*
X308808Y1738808D01*
X307767D01*
G01X308808D02*
X309433Y1737600D01*
G01X310992Y1737892D02*
X311283Y1737683D01*
X311617Y1737600D01*
X311950Y1737683D01*
X312242Y1737933D01*
X312450Y1738308D01*
X312533Y1738683D01*
Y1739142D01*
X312450Y1739517D01*
X312242Y1739850D01*
X311992Y1740017D01*
X311700Y1740100D01*
X311367Y1740017D01*
X311117Y1739850D01*
X310950Y1739600D01*
X310867Y1739267D01*
X310950Y1738975D01*
X311158Y1738683D01*
X311408Y1738517D01*
X311700Y1738475D01*
X312033Y1738558D01*
X312283Y1738767D01*
X312533Y1739142D01*
G01X314800Y1740100D02*
X314467Y1740017D01*
X314217Y1739808D01*
X314050Y1739558D01*
X313925Y1739225D01*
X313883Y1738850D01*
X313925Y1738475D01*
X314050Y1738142D01*
X314217Y1737892D01*
X314467Y1737683D01*
X314800Y1737600D01*
X315133Y1737683D01*
X315383Y1737892D01*
X315550Y1738142D01*
X315675Y1738475D01*
X315717Y1738850D01*
X315675Y1739225D01*
X315550Y1739558D01*
X315383Y1739808D01*
X315133Y1740017D01*
X314800Y1740100D01*
G01X317108Y1738642D02*
X317400Y1738933D01*
X317650Y1739100D01*
X317983Y1739183D01*
X318275Y1739100D01*
X318483Y1738933D01*
X318650Y1738683D01*
X318692Y1738392D01*
X318650Y1738142D01*
X318483Y1737892D01*
X318233Y1737683D01*
X317942Y1737600D01*
X317608Y1737683D01*
X317317Y1737933D01*
X317150Y1738308D01*
X317108Y1738725D01*
X317192Y1739267D01*
X317317Y1739558D01*
X317525Y1739850D01*
X317817Y1740058D01*
X318108Y1740100D01*
X318400Y1740017D01*
X318608Y1739808D01*
G01X321000Y1737600D02*
Y1740100D01*
X320500Y1739600D01*
G01Y1737600D02*
X321500D01*
G01X331209Y1752217D02*
X328709D01*
Y1753258D01*
X328834Y1753592D01*
X329001Y1753800D01*
X329334Y1753883D01*
X329667Y1753800D01*
X329876Y1753550D01*
X330001Y1753258D01*
Y1752217D01*
G01Y1753258D02*
X331209Y1753883D01*
G01X330917Y1755442D02*
X331126Y1755733D01*
X331209Y1756067D01*
X331126Y1756400D01*
X330876Y1756692D01*
X330501Y1756900D01*
X330126Y1756983D01*
X329667D01*
X329292Y1756900D01*
X328959Y1756692D01*
X328792Y1756442D01*
X328709Y1756150D01*
X328792Y1755817D01*
X328959Y1755567D01*
X329209Y1755400D01*
X329542Y1755317D01*
X329834Y1755400D01*
X330126Y1755608D01*
X330292Y1755858D01*
X330334Y1756150D01*
X330251Y1756483D01*
X330042Y1756733D01*
X329667Y1756983D01*
G01X328709Y1759250D02*
X328792Y1758917D01*
X329001Y1758667D01*
X329251Y1758500D01*
X329584Y1758375D01*
X329959Y1758333D01*
X330334Y1758375D01*
X330667Y1758500D01*
X330917Y1758667D01*
X331126Y1758917D01*
X331209Y1759250D01*
X331126Y1759583D01*
X330917Y1759833D01*
X330667Y1760000D01*
X330334Y1760125D01*
X329959Y1760167D01*
X329584Y1760125D01*
X329251Y1760000D01*
X329001Y1759833D01*
X328792Y1759583D01*
X328709Y1759250D01*
G01X330167Y1761558D02*
X329876Y1761850D01*
X329709Y1762100D01*
X329626Y1762433D01*
X329709Y1762725D01*
X329876Y1762933D01*
X330126Y1763100D01*
X330417Y1763142D01*
X330667Y1763100D01*
X330917Y1762933D01*
X331126Y1762683D01*
X331209Y1762392D01*
X331126Y1762058D01*
X330876Y1761767D01*
X330501Y1761600D01*
X330084Y1761558D01*
X329542Y1761642D01*
X329251Y1761767D01*
X328959Y1761975D01*
X328751Y1762267D01*
X328709Y1762558D01*
X328792Y1762850D01*
X329001Y1763058D01*
G01X330709Y1764533D02*
X331001Y1764783D01*
X331167Y1765117D01*
X331209Y1765492D01*
X331167Y1765825D01*
X330959Y1766158D01*
X330709Y1766367D01*
X330459Y1766408D01*
X330167Y1766325D01*
X329959Y1766033D01*
X329876Y1765742D01*
Y1765367D01*
G01Y1765742D02*
X329751Y1765992D01*
X329542Y1766200D01*
X329292Y1766283D01*
X329042Y1766200D01*
X328834Y1765992D01*
X328709Y1765617D01*
X328751Y1765242D01*
X328917Y1764867D01*
G01X326819Y1752137D02*
X324319D01*
Y1753178D01*
X324444Y1753512D01*
X324611Y1753720D01*
X324944Y1753803D01*
X325277Y1753720D01*
X325486Y1753470D01*
X325611Y1753178D01*
Y1752137D01*
G01Y1753178D02*
X326819Y1753803D01*
G01X326527Y1755362D02*
X326736Y1755653D01*
X326819Y1755987D01*
X326736Y1756320D01*
X326486Y1756612D01*
X326111Y1756820D01*
X325736Y1756903D01*
X325277D01*
X324902Y1756820D01*
X324569Y1756612D01*
X324402Y1756362D01*
X324319Y1756070D01*
X324402Y1755737D01*
X324569Y1755487D01*
X324819Y1755320D01*
X325152Y1755237D01*
X325444Y1755320D01*
X325736Y1755528D01*
X325902Y1755778D01*
X325944Y1756070D01*
X325861Y1756403D01*
X325652Y1756653D01*
X325277Y1756903D01*
G01X324319Y1759170D02*
X324402Y1758837D01*
X324611Y1758587D01*
X324861Y1758420D01*
X325194Y1758295D01*
X325569Y1758253D01*
X325944Y1758295D01*
X326277Y1758420D01*
X326527Y1758587D01*
X326736Y1758837D01*
X326819Y1759170D01*
X326736Y1759503D01*
X326527Y1759753D01*
X326277Y1759920D01*
X325944Y1760045D01*
X325569Y1760087D01*
X325194Y1760045D01*
X324861Y1759920D01*
X324611Y1759753D01*
X324402Y1759503D01*
X324319Y1759170D01*
G01X325777Y1761478D02*
X325486Y1761770D01*
X325319Y1762020D01*
X325236Y1762353D01*
X325319Y1762645D01*
X325486Y1762853D01*
X325736Y1763020D01*
X326027Y1763062D01*
X326277Y1763020D01*
X326527Y1762853D01*
X326736Y1762603D01*
X326819Y1762312D01*
X326736Y1761978D01*
X326486Y1761687D01*
X326111Y1761520D01*
X325694Y1761478D01*
X325152Y1761562D01*
X324861Y1761687D01*
X324569Y1761895D01*
X324361Y1762187D01*
X324319Y1762478D01*
X324402Y1762770D01*
X324611Y1762978D01*
G01X326819Y1765870D02*
X324319D01*
X326111Y1764328D01*
Y1766412D01*
G01X304625Y1745933D02*
X304958Y1745725D01*
X305333Y1745600D01*
X305667D01*
X306000Y1745725D01*
X306250Y1745933D01*
X306375Y1746225D01*
X306292Y1746517D01*
X306083Y1746767D01*
X305708Y1746933D01*
X305208Y1747017D01*
X304917Y1747183D01*
X304792Y1747475D01*
X304875Y1747767D01*
X305083Y1747975D01*
X305375Y1748100D01*
X305667D01*
X305958Y1748017D01*
X306208Y1747808D01*
G01X307767Y1745600D02*
Y1748100D01*
X308808D01*
X309142Y1747975D01*
X309350Y1747808D01*
X309433Y1747475D01*
X309350Y1747142D01*
X309100Y1746933D01*
X308808Y1746808D01*
X307767D01*
G01X308808D02*
X309433Y1745600D01*
G01X310992Y1745892D02*
X311283Y1745683D01*
X311617Y1745600D01*
X311950Y1745683D01*
X312242Y1745933D01*
X312450Y1746308D01*
X312533Y1746683D01*
Y1747142D01*
X312450Y1747517D01*
X312242Y1747850D01*
X311992Y1748017D01*
X311700Y1748100D01*
X311367Y1748017D01*
X311117Y1747850D01*
X310950Y1747600D01*
X310867Y1747267D01*
X310950Y1746975D01*
X311158Y1746683D01*
X311408Y1746517D01*
X311700Y1746475D01*
X312033Y1746558D01*
X312283Y1746767D01*
X312533Y1747142D01*
G01X315300Y1745600D02*
Y1748100D01*
X313758Y1746308D01*
X315842D01*
G01X316983Y1745975D02*
X317233Y1745767D01*
X317525Y1745642D01*
X317900Y1745600D01*
X318275Y1745683D01*
X318567Y1745850D01*
X318775Y1746142D01*
X318817Y1746475D01*
X318733Y1746808D01*
X318525Y1747017D01*
X318233Y1747183D01*
X317942Y1747225D01*
X317650Y1747183D01*
X317275Y1747017D01*
X317400Y1748100D01*
X318525D01*
G01X304625Y1733933D02*
X304958Y1733725D01*
X305333Y1733600D01*
X305667D01*
X306000Y1733725D01*
X306250Y1733933D01*
X306375Y1734225D01*
X306292Y1734517D01*
X306083Y1734767D01*
X305708Y1734933D01*
X305208Y1735017D01*
X304917Y1735183D01*
X304792Y1735475D01*
X304875Y1735767D01*
X305083Y1735975D01*
X305375Y1736100D01*
X305667D01*
X305958Y1736017D01*
X306208Y1735808D01*
G01X307767Y1733600D02*
Y1736100D01*
X308808D01*
X309142Y1735975D01*
X309350Y1735808D01*
X309433Y1735475D01*
X309350Y1735142D01*
X309100Y1734933D01*
X308808Y1734808D01*
X307767D01*
G01X308808D02*
X309433Y1733600D01*
G01X310992Y1733892D02*
X311283Y1733683D01*
X311617Y1733600D01*
X311950Y1733683D01*
X312242Y1733933D01*
X312450Y1734308D01*
X312533Y1734683D01*
Y1735142D01*
X312450Y1735517D01*
X312242Y1735850D01*
X311992Y1736017D01*
X311700Y1736100D01*
X311367Y1736017D01*
X311117Y1735850D01*
X310950Y1735600D01*
X310867Y1735267D01*
X310950Y1734975D01*
X311158Y1734683D01*
X311408Y1734517D01*
X311700Y1734475D01*
X312033Y1734558D01*
X312283Y1734767D01*
X312533Y1735142D01*
G01X315300Y1733600D02*
Y1736100D01*
X313758Y1734308D01*
X315842D01*
G01X317108Y1734642D02*
X317400Y1734933D01*
X317650Y1735100D01*
X317983Y1735183D01*
X318275Y1735100D01*
X318483Y1734933D01*
X318650Y1734683D01*
X318692Y1734392D01*
X318650Y1734142D01*
X318483Y1733892D01*
X318233Y1733683D01*
X317942Y1733600D01*
X317608Y1733683D01*
X317317Y1733933D01*
X317150Y1734308D01*
X317108Y1734725D01*
X317192Y1735267D01*
X317317Y1735558D01*
X317525Y1735850D01*
X317817Y1736058D01*
X318108Y1736100D01*
X318400Y1736017D01*
X318608Y1735808D01*
G01X304625Y1741933D02*
X304958Y1741725D01*
X305333Y1741600D01*
X305667D01*
X306000Y1741725D01*
X306250Y1741933D01*
X306375Y1742225D01*
X306292Y1742517D01*
X306083Y1742767D01*
X305708Y1742933D01*
X305208Y1743017D01*
X304917Y1743183D01*
X304792Y1743475D01*
X304875Y1743767D01*
X305083Y1743975D01*
X305375Y1744100D01*
X305667D01*
X305958Y1744017D01*
X306208Y1743808D01*
G01X307767Y1741600D02*
Y1744100D01*
X308808D01*
X309142Y1743975D01*
X309350Y1743808D01*
X309433Y1743475D01*
X309350Y1743142D01*
X309100Y1742933D01*
X308808Y1742808D01*
X307767D01*
G01X308808D02*
X309433Y1741600D01*
G01X310992Y1741892D02*
X311283Y1741683D01*
X311617Y1741600D01*
X311950Y1741683D01*
X312242Y1741933D01*
X312450Y1742308D01*
X312533Y1742683D01*
Y1743142D01*
X312450Y1743517D01*
X312242Y1743850D01*
X311992Y1744017D01*
X311700Y1744100D01*
X311367Y1744017D01*
X311117Y1743850D01*
X310950Y1743600D01*
X310867Y1743267D01*
X310950Y1742975D01*
X311158Y1742683D01*
X311408Y1742517D01*
X311700Y1742475D01*
X312033Y1742558D01*
X312283Y1742767D01*
X312533Y1743142D01*
G01X315300Y1741600D02*
Y1744100D01*
X313758Y1742308D01*
X315842D01*
G01X317817Y1741600D02*
X317900Y1742142D01*
X318025Y1742600D01*
X318192Y1743017D01*
X318400Y1743475D01*
X318733Y1744100D01*
X317067D01*
G01X304667Y1729600D02*
Y1732100D01*
X305708D01*
X306042Y1731975D01*
X306250Y1731808D01*
X306333Y1731475D01*
X306250Y1731142D01*
X306000Y1730933D01*
X305708Y1730808D01*
X304667D01*
G01X305708D02*
X306333Y1729600D01*
G01X307892Y1729892D02*
X308183Y1729683D01*
X308517Y1729600D01*
X308850Y1729683D01*
X309142Y1729933D01*
X309350Y1730308D01*
X309433Y1730683D01*
Y1731142D01*
X309350Y1731517D01*
X309142Y1731850D01*
X308892Y1732017D01*
X308600Y1732100D01*
X308267Y1732017D01*
X308017Y1731850D01*
X307850Y1731600D01*
X307767Y1731267D01*
X307850Y1730975D01*
X308058Y1730683D01*
X308308Y1730517D01*
X308600Y1730475D01*
X308933Y1730558D01*
X309183Y1730767D01*
X309433Y1731142D01*
G01X310783Y1730100D02*
X311033Y1729808D01*
X311367Y1729642D01*
X311742Y1729600D01*
X312075Y1729642D01*
X312408Y1729850D01*
X312617Y1730100D01*
X312658Y1730350D01*
X312575Y1730642D01*
X312283Y1730850D01*
X311992Y1730933D01*
X311617D01*
G01X311992D02*
X312242Y1731058D01*
X312450Y1731267D01*
X312533Y1731517D01*
X312450Y1731767D01*
X312242Y1731975D01*
X311867Y1732100D01*
X311492Y1732058D01*
X311117Y1731892D01*
G01X315300Y1729600D02*
Y1732100D01*
X313758Y1730308D01*
X315842D01*
G01X317192Y1729892D02*
X317483Y1729683D01*
X317817Y1729600D01*
X318150Y1729683D01*
X318442Y1729933D01*
X318650Y1730308D01*
X318733Y1730683D01*
Y1731142D01*
X318650Y1731517D01*
X318442Y1731850D01*
X318192Y1732017D01*
X317900Y1732100D01*
X317567Y1732017D01*
X317317Y1731850D01*
X317150Y1731600D01*
X317067Y1731267D01*
X317150Y1730975D01*
X317358Y1730683D01*
X317608Y1730517D01*
X317900Y1730475D01*
X318233Y1730558D01*
X318483Y1730767D01*
X318733Y1731142D01*
G01X304667Y1749600D02*
Y1752100D01*
X305708D01*
X306042Y1751975D01*
X306250Y1751808D01*
X306333Y1751475D01*
X306250Y1751142D01*
X306000Y1750933D01*
X305708Y1750808D01*
X304667D01*
G01X305708D02*
X306333Y1749600D01*
G01X307892Y1749892D02*
X308183Y1749683D01*
X308517Y1749600D01*
X308850Y1749683D01*
X309142Y1749933D01*
X309350Y1750308D01*
X309433Y1750683D01*
Y1751142D01*
X309350Y1751517D01*
X309142Y1751850D01*
X308892Y1752017D01*
X308600Y1752100D01*
X308267Y1752017D01*
X308017Y1751850D01*
X307850Y1751600D01*
X307767Y1751267D01*
X307850Y1750975D01*
X308058Y1750683D01*
X308308Y1750517D01*
X308600Y1750475D01*
X308933Y1750558D01*
X309183Y1750767D01*
X309433Y1751142D01*
G01X310783Y1750100D02*
X311033Y1749808D01*
X311367Y1749642D01*
X311742Y1749600D01*
X312075Y1749642D01*
X312408Y1749850D01*
X312617Y1750100D01*
X312658Y1750350D01*
X312575Y1750642D01*
X312283Y1750850D01*
X311992Y1750933D01*
X311617D01*
G01X311992D02*
X312242Y1751058D01*
X312450Y1751267D01*
X312533Y1751517D01*
X312450Y1751767D01*
X312242Y1751975D01*
X311867Y1752100D01*
X311492Y1752058D01*
X311117Y1751892D01*
G01X313883Y1749975D02*
X314133Y1749767D01*
X314425Y1749642D01*
X314800Y1749600D01*
X315175Y1749683D01*
X315467Y1749850D01*
X315675Y1750142D01*
X315717Y1750475D01*
X315633Y1750808D01*
X315425Y1751017D01*
X315133Y1751183D01*
X314842Y1751225D01*
X314550Y1751183D01*
X314175Y1751017D01*
X314300Y1752100D01*
X315425D01*
G01X317900D02*
X317567Y1752017D01*
X317317Y1751808D01*
X317150Y1751558D01*
X317025Y1751225D01*
X316983Y1750850D01*
X317025Y1750475D01*
X317150Y1750142D01*
X317317Y1749892D01*
X317567Y1749683D01*
X317900Y1749600D01*
X318233Y1749683D01*
X318483Y1749892D01*
X318650Y1750142D01*
X318775Y1750475D01*
X318817Y1750850D01*
X318775Y1751225D01*
X318650Y1751558D01*
X318483Y1751808D01*
X318233Y1752017D01*
X317900Y1752100D01*
G01X322800Y1727000D02*
Y1723000D01*
X330200D01*
G01X265500Y1760483D02*
X267292D01*
X267667Y1760650D01*
X267917Y1760983D01*
X268000Y1761400D01*
X267917Y1761817D01*
X267667Y1762150D01*
X267292Y1762317D01*
X265500D01*
G01X267625Y1763583D02*
X267833Y1763833D01*
X267958Y1764125D01*
X268000Y1764500D01*
X267917Y1764875D01*
X267750Y1765167D01*
X267458Y1765375D01*
X267125Y1765417D01*
X266792Y1765333D01*
X266583Y1765125D01*
X266417Y1764833D01*
X266375Y1764542D01*
X266417Y1764250D01*
X266583Y1763875D01*
X265500Y1764000D01*
Y1765125D01*
G01Y1767600D02*
X265583Y1767267D01*
X265792Y1767017D01*
X266042Y1766850D01*
X266375Y1766725D01*
X266750Y1766683D01*
X267125Y1766725D01*
X267458Y1766850D01*
X267708Y1767017D01*
X267917Y1767267D01*
X268000Y1767600D01*
X267917Y1767933D01*
X267708Y1768183D01*
X267458Y1768350D01*
X267125Y1768475D01*
X266750Y1768517D01*
X266375Y1768475D01*
X266042Y1768350D01*
X265792Y1768183D01*
X265583Y1767933D01*
X265500Y1767600D01*
G01X292560Y1797837D02*
X290060D01*
Y1798878D01*
X290185Y1799212D01*
X290352Y1799420D01*
X290685Y1799503D01*
X291018Y1799420D01*
X291227Y1799170D01*
X291352Y1798878D01*
Y1797837D01*
G01Y1798878D02*
X292560Y1799503D01*
G01X292060Y1800853D02*
X292352Y1801103D01*
X292518Y1801437D01*
X292560Y1801812D01*
X292518Y1802145D01*
X292310Y1802478D01*
X292060Y1802687D01*
X291810Y1802728D01*
X291518Y1802645D01*
X291310Y1802353D01*
X291227Y1802062D01*
Y1801687D01*
G01Y1802062D02*
X291102Y1802312D01*
X290893Y1802520D01*
X290643Y1802603D01*
X290393Y1802520D01*
X290185Y1802312D01*
X290060Y1801937D01*
X290102Y1801562D01*
X290268Y1801187D01*
G01X292560Y1805370D02*
X290060D01*
X291852Y1803828D01*
Y1805912D01*
G01X292185Y1807053D02*
X292393Y1807303D01*
X292518Y1807595D01*
X292560Y1807970D01*
X292477Y1808345D01*
X292310Y1808637D01*
X292018Y1808845D01*
X291685Y1808887D01*
X291352Y1808803D01*
X291143Y1808595D01*
X290977Y1808303D01*
X290935Y1808012D01*
X290977Y1807720D01*
X291143Y1807345D01*
X290060Y1807470D01*
Y1808595D01*
G01X284560Y1797837D02*
X282060D01*
Y1798878D01*
X282185Y1799212D01*
X282352Y1799420D01*
X282685Y1799503D01*
X283018Y1799420D01*
X283227Y1799170D01*
X283352Y1798878D01*
Y1797837D01*
G01Y1798878D02*
X284560Y1799503D01*
G01X284060Y1800853D02*
X284352Y1801103D01*
X284518Y1801437D01*
X284560Y1801812D01*
X284518Y1802145D01*
X284310Y1802478D01*
X284060Y1802687D01*
X283810Y1802728D01*
X283518Y1802645D01*
X283310Y1802353D01*
X283227Y1802062D01*
Y1801687D01*
G01Y1802062D02*
X283102Y1802312D01*
X282893Y1802520D01*
X282643Y1802603D01*
X282393Y1802520D01*
X282185Y1802312D01*
X282060Y1801937D01*
X282102Y1801562D01*
X282268Y1801187D01*
G01X284560Y1805370D02*
X282060D01*
X283852Y1803828D01*
Y1805912D01*
G01X283518Y1807178D02*
X283227Y1807470D01*
X283060Y1807720D01*
X282977Y1808053D01*
X283060Y1808345D01*
X283227Y1808553D01*
X283477Y1808720D01*
X283768Y1808762D01*
X284018Y1808720D01*
X284268Y1808553D01*
X284477Y1808303D01*
X284560Y1808012D01*
X284477Y1807678D01*
X284227Y1807387D01*
X283852Y1807220D01*
X283435Y1807178D01*
X282893Y1807262D01*
X282602Y1807387D01*
X282310Y1807595D01*
X282102Y1807887D01*
X282060Y1808178D01*
X282143Y1808470D01*
X282352Y1808678D01*
G01X276560Y1797837D02*
X274060D01*
Y1798878D01*
X274185Y1799212D01*
X274352Y1799420D01*
X274685Y1799503D01*
X275018Y1799420D01*
X275227Y1799170D01*
X275352Y1798878D01*
Y1797837D01*
G01Y1798878D02*
X276560Y1799503D01*
G01X276060Y1800853D02*
X276352Y1801103D01*
X276518Y1801437D01*
X276560Y1801812D01*
X276518Y1802145D01*
X276310Y1802478D01*
X276060Y1802687D01*
X275810Y1802728D01*
X275518Y1802645D01*
X275310Y1802353D01*
X275227Y1802062D01*
Y1801687D01*
G01Y1802062D02*
X275102Y1802312D01*
X274893Y1802520D01*
X274643Y1802603D01*
X274393Y1802520D01*
X274185Y1802312D01*
X274060Y1801937D01*
X274102Y1801562D01*
X274268Y1801187D01*
G01X276560Y1805370D02*
X274060D01*
X275852Y1803828D01*
Y1805912D01*
G01X276560Y1807887D02*
X276018Y1807970D01*
X275560Y1808095D01*
X275143Y1808262D01*
X274685Y1808470D01*
X274060Y1808803D01*
Y1807137D01*
G01X288560Y1797837D02*
X286060D01*
Y1798878D01*
X286185Y1799212D01*
X286352Y1799420D01*
X286685Y1799503D01*
X287018Y1799420D01*
X287227Y1799170D01*
X287352Y1798878D01*
Y1797837D01*
G01Y1798878D02*
X288560Y1799503D01*
G01X288060Y1800853D02*
X288352Y1801103D01*
X288518Y1801437D01*
X288560Y1801812D01*
X288518Y1802145D01*
X288310Y1802478D01*
X288060Y1802687D01*
X287810Y1802728D01*
X287518Y1802645D01*
X287310Y1802353D01*
X287227Y1802062D01*
Y1801687D01*
G01Y1802062D02*
X287102Y1802312D01*
X286893Y1802520D01*
X286643Y1802603D01*
X286393Y1802520D01*
X286185Y1802312D01*
X286060Y1801937D01*
X286102Y1801562D01*
X286268Y1801187D01*
G01X288560Y1805370D02*
X286060D01*
X287852Y1803828D01*
Y1805912D01*
G01X288560Y1807970D02*
X288518Y1808262D01*
X288393Y1808595D01*
X288185Y1808803D01*
X287893Y1808887D01*
X287602Y1808803D01*
X287352Y1808553D01*
X287227Y1808178D01*
Y1807762D01*
X287143Y1807512D01*
X286935Y1807303D01*
X286643Y1807220D01*
X286352Y1807345D01*
X286143Y1807637D01*
X286060Y1807970D01*
X286143Y1808303D01*
X286352Y1808595D01*
X286643Y1808720D01*
X286935Y1808637D01*
X287143Y1808428D01*
X287227Y1808178D01*
Y1807762D01*
X287352Y1807387D01*
X287602Y1807137D01*
X287893Y1807053D01*
X288185Y1807137D01*
X288393Y1807345D01*
X288518Y1807678D01*
X288560Y1807970D01*
G01X280560Y1797837D02*
X278060D01*
Y1798878D01*
X278185Y1799212D01*
X278352Y1799420D01*
X278685Y1799503D01*
X279018Y1799420D01*
X279227Y1799170D01*
X279352Y1798878D01*
Y1797837D01*
G01Y1798878D02*
X280560Y1799503D01*
G01X280060Y1800853D02*
X280352Y1801103D01*
X280518Y1801437D01*
X280560Y1801812D01*
X280518Y1802145D01*
X280310Y1802478D01*
X280060Y1802687D01*
X279810Y1802728D01*
X279518Y1802645D01*
X279310Y1802353D01*
X279227Y1802062D01*
Y1801687D01*
G01Y1802062D02*
X279102Y1802312D01*
X278893Y1802520D01*
X278643Y1802603D01*
X278393Y1802520D01*
X278185Y1802312D01*
X278060Y1801937D01*
X278102Y1801562D01*
X278268Y1801187D01*
G01X280560Y1805370D02*
X278060D01*
X279852Y1803828D01*
Y1805912D01*
G01X280268Y1807262D02*
X280477Y1807553D01*
X280560Y1807887D01*
X280477Y1808220D01*
X280227Y1808512D01*
X279852Y1808720D01*
X279477Y1808803D01*
X279018D01*
X278643Y1808720D01*
X278310Y1808512D01*
X278143Y1808262D01*
X278060Y1807970D01*
X278143Y1807637D01*
X278310Y1807387D01*
X278560Y1807220D01*
X278893Y1807137D01*
X279185Y1807220D01*
X279477Y1807428D01*
X279643Y1807678D01*
X279685Y1807970D01*
X279602Y1808303D01*
X279393Y1808553D01*
X279018Y1808803D01*
G01X272560Y1797837D02*
X270060D01*
Y1798878D01*
X270185Y1799212D01*
X270352Y1799420D01*
X270685Y1799503D01*
X271018Y1799420D01*
X271227Y1799170D01*
X271352Y1798878D01*
Y1797837D01*
G01Y1798878D02*
X272560Y1799503D01*
G01X272060Y1800853D02*
X272352Y1801103D01*
X272518Y1801437D01*
X272560Y1801812D01*
X272518Y1802145D01*
X272310Y1802478D01*
X272060Y1802687D01*
X271810Y1802728D01*
X271518Y1802645D01*
X271310Y1802353D01*
X271227Y1802062D01*
Y1801687D01*
G01Y1802062D02*
X271102Y1802312D01*
X270893Y1802520D01*
X270643Y1802603D01*
X270393Y1802520D01*
X270185Y1802312D01*
X270060Y1801937D01*
X270102Y1801562D01*
X270268Y1801187D01*
G01X272185Y1803953D02*
X272393Y1804203D01*
X272518Y1804495D01*
X272560Y1804870D01*
X272477Y1805245D01*
X272310Y1805537D01*
X272018Y1805745D01*
X271685Y1805787D01*
X271352Y1805703D01*
X271143Y1805495D01*
X270977Y1805203D01*
X270935Y1804912D01*
X270977Y1804620D01*
X271143Y1804245D01*
X270060Y1804370D01*
Y1805495D01*
G01Y1807970D02*
X270143Y1807637D01*
X270352Y1807387D01*
X270602Y1807220D01*
X270935Y1807095D01*
X271310Y1807053D01*
X271685Y1807095D01*
X272018Y1807220D01*
X272268Y1807387D01*
X272477Y1807637D01*
X272560Y1807970D01*
X272477Y1808303D01*
X272268Y1808553D01*
X272018Y1808720D01*
X271685Y1808845D01*
X271310Y1808887D01*
X270935Y1808845D01*
X270602Y1808720D01*
X270352Y1808553D01*
X270143Y1808303D01*
X270060Y1807970D01*
G01X272975Y1925967D02*
Y1928467D01*
G01X274725D02*
Y1925967D01*
G01Y1927217D02*
X272975D01*
G01X276158Y1928050D02*
X276408Y1928300D01*
X276700Y1928425D01*
X277033Y1928467D01*
X277450Y1928384D01*
X277742Y1928175D01*
X277825Y1927925D01*
X277783Y1927675D01*
X277617Y1927467D01*
X276783Y1927050D01*
X276408Y1926759D01*
X276158Y1926342D01*
X276075Y1925967D01*
X277825D01*
G01X358000Y45017D02*
X355500D01*
Y46058D01*
X355625Y46392D01*
X355792Y46600D01*
X356125Y46683D01*
X356458Y46600D01*
X356667Y46350D01*
X356792Y46058D01*
Y45017D01*
G01Y46058D02*
X358000Y46683D01*
G01X357500Y48033D02*
X357792Y48283D01*
X357958Y48617D01*
X358000Y48992D01*
X357958Y49325D01*
X357750Y49658D01*
X357500Y49867D01*
X357250Y49908D01*
X356958Y49825D01*
X356750Y49533D01*
X356667Y49242D01*
Y48867D01*
G01Y49242D02*
X356542Y49492D01*
X356333Y49700D01*
X356083Y49783D01*
X355833Y49700D01*
X355625Y49492D01*
X355500Y49117D01*
X355542Y48742D01*
X355708Y48367D01*
G01X356958Y51258D02*
X356667Y51550D01*
X356500Y51800D01*
X356417Y52133D01*
X356500Y52425D01*
X356667Y52633D01*
X356917Y52800D01*
X357208Y52842D01*
X357458Y52800D01*
X357708Y52633D01*
X357917Y52383D01*
X358000Y52092D01*
X357917Y51758D01*
X357667Y51467D01*
X357292Y51300D01*
X356875Y51258D01*
X356333Y51342D01*
X356042Y51467D01*
X355750Y51675D01*
X355542Y51967D01*
X355500Y52258D01*
X355583Y52550D01*
X355792Y52758D01*
G01X355917Y54358D02*
X355667Y54608D01*
X355542Y54900D01*
X355500Y55233D01*
X355583Y55650D01*
X355792Y55942D01*
X356042Y56025D01*
X356292Y55983D01*
X356500Y55817D01*
X356917Y54983D01*
X357208Y54608D01*
X357625Y54358D01*
X358000Y54275D01*
Y56025D01*
G01X366467Y121593D02*
X366217Y121718D01*
X365925Y121801D01*
X365592D01*
X365217Y121676D01*
X364925Y121468D01*
X364717Y121218D01*
X364550Y120801D01*
X364508Y120426D01*
X364592Y120051D01*
X364717Y119801D01*
X364967Y119551D01*
X365258Y119384D01*
X365550Y119301D01*
X365842D01*
X366133Y119384D01*
X366383Y119509D01*
X366592Y119676D01*
G01X367733Y119801D02*
X367983Y119509D01*
X368317Y119343D01*
X368692Y119301D01*
X369025Y119343D01*
X369358Y119551D01*
X369567Y119801D01*
X369608Y120051D01*
X369525Y120343D01*
X369233Y120551D01*
X368942Y120634D01*
X368567D01*
G01X368942D02*
X369192Y120759D01*
X369400Y120968D01*
X369483Y121218D01*
X369400Y121468D01*
X369192Y121676D01*
X368817Y121801D01*
X368442Y121759D01*
X368067Y121593D01*
G01X370833Y119676D02*
X371083Y119468D01*
X371375Y119343D01*
X371750Y119301D01*
X372125Y119384D01*
X372417Y119551D01*
X372625Y119843D01*
X372667Y120176D01*
X372583Y120509D01*
X372375Y120718D01*
X372083Y120884D01*
X371792Y120926D01*
X371500Y120884D01*
X371125Y120718D01*
X371250Y121801D01*
X372375D01*
G01X374058Y121384D02*
X374308Y121634D01*
X374600Y121759D01*
X374933Y121801D01*
X375350Y121718D01*
X375642Y121509D01*
X375725Y121259D01*
X375683Y121009D01*
X375517Y120801D01*
X374683Y120384D01*
X374308Y120093D01*
X374058Y119676D01*
X373975Y119301D01*
X375725D01*
G01X366477Y117012D02*
X366227Y117137D01*
X365935Y117220D01*
X365602D01*
X365227Y117095D01*
X364935Y116887D01*
X364727Y116637D01*
X364560Y116220D01*
X364518Y115845D01*
X364602Y115470D01*
X364727Y115220D01*
X364977Y114970D01*
X365268Y114803D01*
X365560Y114720D01*
X365852D01*
X366143Y114803D01*
X366393Y114928D01*
X366602Y115095D01*
G01X367743Y115220D02*
X367993Y114928D01*
X368327Y114762D01*
X368702Y114720D01*
X369035Y114762D01*
X369368Y114970D01*
X369577Y115220D01*
X369618Y115470D01*
X369535Y115762D01*
X369243Y115970D01*
X368952Y116053D01*
X368577D01*
G01X368952D02*
X369202Y116178D01*
X369410Y116387D01*
X369493Y116637D01*
X369410Y116887D01*
X369202Y117095D01*
X368827Y117220D01*
X368452Y117178D01*
X368077Y117012D01*
G01X370968Y115762D02*
X371260Y116053D01*
X371510Y116220D01*
X371843Y116303D01*
X372135Y116220D01*
X372343Y116053D01*
X372510Y115803D01*
X372552Y115512D01*
X372510Y115262D01*
X372343Y115012D01*
X372093Y114803D01*
X371802Y114720D01*
X371468Y114803D01*
X371177Y115053D01*
X371010Y115428D01*
X370968Y115845D01*
X371052Y116387D01*
X371177Y116678D01*
X371385Y116970D01*
X371677Y117178D01*
X371968Y117220D01*
X372260Y117137D01*
X372468Y116928D01*
G01X373943Y115220D02*
X374193Y114928D01*
X374527Y114762D01*
X374902Y114720D01*
X375235Y114762D01*
X375568Y114970D01*
X375777Y115220D01*
X375818Y115470D01*
X375735Y115762D01*
X375443Y115970D01*
X375152Y116053D01*
X374777D01*
G01X375152D02*
X375402Y116178D01*
X375610Y116387D01*
X375693Y116637D01*
X375610Y116887D01*
X375402Y117095D01*
X375027Y117220D01*
X374652Y117178D01*
X374277Y117012D01*
G01X374767Y77292D02*
X374517Y77417D01*
X374225Y77500D01*
X373892D01*
X373517Y77375D01*
X373225Y77167D01*
X373017Y76917D01*
X372850Y76500D01*
X372808Y76125D01*
X372892Y75750D01*
X373017Y75500D01*
X373267Y75250D01*
X373558Y75083D01*
X373850Y75000D01*
X374142D01*
X374433Y75083D01*
X374683Y75208D01*
X374892Y75375D01*
G01X376033Y75500D02*
X376283Y75208D01*
X376617Y75042D01*
X376992Y75000D01*
X377325Y75042D01*
X377658Y75250D01*
X377867Y75500D01*
X377908Y75750D01*
X377825Y76042D01*
X377533Y76250D01*
X377242Y76333D01*
X376867D01*
G01X377242D02*
X377492Y76458D01*
X377700Y76667D01*
X377783Y76917D01*
X377700Y77167D01*
X377492Y77375D01*
X377117Y77500D01*
X376742Y77458D01*
X376367Y77292D01*
G01X379133Y75375D02*
X379383Y75167D01*
X379675Y75042D01*
X380050Y75000D01*
X380425Y75083D01*
X380717Y75250D01*
X380925Y75542D01*
X380967Y75875D01*
X380883Y76208D01*
X380675Y76417D01*
X380383Y76583D01*
X380092Y76625D01*
X379800Y76583D01*
X379425Y76417D01*
X379550Y77500D01*
X380675D01*
G01X383067Y75000D02*
X383150Y75542D01*
X383275Y76000D01*
X383442Y76417D01*
X383650Y76875D01*
X383983Y77500D01*
X382317D01*
G01X386008Y99267D02*
X385883Y99017D01*
X385800Y98725D01*
Y98392D01*
X385925Y98017D01*
X386133Y97725D01*
X386383Y97517D01*
X386800Y97350D01*
X387175Y97308D01*
X387550Y97392D01*
X387800Y97517D01*
X388050Y97767D01*
X388217Y98058D01*
X388300Y98350D01*
Y98642D01*
X388217Y98933D01*
X388092Y99183D01*
X387925Y99392D01*
G01X387800Y100533D02*
X388092Y100783D01*
X388258Y101117D01*
X388300Y101492D01*
X388258Y101825D01*
X388050Y102158D01*
X387800Y102367D01*
X387550Y102408D01*
X387258Y102325D01*
X387050Y102033D01*
X386967Y101742D01*
Y101367D01*
G01Y101742D02*
X386842Y101992D01*
X386633Y102200D01*
X386383Y102283D01*
X386133Y102200D01*
X385925Y101992D01*
X385800Y101617D01*
X385842Y101242D01*
X386008Y100867D01*
G01X387925Y103633D02*
X388133Y103883D01*
X388258Y104175D01*
X388300Y104550D01*
X388217Y104925D01*
X388050Y105217D01*
X387758Y105425D01*
X387425Y105467D01*
X387092Y105383D01*
X386883Y105175D01*
X386717Y104883D01*
X386675Y104592D01*
X386717Y104300D01*
X386883Y103925D01*
X385800Y104050D01*
Y105175D01*
G01X388300Y107650D02*
X388258Y107942D01*
X388133Y108275D01*
X387925Y108483D01*
X387633Y108567D01*
X387342Y108483D01*
X387092Y108233D01*
X386967Y107858D01*
Y107442D01*
X386883Y107192D01*
X386675Y106983D01*
X386383Y106900D01*
X386092Y107025D01*
X385883Y107317D01*
X385800Y107650D01*
X385883Y107983D01*
X386092Y108275D01*
X386383Y108400D01*
X386675Y108317D01*
X386883Y108108D01*
X386967Y107858D01*
Y107442D01*
X387092Y107067D01*
X387342Y106817D01*
X387633Y106733D01*
X387925Y106817D01*
X388133Y107025D01*
X388258Y107358D01*
X388300Y107650D01*
G01X386008Y83167D02*
X385883Y82917D01*
X385800Y82625D01*
Y82292D01*
X385925Y81917D01*
X386133Y81625D01*
X386383Y81417D01*
X386800Y81250D01*
X387175Y81208D01*
X387550Y81292D01*
X387800Y81417D01*
X388050Y81667D01*
X388217Y81958D01*
X388300Y82250D01*
Y82542D01*
X388217Y82833D01*
X388092Y83083D01*
X387925Y83292D01*
G01X387800Y84433D02*
X388092Y84683D01*
X388258Y85017D01*
X388300Y85392D01*
X388258Y85725D01*
X388050Y86058D01*
X387800Y86267D01*
X387550Y86308D01*
X387258Y86225D01*
X387050Y85933D01*
X386967Y85642D01*
Y85267D01*
G01Y85642D02*
X386842Y85892D01*
X386633Y86100D01*
X386383Y86183D01*
X386133Y86100D01*
X385925Y85892D01*
X385800Y85517D01*
X385842Y85142D01*
X386008Y84767D01*
G01X387925Y87533D02*
X388133Y87783D01*
X388258Y88075D01*
X388300Y88450D01*
X388217Y88825D01*
X388050Y89117D01*
X387758Y89325D01*
X387425Y89367D01*
X387092Y89283D01*
X386883Y89075D01*
X386717Y88783D01*
X386675Y88492D01*
X386717Y88200D01*
X386883Y87825D01*
X385800Y87950D01*
Y89075D01*
G01X388008Y90842D02*
X388217Y91133D01*
X388300Y91467D01*
X388217Y91800D01*
X387967Y92092D01*
X387592Y92300D01*
X387217Y92383D01*
X386758D01*
X386383Y92300D01*
X386050Y92092D01*
X385883Y91842D01*
X385800Y91550D01*
X385883Y91217D01*
X386050Y90967D01*
X386300Y90800D01*
X386633Y90717D01*
X386925Y90800D01*
X387217Y91008D01*
X387383Y91258D01*
X387425Y91550D01*
X387342Y91883D01*
X387133Y92133D01*
X386758Y92383D01*
G01X356000Y65300D02*
X360000D01*
Y72700D01*
G01X337909Y66857D02*
X335409D01*
Y67898D01*
X335534Y68232D01*
X335701Y68440D01*
X336034Y68523D01*
X336367Y68440D01*
X336576Y68190D01*
X336701Y67898D01*
Y66857D01*
G01Y67898D02*
X337909Y68523D01*
G01X337409Y69873D02*
X337701Y70123D01*
X337867Y70457D01*
X337909Y70832D01*
X337867Y71165D01*
X337659Y71498D01*
X337409Y71707D01*
X337159Y71748D01*
X336867Y71665D01*
X336659Y71373D01*
X336576Y71082D01*
Y70707D01*
G01Y71082D02*
X336451Y71332D01*
X336242Y71540D01*
X335992Y71623D01*
X335742Y71540D01*
X335534Y71332D01*
X335409Y70957D01*
X335451Y70582D01*
X335617Y70207D01*
G01X336867Y73098D02*
X336576Y73390D01*
X336409Y73640D01*
X336326Y73973D01*
X336409Y74265D01*
X336576Y74473D01*
X336826Y74640D01*
X337117Y74682D01*
X337367Y74640D01*
X337617Y74473D01*
X337826Y74223D01*
X337909Y73932D01*
X337826Y73598D01*
X337576Y73307D01*
X337201Y73140D01*
X336784Y73098D01*
X336242Y73182D01*
X335951Y73307D01*
X335659Y73515D01*
X335451Y73807D01*
X335409Y74098D01*
X335492Y74390D01*
X335701Y74598D01*
G01X337909Y77490D02*
X335409D01*
X337201Y75948D01*
Y78032D01*
G01X346500Y69800D02*
X350500D01*
Y77200D01*
G01X341909Y66857D02*
X339409D01*
Y67898D01*
X339534Y68232D01*
X339701Y68440D01*
X340034Y68523D01*
X340367Y68440D01*
X340576Y68190D01*
X340701Y67898D01*
Y66857D01*
G01Y67898D02*
X341909Y68523D01*
G01X341409Y69873D02*
X341701Y70123D01*
X341867Y70457D01*
X341909Y70832D01*
X341867Y71165D01*
X341659Y71498D01*
X341409Y71707D01*
X341159Y71748D01*
X340867Y71665D01*
X340659Y71373D01*
X340576Y71082D01*
Y70707D01*
G01Y71082D02*
X340451Y71332D01*
X340242Y71540D01*
X339992Y71623D01*
X339742Y71540D01*
X339534Y71332D01*
X339409Y70957D01*
X339451Y70582D01*
X339617Y70207D01*
G01X341909Y73890D02*
X341867Y74182D01*
X341742Y74515D01*
X341534Y74723D01*
X341242Y74807D01*
X340951Y74723D01*
X340701Y74473D01*
X340576Y74098D01*
Y73682D01*
X340492Y73432D01*
X340284Y73223D01*
X339992Y73140D01*
X339701Y73265D01*
X339492Y73557D01*
X339409Y73890D01*
X339492Y74223D01*
X339701Y74515D01*
X339992Y74640D01*
X340284Y74557D01*
X340492Y74348D01*
X340576Y74098D01*
Y73682D01*
X340701Y73307D01*
X340951Y73057D01*
X341242Y72973D01*
X341534Y73057D01*
X341742Y73265D01*
X341867Y73598D01*
X341909Y73890D01*
G01Y76990D02*
X339409D01*
X339909Y76490D01*
G01X341909D02*
Y77490D01*
G01X354500Y77200D02*
X350500D01*
Y69800D01*
G01X372697Y56210D02*
Y58710D01*
X373738D01*
X374072Y58585D01*
X374280Y58418D01*
X374363Y58085D01*
X374280Y57752D01*
X374030Y57543D01*
X373738Y57418D01*
X372697D01*
G01X373738D02*
X374363Y56210D01*
G01X375713Y56710D02*
X375963Y56418D01*
X376297Y56252D01*
X376672Y56210D01*
X377005Y56252D01*
X377338Y56460D01*
X377547Y56710D01*
X377588Y56960D01*
X377505Y57252D01*
X377213Y57460D01*
X376922Y57543D01*
X376547D01*
G01X376922D02*
X377172Y57668D01*
X377380Y57877D01*
X377463Y58127D01*
X377380Y58377D01*
X377172Y58585D01*
X376797Y58710D01*
X376422Y58668D01*
X376047Y58502D01*
G01X379730Y56210D02*
X380022Y56252D01*
X380355Y56377D01*
X380563Y56585D01*
X380647Y56877D01*
X380563Y57168D01*
X380313Y57418D01*
X379938Y57543D01*
X379522D01*
X379272Y57627D01*
X379063Y57835D01*
X378980Y58127D01*
X379105Y58418D01*
X379397Y58627D01*
X379730Y58710D01*
X380063Y58627D01*
X380355Y58418D01*
X380480Y58127D01*
X380397Y57835D01*
X380188Y57627D01*
X379938Y57543D01*
X379522D01*
X379147Y57418D01*
X378897Y57168D01*
X378813Y56877D01*
X378897Y56585D01*
X379105Y56377D01*
X379438Y56252D01*
X379730Y56210D01*
G01X382747D02*
X382830Y56752D01*
X382955Y57210D01*
X383122Y57627D01*
X383330Y58085D01*
X383663Y58710D01*
X381997D01*
G01X361800Y60000D02*
Y56000D01*
X369200D01*
G01X371917Y66881D02*
Y69381D01*
X372958D01*
X373292Y69256D01*
X373500Y69089D01*
X373583Y68756D01*
X373500Y68423D01*
X373250Y68214D01*
X372958Y68089D01*
X371917D01*
G01X372958D02*
X373583Y66881D01*
G01X374933Y67381D02*
X375183Y67089D01*
X375517Y66923D01*
X375892Y66881D01*
X376225Y66923D01*
X376558Y67131D01*
X376767Y67381D01*
X376808Y67631D01*
X376725Y67923D01*
X376433Y68131D01*
X376142Y68214D01*
X375767D01*
G01X376142D02*
X376392Y68339D01*
X376600Y68548D01*
X376683Y68798D01*
X376600Y69048D01*
X376392Y69256D01*
X376017Y69381D01*
X375642Y69339D01*
X375267Y69173D01*
G01X378950Y66881D02*
X379242Y66923D01*
X379575Y67048D01*
X379783Y67256D01*
X379867Y67548D01*
X379783Y67839D01*
X379533Y68089D01*
X379158Y68214D01*
X378742D01*
X378492Y68298D01*
X378283Y68506D01*
X378200Y68798D01*
X378325Y69089D01*
X378617Y69298D01*
X378950Y69381D01*
X379283Y69298D01*
X379575Y69089D01*
X379700Y68798D01*
X379617Y68506D01*
X379408Y68298D01*
X379158Y68214D01*
X378742D01*
X378367Y68089D01*
X378117Y67839D01*
X378033Y67548D01*
X378117Y67256D01*
X378325Y67048D01*
X378658Y66923D01*
X378950Y66881D01*
G01X381342Y67173D02*
X381633Y66964D01*
X381967Y66881D01*
X382300Y66964D01*
X382592Y67214D01*
X382800Y67589D01*
X382883Y67964D01*
Y68423D01*
X382800Y68798D01*
X382592Y69131D01*
X382342Y69298D01*
X382050Y69381D01*
X381717Y69298D01*
X381467Y69131D01*
X381300Y68881D01*
X381217Y68548D01*
X381300Y68256D01*
X381508Y67964D01*
X381758Y67798D01*
X382050Y67756D01*
X382383Y67839D01*
X382633Y68048D01*
X382883Y68423D01*
G01X369200Y66500D02*
Y70500D01*
X361800D01*
G01X396300Y81417D02*
X393800D01*
Y82458D01*
X393925Y82792D01*
X394092Y83000D01*
X394425Y83083D01*
X394758Y83000D01*
X394967Y82750D01*
X395092Y82458D01*
Y81417D01*
G01Y82458D02*
X396300Y83083D01*
G01X395800Y84433D02*
X396092Y84683D01*
X396258Y85017D01*
X396300Y85392D01*
X396258Y85725D01*
X396050Y86058D01*
X395800Y86267D01*
X395550Y86308D01*
X395258Y86225D01*
X395050Y85933D01*
X394967Y85642D01*
Y85267D01*
G01Y85642D02*
X394842Y85892D01*
X394633Y86100D01*
X394383Y86183D01*
X394133Y86100D01*
X393925Y85892D01*
X393800Y85517D01*
X393842Y85142D01*
X394008Y84767D01*
G01X396300Y88450D02*
X396258Y88742D01*
X396133Y89075D01*
X395925Y89283D01*
X395633Y89367D01*
X395342Y89283D01*
X395092Y89033D01*
X394967Y88658D01*
Y88242D01*
X394883Y87992D01*
X394675Y87783D01*
X394383Y87700D01*
X394092Y87825D01*
X393883Y88117D01*
X393800Y88450D01*
X393883Y88783D01*
X394092Y89075D01*
X394383Y89200D01*
X394675Y89117D01*
X394883Y88908D01*
X394967Y88658D01*
Y88242D01*
X395092Y87867D01*
X395342Y87617D01*
X395633Y87533D01*
X395925Y87617D01*
X396133Y87825D01*
X396258Y88158D01*
X396300Y88450D01*
G01Y91550D02*
X396258Y91842D01*
X396133Y92175D01*
X395925Y92383D01*
X395633Y92467D01*
X395342Y92383D01*
X395092Y92133D01*
X394967Y91758D01*
Y91342D01*
X394883Y91092D01*
X394675Y90883D01*
X394383Y90800D01*
X394092Y90925D01*
X393883Y91217D01*
X393800Y91550D01*
X393883Y91883D01*
X394092Y92175D01*
X394383Y92300D01*
X394675Y92217D01*
X394883Y92008D01*
X394967Y91758D01*
Y91342D01*
X395092Y90967D01*
X395342Y90717D01*
X395633Y90633D01*
X395925Y90717D01*
X396133Y90925D01*
X396258Y91258D01*
X396300Y91550D01*
G01X380200Y82700D02*
X384200D01*
Y90100D01*
G01X392300Y81417D02*
X389800D01*
Y82458D01*
X389925Y82792D01*
X390092Y83000D01*
X390425Y83083D01*
X390758Y83000D01*
X390967Y82750D01*
X391092Y82458D01*
Y81417D01*
G01Y82458D02*
X392300Y83083D01*
G01X391800Y84433D02*
X392092Y84683D01*
X392258Y85017D01*
X392300Y85392D01*
X392258Y85725D01*
X392050Y86058D01*
X391800Y86267D01*
X391550Y86308D01*
X391258Y86225D01*
X391050Y85933D01*
X390967Y85642D01*
Y85267D01*
G01Y85642D02*
X390842Y85892D01*
X390633Y86100D01*
X390383Y86183D01*
X390133Y86100D01*
X389925Y85892D01*
X389800Y85517D01*
X389842Y85142D01*
X390008Y84767D01*
G01X392008Y87742D02*
X392217Y88033D01*
X392300Y88367D01*
X392217Y88700D01*
X391967Y88992D01*
X391592Y89200D01*
X391217Y89283D01*
X390758D01*
X390383Y89200D01*
X390050Y88992D01*
X389883Y88742D01*
X389800Y88450D01*
X389883Y88117D01*
X390050Y87867D01*
X390300Y87700D01*
X390633Y87617D01*
X390925Y87700D01*
X391217Y87908D01*
X391383Y88158D01*
X391425Y88450D01*
X391342Y88783D01*
X391133Y89033D01*
X390758Y89283D01*
G01X389800Y91550D02*
X389883Y91217D01*
X390092Y90967D01*
X390342Y90800D01*
X390675Y90675D01*
X391050Y90633D01*
X391425Y90675D01*
X391758Y90800D01*
X392008Y90967D01*
X392217Y91217D01*
X392300Y91550D01*
X392217Y91883D01*
X392008Y92133D01*
X391758Y92300D01*
X391425Y92425D01*
X391050Y92467D01*
X390675Y92425D01*
X390342Y92300D01*
X390092Y92133D01*
X389883Y91883D01*
X389800Y91550D01*
G01X380100Y90100D02*
X376100D01*
Y82700D01*
G01X397300Y97467D02*
X394800D01*
Y98508D01*
X394925Y98842D01*
X395092Y99050D01*
X395425Y99133D01*
X395758Y99050D01*
X395967Y98800D01*
X396092Y98508D01*
Y97467D01*
G01Y98508D02*
X397300Y99133D01*
G01X397008Y100692D02*
X397217Y100983D01*
X397300Y101317D01*
X397217Y101650D01*
X396967Y101942D01*
X396592Y102150D01*
X396217Y102233D01*
X395758D01*
X395383Y102150D01*
X395050Y101942D01*
X394883Y101692D01*
X394800Y101400D01*
X394883Y101067D01*
X395050Y100817D01*
X395300Y100650D01*
X395633Y100567D01*
X395925Y100650D01*
X396217Y100858D01*
X396383Y101108D01*
X396425Y101400D01*
X396342Y101733D01*
X396133Y101983D01*
X395758Y102233D01*
G01X397300Y104417D02*
X396758Y104500D01*
X396300Y104625D01*
X395883Y104792D01*
X395425Y105000D01*
X394800Y105333D01*
Y103667D01*
G01X396925Y106683D02*
X397133Y106933D01*
X397258Y107225D01*
X397300Y107600D01*
X397217Y107975D01*
X397050Y108267D01*
X396758Y108475D01*
X396425Y108517D01*
X396092Y108433D01*
X395883Y108225D01*
X395717Y107933D01*
X395675Y107642D01*
X395717Y107350D01*
X395883Y106975D01*
X394800Y107100D01*
Y108225D01*
G01X397300Y110617D02*
X396758Y110700D01*
X396300Y110825D01*
X395883Y110992D01*
X395425Y111200D01*
X394800Y111533D01*
Y109867D01*
G01X380000Y99300D02*
X384000D01*
Y106700D01*
G01X392800Y97467D02*
X390300D01*
Y98508D01*
X390425Y98842D01*
X390592Y99050D01*
X390925Y99133D01*
X391258Y99050D01*
X391467Y98800D01*
X391592Y98508D01*
Y97467D01*
G01Y98508D02*
X392800Y99133D01*
G01X392508Y100692D02*
X392717Y100983D01*
X392800Y101317D01*
X392717Y101650D01*
X392467Y101942D01*
X392092Y102150D01*
X391717Y102233D01*
X391258D01*
X390883Y102150D01*
X390550Y101942D01*
X390383Y101692D01*
X390300Y101400D01*
X390383Y101067D01*
X390550Y100817D01*
X390800Y100650D01*
X391133Y100567D01*
X391425Y100650D01*
X391717Y100858D01*
X391883Y101108D01*
X391925Y101400D01*
X391842Y101733D01*
X391633Y101983D01*
X391258Y102233D01*
G01X392800Y104417D02*
X392258Y104500D01*
X391800Y104625D01*
X391383Y104792D01*
X390925Y105000D01*
X390300Y105333D01*
Y103667D01*
G01X392425Y106683D02*
X392633Y106933D01*
X392758Y107225D01*
X392800Y107600D01*
X392717Y107975D01*
X392550Y108267D01*
X392258Y108475D01*
X391925Y108517D01*
X391592Y108433D01*
X391383Y108225D01*
X391217Y107933D01*
X391175Y107642D01*
X391217Y107350D01*
X391383Y106975D01*
X390300Y107100D01*
Y108225D01*
G01X392800Y110700D02*
X392758Y110992D01*
X392633Y111325D01*
X392425Y111533D01*
X392133Y111617D01*
X391842Y111533D01*
X391592Y111283D01*
X391467Y110908D01*
Y110492D01*
X391383Y110242D01*
X391175Y110033D01*
X390883Y109950D01*
X390592Y110075D01*
X390383Y110367D01*
X390300Y110700D01*
X390383Y111033D01*
X390592Y111325D01*
X390883Y111450D01*
X391175Y111367D01*
X391383Y111158D01*
X391467Y110908D01*
Y110492D01*
X391592Y110117D01*
X391842Y109867D01*
X392133Y109783D01*
X392425Y109867D01*
X392633Y110075D01*
X392758Y110408D01*
X392800Y110700D01*
G01X379500Y106700D02*
X375500D01*
Y99300D01*
G01X345800Y61000D02*
Y58500D01*
G01X344842Y61000D02*
X346758D01*
G01X348067Y58500D02*
Y61000D01*
X349067D01*
X349400Y60875D01*
X349650Y60583D01*
X349733Y60250D01*
X349650Y59917D01*
X349442Y59667D01*
X349067Y59542D01*
X348067D01*
G01X352000Y58500D02*
Y61000D01*
X351500Y60500D01*
G01Y58500D02*
X352500D01*
G01X354183Y58875D02*
X354433Y58667D01*
X354725Y58542D01*
X355100Y58500D01*
X355475Y58583D01*
X355767Y58750D01*
X355975Y59042D01*
X356017Y59375D01*
X355933Y59708D01*
X355725Y59917D01*
X355433Y60083D01*
X355142Y60125D01*
X354850Y60083D01*
X354475Y59917D01*
X354600Y61000D01*
X355725D01*
G01X358200D02*
X357867Y60917D01*
X357617Y60708D01*
X357450Y60458D01*
X357325Y60125D01*
X357283Y59750D01*
X357325Y59375D01*
X357450Y59042D01*
X357617Y58792D01*
X357867Y58583D01*
X358200Y58500D01*
X358533Y58583D01*
X358783Y58792D01*
X358950Y59042D01*
X359075Y59375D01*
X359117Y59750D01*
X359075Y60125D01*
X358950Y60458D01*
X358783Y60708D01*
X358533Y60917D01*
X358200Y61000D01*
G01X346000Y92483D02*
X347792D01*
X348167Y92650D01*
X348417Y92983D01*
X348500Y93400D01*
X348417Y93817D01*
X348167Y94150D01*
X347792Y94317D01*
X346000D01*
G01X348125Y95583D02*
X348333Y95833D01*
X348458Y96125D01*
X348500Y96500D01*
X348417Y96875D01*
X348250Y97167D01*
X347958Y97375D01*
X347625Y97417D01*
X347292Y97333D01*
X347083Y97125D01*
X346917Y96833D01*
X346875Y96542D01*
X346917Y96250D01*
X347083Y95875D01*
X346000Y96000D01*
Y97125D01*
G01X348000Y98683D02*
X348292Y98933D01*
X348458Y99267D01*
X348500Y99642D01*
X348458Y99975D01*
X348250Y100308D01*
X348000Y100517D01*
X347750Y100558D01*
X347458Y100475D01*
X347250Y100183D01*
X347167Y99892D01*
Y99517D01*
G01Y99892D02*
X347042Y100142D01*
X346833Y100350D01*
X346583Y100433D01*
X346333Y100350D01*
X346125Y100142D01*
X346000Y99767D01*
X346042Y99392D01*
X346208Y99017D01*
G01X350600Y92500D02*
Y100500D01*
X363000D01*
Y92500D01*
X350600D01*
G01X352300Y96500D02*
X350800Y98000D01*
G01X352300Y96500D02*
X350800Y95000D01*
G01X337729Y122807D02*
X335229D01*
Y123848D01*
X335354Y124182D01*
X335521Y124390D01*
X335854Y124473D01*
X336187Y124390D01*
X336396Y124140D01*
X336521Y123848D01*
Y122807D01*
G01Y123848D02*
X337729Y124473D01*
G01X337229Y125823D02*
X337521Y126073D01*
X337687Y126407D01*
X337729Y126782D01*
X337687Y127115D01*
X337479Y127448D01*
X337229Y127657D01*
X336979Y127698D01*
X336687Y127615D01*
X336479Y127323D01*
X336396Y127032D01*
Y126657D01*
G01Y127032D02*
X336271Y127282D01*
X336062Y127490D01*
X335812Y127573D01*
X335562Y127490D01*
X335354Y127282D01*
X335229Y126907D01*
X335271Y126532D01*
X335437Y126157D01*
G01X337729Y129757D02*
X337187Y129840D01*
X336729Y129965D01*
X336312Y130132D01*
X335854Y130340D01*
X335229Y130673D01*
Y129007D01*
G01X337437Y132232D02*
X337646Y132523D01*
X337729Y132857D01*
X337646Y133190D01*
X337396Y133482D01*
X337021Y133690D01*
X336646Y133773D01*
X336187D01*
X335812Y133690D01*
X335479Y133482D01*
X335312Y133232D01*
X335229Y132940D01*
X335312Y132607D01*
X335479Y132357D01*
X335729Y132190D01*
X336062Y132107D01*
X336354Y132190D01*
X336646Y132398D01*
X336812Y132648D01*
X336854Y132940D01*
X336771Y133273D01*
X336562Y133523D01*
X336187Y133773D01*
G01X346500Y121800D02*
X350500D01*
Y129200D01*
G01X342550Y122687D02*
X340050D01*
Y123728D01*
X340175Y124062D01*
X340342Y124270D01*
X340675Y124353D01*
X341008Y124270D01*
X341217Y124020D01*
X341342Y123728D01*
Y122687D01*
G01Y123728D02*
X342550Y124353D01*
G01X342050Y125703D02*
X342342Y125953D01*
X342508Y126287D01*
X342550Y126662D01*
X342508Y126995D01*
X342300Y127328D01*
X342050Y127537D01*
X341800Y127578D01*
X341508Y127495D01*
X341300Y127203D01*
X341217Y126912D01*
Y126537D01*
G01Y126912D02*
X341092Y127162D01*
X340883Y127370D01*
X340633Y127453D01*
X340383Y127370D01*
X340175Y127162D01*
X340050Y126787D01*
X340092Y126412D01*
X340258Y126037D01*
G01X342550Y129720D02*
X342508Y130012D01*
X342383Y130345D01*
X342175Y130553D01*
X341883Y130637D01*
X341592Y130553D01*
X341342Y130303D01*
X341217Y129928D01*
Y129512D01*
X341133Y129262D01*
X340925Y129053D01*
X340633Y128970D01*
X340342Y129095D01*
X340133Y129387D01*
X340050Y129720D01*
X340133Y130053D01*
X340342Y130345D01*
X340633Y130470D01*
X340925Y130387D01*
X341133Y130178D01*
X341217Y129928D01*
Y129512D01*
X341342Y129137D01*
X341592Y128887D01*
X341883Y128803D01*
X342175Y128887D01*
X342383Y129095D01*
X342508Y129428D01*
X342550Y129720D01*
G01X340467Y132028D02*
X340217Y132278D01*
X340092Y132570D01*
X340050Y132903D01*
X340133Y133320D01*
X340342Y133612D01*
X340592Y133695D01*
X340842Y133653D01*
X341050Y133487D01*
X341467Y132653D01*
X341758Y132278D01*
X342175Y132028D01*
X342550Y131945D01*
Y133695D01*
G01X350500Y121800D02*
X354500D01*
Y129200D01*
G01X381387Y332093D02*
X381137Y332218D01*
X380845Y332301D01*
X380512D01*
X380137Y332176D01*
X379845Y331968D01*
X379637Y331718D01*
X379470Y331301D01*
X379428Y330926D01*
X379512Y330551D01*
X379637Y330301D01*
X379887Y330051D01*
X380178Y329884D01*
X380470Y329801D01*
X380762D01*
X381053Y329884D01*
X381303Y330009D01*
X381512Y330176D01*
G01X382862Y330093D02*
X383153Y329884D01*
X383487Y329801D01*
X383820Y329884D01*
X384112Y330134D01*
X384320Y330509D01*
X384403Y330884D01*
Y331343D01*
X384320Y331718D01*
X384112Y332051D01*
X383862Y332218D01*
X383570Y332301D01*
X383237Y332218D01*
X382987Y332051D01*
X382820Y331801D01*
X382737Y331468D01*
X382820Y331176D01*
X383028Y330884D01*
X383278Y330718D01*
X383570Y330676D01*
X383903Y330759D01*
X384153Y330968D01*
X384403Y331343D01*
G01X385753Y330301D02*
X386003Y330009D01*
X386337Y329843D01*
X386712Y329801D01*
X387045Y329843D01*
X387378Y330051D01*
X387587Y330301D01*
X387628Y330551D01*
X387545Y330843D01*
X387253Y331051D01*
X386962Y331134D01*
X386587D01*
G01X386962D02*
X387212Y331259D01*
X387420Y331468D01*
X387503Y331718D01*
X387420Y331968D01*
X387212Y332176D01*
X386837Y332301D01*
X386462Y332259D01*
X386087Y332093D01*
G01X388853Y330176D02*
X389103Y329968D01*
X389395Y329843D01*
X389770Y329801D01*
X390145Y329884D01*
X390437Y330051D01*
X390645Y330343D01*
X390687Y330676D01*
X390603Y331009D01*
X390395Y331218D01*
X390103Y331384D01*
X389812Y331426D01*
X389520Y331384D01*
X389145Y331218D01*
X389270Y332301D01*
X390395D01*
G01X391953Y330176D02*
X392203Y329968D01*
X392495Y329843D01*
X392870Y329801D01*
X393245Y329884D01*
X393537Y330051D01*
X393745Y330343D01*
X393787Y330676D01*
X393703Y331009D01*
X393495Y331218D01*
X393203Y331384D01*
X392912Y331426D01*
X392620Y331384D01*
X392245Y331218D01*
X392370Y332301D01*
X393495D01*
G01X344957Y332482D02*
X344707Y332607D01*
X344415Y332690D01*
X344082D01*
X343707Y332565D01*
X343415Y332357D01*
X343207Y332107D01*
X343040Y331690D01*
X342998Y331315D01*
X343082Y330940D01*
X343207Y330690D01*
X343457Y330440D01*
X343748Y330273D01*
X344040Y330190D01*
X344332D01*
X344623Y330273D01*
X344873Y330398D01*
X345082Y330565D01*
G01X346432Y330482D02*
X346723Y330273D01*
X347057Y330190D01*
X347390Y330273D01*
X347682Y330523D01*
X347890Y330898D01*
X347973Y331273D01*
Y331732D01*
X347890Y332107D01*
X347682Y332440D01*
X347432Y332607D01*
X347140Y332690D01*
X346807Y332607D01*
X346557Y332440D01*
X346390Y332190D01*
X346307Y331857D01*
X346390Y331565D01*
X346598Y331273D01*
X346848Y331107D01*
X347140Y331065D01*
X347473Y331148D01*
X347723Y331357D01*
X347973Y331732D01*
G01X349323Y330690D02*
X349573Y330398D01*
X349907Y330232D01*
X350282Y330190D01*
X350615Y330232D01*
X350948Y330440D01*
X351157Y330690D01*
X351198Y330940D01*
X351115Y331232D01*
X350823Y331440D01*
X350532Y331523D01*
X350157D01*
G01X350532D02*
X350782Y331648D01*
X350990Y331857D01*
X351073Y332107D01*
X350990Y332357D01*
X350782Y332565D01*
X350407Y332690D01*
X350032Y332648D01*
X349657Y332482D01*
G01X352423Y330690D02*
X352673Y330398D01*
X353007Y330232D01*
X353382Y330190D01*
X353715Y330232D01*
X354048Y330440D01*
X354257Y330690D01*
X354298Y330940D01*
X354215Y331232D01*
X353923Y331440D01*
X353632Y331523D01*
X353257D01*
G01X353632D02*
X353882Y331648D01*
X354090Y331857D01*
X354173Y332107D01*
X354090Y332357D01*
X353882Y332565D01*
X353507Y332690D01*
X353132Y332648D01*
X352757Y332482D01*
G01X355732Y330482D02*
X356023Y330273D01*
X356357Y330190D01*
X356690Y330273D01*
X356982Y330523D01*
X357190Y330898D01*
X357273Y331273D01*
Y331732D01*
X357190Y332107D01*
X356982Y332440D01*
X356732Y332607D01*
X356440Y332690D01*
X356107Y332607D01*
X355857Y332440D01*
X355690Y332190D01*
X355607Y331857D01*
X355690Y331565D01*
X355898Y331273D01*
X356148Y331107D01*
X356440Y331065D01*
X356773Y331148D01*
X357023Y331357D01*
X357273Y331732D01*
G01X379637Y309371D02*
Y311871D01*
X380678D01*
X381012Y311746D01*
X381220Y311579D01*
X381303Y311246D01*
X381220Y310913D01*
X380970Y310704D01*
X380678Y310579D01*
X379637D01*
G01X380678D02*
X381303Y309371D01*
G01X382862Y309663D02*
X383153Y309454D01*
X383487Y309371D01*
X383820Y309454D01*
X384112Y309704D01*
X384320Y310079D01*
X384403Y310454D01*
Y310913D01*
X384320Y311288D01*
X384112Y311621D01*
X383862Y311788D01*
X383570Y311871D01*
X383237Y311788D01*
X382987Y311621D01*
X382820Y311371D01*
X382737Y311038D01*
X382820Y310746D01*
X383028Y310454D01*
X383278Y310288D01*
X383570Y310246D01*
X383903Y310329D01*
X384153Y310538D01*
X384403Y310913D01*
G01X387170Y309371D02*
Y311871D01*
X385628Y310079D01*
X387712D01*
G01X388853Y309746D02*
X389103Y309538D01*
X389395Y309413D01*
X389770Y309371D01*
X390145Y309454D01*
X390437Y309621D01*
X390645Y309913D01*
X390687Y310246D01*
X390603Y310579D01*
X390395Y310788D01*
X390103Y310954D01*
X389812Y310996D01*
X389520Y310954D01*
X389145Y310788D01*
X389270Y311871D01*
X390395D01*
G01X392870Y309371D02*
X393162Y309413D01*
X393495Y309538D01*
X393703Y309746D01*
X393787Y310038D01*
X393703Y310329D01*
X393453Y310579D01*
X393078Y310704D01*
X392662D01*
X392412Y310788D01*
X392203Y310996D01*
X392120Y311288D01*
X392245Y311579D01*
X392537Y311788D01*
X392870Y311871D01*
X393203Y311788D01*
X393495Y311579D01*
X393620Y311288D01*
X393537Y310996D01*
X393328Y310788D01*
X393078Y310704D01*
X392662D01*
X392287Y310579D01*
X392037Y310329D01*
X391953Y310038D01*
X392037Y309746D01*
X392245Y309538D01*
X392578Y309413D01*
X392870Y309371D01*
G01X342167Y308000D02*
Y310500D01*
X343208D01*
X343542Y310375D01*
X343750Y310208D01*
X343833Y309875D01*
X343750Y309542D01*
X343500Y309333D01*
X343208Y309208D01*
X342167D01*
G01X343208D02*
X343833Y308000D01*
G01X345392Y308292D02*
X345683Y308083D01*
X346017Y308000D01*
X346350Y308083D01*
X346642Y308333D01*
X346850Y308708D01*
X346933Y309083D01*
Y309542D01*
X346850Y309917D01*
X346642Y310250D01*
X346392Y310417D01*
X346100Y310500D01*
X345767Y310417D01*
X345517Y310250D01*
X345350Y310000D01*
X345267Y309667D01*
X345350Y309375D01*
X345558Y309083D01*
X345808Y308917D01*
X346100Y308875D01*
X346433Y308958D01*
X346683Y309167D01*
X346933Y309542D01*
G01X348283Y308375D02*
X348533Y308167D01*
X348825Y308042D01*
X349200Y308000D01*
X349575Y308083D01*
X349867Y308250D01*
X350075Y308542D01*
X350117Y308875D01*
X350033Y309208D01*
X349825Y309417D01*
X349533Y309583D01*
X349242Y309625D01*
X348950Y309583D01*
X348575Y309417D01*
X348700Y310500D01*
X349825D01*
G01X352300D02*
X351967Y310417D01*
X351717Y310208D01*
X351550Y309958D01*
X351425Y309625D01*
X351383Y309250D01*
X351425Y308875D01*
X351550Y308542D01*
X351717Y308292D01*
X351967Y308083D01*
X352300Y308000D01*
X352633Y308083D01*
X352883Y308292D01*
X353050Y308542D01*
X353175Y308875D01*
X353217Y309250D01*
X353175Y309625D01*
X353050Y309958D01*
X352883Y310208D01*
X352633Y310417D01*
X352300Y310500D01*
G01X355317Y308000D02*
X355400Y308542D01*
X355525Y309000D01*
X355692Y309417D01*
X355900Y309875D01*
X356233Y310500D01*
X354567D01*
G01X349834Y313967D02*
X347334D01*
Y315008D01*
X347459Y315342D01*
X347626Y315550D01*
X347959Y315633D01*
X348292Y315550D01*
X348501Y315300D01*
X348626Y315008D01*
Y313967D01*
G01Y315008D02*
X349834Y315633D01*
G01X349542Y317192D02*
X349751Y317483D01*
X349834Y317817D01*
X349751Y318150D01*
X349501Y318442D01*
X349126Y318650D01*
X348751Y318733D01*
X348292D01*
X347917Y318650D01*
X347584Y318442D01*
X347417Y318192D01*
X347334Y317900D01*
X347417Y317567D01*
X347584Y317317D01*
X347834Y317150D01*
X348167Y317067D01*
X348459Y317150D01*
X348751Y317358D01*
X348917Y317608D01*
X348959Y317900D01*
X348876Y318233D01*
X348667Y318483D01*
X348292Y318733D01*
G01X348792Y320208D02*
X348501Y320500D01*
X348334Y320750D01*
X348251Y321083D01*
X348334Y321375D01*
X348501Y321583D01*
X348751Y321750D01*
X349042Y321792D01*
X349292Y321750D01*
X349542Y321583D01*
X349751Y321333D01*
X349834Y321042D01*
X349751Y320708D01*
X349501Y320417D01*
X349126Y320250D01*
X348709Y320208D01*
X348167Y320292D01*
X347876Y320417D01*
X347584Y320625D01*
X347376Y320917D01*
X347334Y321208D01*
X347417Y321500D01*
X347626Y321708D01*
G01X347334Y324100D02*
X347417Y323767D01*
X347626Y323517D01*
X347876Y323350D01*
X348209Y323225D01*
X348584Y323183D01*
X348959Y323225D01*
X349292Y323350D01*
X349542Y323517D01*
X349751Y323767D01*
X349834Y324100D01*
X349751Y324433D01*
X349542Y324683D01*
X349292Y324850D01*
X348959Y324975D01*
X348584Y325017D01*
X348209Y324975D01*
X347876Y324850D01*
X347626Y324683D01*
X347417Y324433D01*
X347334Y324100D01*
G01X349834Y327117D02*
X349292Y327200D01*
X348834Y327325D01*
X348417Y327492D01*
X347959Y327700D01*
X347334Y328033D01*
Y326367D01*
G01X333000Y313067D02*
X330500D01*
Y314108D01*
X330625Y314442D01*
X330792Y314650D01*
X331125Y314733D01*
X331458Y314650D01*
X331667Y314400D01*
X331792Y314108D01*
Y313067D01*
G01Y314108D02*
X333000Y314733D01*
G01X332708Y316292D02*
X332917Y316583D01*
X333000Y316917D01*
X332917Y317250D01*
X332667Y317542D01*
X332292Y317750D01*
X331917Y317833D01*
X331458D01*
X331083Y317750D01*
X330750Y317542D01*
X330583Y317292D01*
X330500Y317000D01*
X330583Y316667D01*
X330750Y316417D01*
X331000Y316250D01*
X331333Y316167D01*
X331625Y316250D01*
X331917Y316458D01*
X332083Y316708D01*
X332125Y317000D01*
X332042Y317333D01*
X331833Y317583D01*
X331458Y317833D01*
G01X331958Y319308D02*
X331667Y319600D01*
X331500Y319850D01*
X331417Y320183D01*
X331500Y320475D01*
X331667Y320683D01*
X331917Y320850D01*
X332208Y320892D01*
X332458Y320850D01*
X332708Y320683D01*
X332917Y320433D01*
X333000Y320142D01*
X332917Y319808D01*
X332667Y319517D01*
X332292Y319350D01*
X331875Y319308D01*
X331333Y319392D01*
X331042Y319517D01*
X330750Y319725D01*
X330542Y320017D01*
X330500Y320308D01*
X330583Y320600D01*
X330792Y320808D01*
G01X330500Y323200D02*
X330583Y322867D01*
X330792Y322617D01*
X331042Y322450D01*
X331375Y322325D01*
X331750Y322283D01*
X332125Y322325D01*
X332458Y322450D01*
X332708Y322617D01*
X332917Y322867D01*
X333000Y323200D01*
X332917Y323533D01*
X332708Y323783D01*
X332458Y323950D01*
X332125Y324075D01*
X331750Y324117D01*
X331375Y324075D01*
X331042Y323950D01*
X330792Y323783D01*
X330583Y323533D01*
X330500Y323200D01*
G01X331958Y325508D02*
X331667Y325800D01*
X331500Y326050D01*
X331417Y326383D01*
X331500Y326675D01*
X331667Y326883D01*
X331917Y327050D01*
X332208Y327092D01*
X332458Y327050D01*
X332708Y326883D01*
X332917Y326633D01*
X333000Y326342D01*
X332917Y326008D01*
X332667Y325717D01*
X332292Y325550D01*
X331875Y325508D01*
X331333Y325592D01*
X331042Y325717D01*
X330750Y325925D01*
X330542Y326217D01*
X330500Y326508D01*
X330583Y326800D01*
X330792Y327008D01*
G01X386669Y313637D02*
X384169D01*
Y314678D01*
X384294Y315012D01*
X384461Y315220D01*
X384794Y315303D01*
X385127Y315220D01*
X385336Y314970D01*
X385461Y314678D01*
Y313637D01*
G01Y314678D02*
X386669Y315303D01*
G01X386377Y316862D02*
X386586Y317153D01*
X386669Y317487D01*
X386586Y317820D01*
X386336Y318112D01*
X385961Y318320D01*
X385586Y318403D01*
X385127D01*
X384752Y318320D01*
X384419Y318112D01*
X384252Y317862D01*
X384169Y317570D01*
X384252Y317237D01*
X384419Y316987D01*
X384669Y316820D01*
X385002Y316737D01*
X385294Y316820D01*
X385586Y317028D01*
X385752Y317278D01*
X385794Y317570D01*
X385711Y317903D01*
X385502Y318153D01*
X385127Y318403D01*
G01X385627Y319878D02*
X385336Y320170D01*
X385169Y320420D01*
X385086Y320753D01*
X385169Y321045D01*
X385336Y321253D01*
X385586Y321420D01*
X385877Y321462D01*
X386127Y321420D01*
X386377Y321253D01*
X386586Y321003D01*
X386669Y320712D01*
X386586Y320378D01*
X386336Y320087D01*
X385961Y319920D01*
X385544Y319878D01*
X385002Y319962D01*
X384711Y320087D01*
X384419Y320295D01*
X384211Y320587D01*
X384169Y320878D01*
X384252Y321170D01*
X384461Y321378D01*
G01X386669Y323770D02*
X384169D01*
X384669Y323270D01*
G01X386669D02*
Y324270D01*
G01X385627Y326078D02*
X385336Y326370D01*
X385169Y326620D01*
X385086Y326953D01*
X385169Y327245D01*
X385336Y327453D01*
X385586Y327620D01*
X385877Y327662D01*
X386127Y327620D01*
X386377Y327453D01*
X386586Y327203D01*
X386669Y326912D01*
X386586Y326578D01*
X386336Y326287D01*
X385961Y326120D01*
X385544Y326078D01*
X385002Y326162D01*
X384711Y326287D01*
X384419Y326495D01*
X384211Y326787D01*
X384169Y327078D01*
X384252Y327370D01*
X384461Y327578D01*
G01X401208Y377217D02*
X401083Y376967D01*
X401000Y376675D01*
Y376342D01*
X401125Y375967D01*
X401333Y375675D01*
X401583Y375467D01*
X402000Y375300D01*
X402375Y375258D01*
X402750Y375342D01*
X403000Y375467D01*
X403250Y375717D01*
X403417Y376008D01*
X403500Y376300D01*
Y376592D01*
X403417Y376883D01*
X403292Y377133D01*
X403125Y377342D01*
G01X403500Y379400D02*
X403458Y379692D01*
X403333Y380025D01*
X403125Y380233D01*
X402833Y380317D01*
X402542Y380233D01*
X402292Y379983D01*
X402167Y379608D01*
Y379192D01*
X402083Y378942D01*
X401875Y378733D01*
X401583Y378650D01*
X401292Y378775D01*
X401083Y379067D01*
X401000Y379400D01*
X401083Y379733D01*
X401292Y380025D01*
X401583Y380150D01*
X401875Y380067D01*
X402083Y379858D01*
X402167Y379608D01*
Y379192D01*
X402292Y378817D01*
X402542Y378567D01*
X402833Y378483D01*
X403125Y378567D01*
X403333Y378775D01*
X403458Y379108D01*
X403500Y379400D01*
G01Y382500D02*
X403458Y382792D01*
X403333Y383125D01*
X403125Y383333D01*
X402833Y383417D01*
X402542Y383333D01*
X402292Y383083D01*
X402167Y382708D01*
Y382292D01*
X402083Y382042D01*
X401875Y381833D01*
X401583Y381750D01*
X401292Y381875D01*
X401083Y382167D01*
X401000Y382500D01*
X401083Y382833D01*
X401292Y383125D01*
X401583Y383250D01*
X401875Y383167D01*
X402083Y382958D01*
X402167Y382708D01*
Y382292D01*
X402292Y381917D01*
X402542Y381667D01*
X402833Y381583D01*
X403125Y381667D01*
X403333Y381875D01*
X403458Y382208D01*
X403500Y382500D01*
G01Y385517D02*
X402958Y385600D01*
X402500Y385725D01*
X402083Y385892D01*
X401625Y386100D01*
X401000Y386433D01*
Y384767D01*
G01X403125Y387783D02*
X403333Y388033D01*
X403458Y388325D01*
X403500Y388700D01*
X403417Y389075D01*
X403250Y389367D01*
X402958Y389575D01*
X402625Y389617D01*
X402292Y389533D01*
X402083Y389325D01*
X401917Y389033D01*
X401875Y388742D01*
X401917Y388450D01*
X402083Y388075D01*
X401000Y388200D01*
Y389325D01*
G01X350200Y339000D02*
Y343000D01*
X342800D01*
G01X385700Y339000D02*
Y343000D01*
X378300D01*
G01X340200Y391000D02*
Y395000D01*
X332800D01*
G01X346500Y369700D02*
X342500D01*
Y362300D01*
G01X332800Y391000D02*
Y387000D01*
X340200D01*
G01X361500Y369700D02*
X357500D01*
Y362300D01*
G01X403710Y354867D02*
X401210D01*
Y355908D01*
X401335Y356242D01*
X401502Y356450D01*
X401835Y356533D01*
X402168Y356450D01*
X402377Y356200D01*
X402502Y355908D01*
Y354867D01*
G01Y355908D02*
X403710Y356533D01*
G01X403418Y358092D02*
X403627Y358383D01*
X403710Y358717D01*
X403627Y359050D01*
X403377Y359342D01*
X403002Y359550D01*
X402627Y359633D01*
X402168D01*
X401793Y359550D01*
X401460Y359342D01*
X401293Y359092D01*
X401210Y358800D01*
X401293Y358467D01*
X401460Y358217D01*
X401710Y358050D01*
X402043Y357967D01*
X402335Y358050D01*
X402627Y358258D01*
X402793Y358508D01*
X402835Y358800D01*
X402752Y359133D01*
X402543Y359383D01*
X402168Y359633D01*
G01X403710Y361900D02*
X401210D01*
X401710Y361400D01*
G01X403710D02*
Y362400D01*
G01X401627Y364208D02*
X401377Y364458D01*
X401252Y364750D01*
X401210Y365083D01*
X401293Y365500D01*
X401502Y365792D01*
X401752Y365875D01*
X402002Y365833D01*
X402210Y365667D01*
X402627Y364833D01*
X402918Y364458D01*
X403335Y364208D01*
X403710Y364125D01*
Y365875D01*
G01Y368600D02*
X401210D01*
X403002Y367058D01*
Y369142D01*
G01X342500Y369700D02*
X338500D01*
Y362300D01*
G01X382000Y369700D02*
X378000D01*
Y362300D01*
G01X397000Y369700D02*
X393000D01*
Y362300D01*
G01X357500Y369700D02*
X353500D01*
Y362300D01*
G01X378000Y369700D02*
X374000D01*
Y362300D01*
G01X393000Y369700D02*
X389000D01*
Y362300D01*
G01X400000Y412200D02*
X396000D01*
Y404800D01*
G01X358200Y339000D02*
Y343000D01*
X350800D01*
G01X393700Y339000D02*
Y343000D01*
X386300D01*
G01X351000Y343300D02*
X355000D01*
Y350700D01*
G01X386500Y343300D02*
X390500D01*
Y350700D01*
G01X343000Y343300D02*
X347000D01*
Y350700D01*
G01X378500Y343300D02*
X382500D01*
Y350700D01*
G01X340223Y410220D02*
X338557D01*
Y412720D01*
X340223D01*
G01X339557Y411512D02*
X338557D01*
G01X341573Y412720D02*
Y410928D01*
X341740Y410553D01*
X342073Y410303D01*
X342490Y410220D01*
X342907Y410303D01*
X343240Y410553D01*
X343407Y410928D01*
Y412720D01*
G01X346090Y410220D02*
Y412720D01*
X344548Y410928D01*
X346632D01*
G01X386200Y378350D02*
X391700D01*
Y383450D01*
G01X348300Y384300D02*
Y378300D01*
X354550D01*
G01X380800Y376485D02*
Y379485D01*
G01X361100Y376485D02*
Y379485D01*
G01X371000D02*
Y377485D01*
G01X390515Y408800D02*
X392515D01*
G01X390515Y389200D02*
X392515D01*
G01X393515Y397100D02*
X390515D01*
G01X347485Y387150D02*
X349485D01*
G01X347485Y406900D02*
X349485D01*
G01Y397085D02*
X346485D01*
G01X364178Y443327D02*
X364053Y443077D01*
X363970Y442785D01*
Y442452D01*
X364095Y442077D01*
X364303Y441785D01*
X364553Y441577D01*
X364970Y441410D01*
X365345Y441368D01*
X365720Y441452D01*
X365970Y441577D01*
X366220Y441827D01*
X366387Y442118D01*
X366470Y442410D01*
Y442702D01*
X366387Y442993D01*
X366262Y443243D01*
X366095Y443452D01*
G01X366178Y444802D02*
X366387Y445093D01*
X366470Y445427D01*
X366387Y445760D01*
X366137Y446052D01*
X365762Y446260D01*
X365387Y446343D01*
X364928D01*
X364553Y446260D01*
X364220Y446052D01*
X364053Y445802D01*
X363970Y445510D01*
X364053Y445177D01*
X364220Y444927D01*
X364470Y444760D01*
X364803Y444677D01*
X365095Y444760D01*
X365387Y444968D01*
X365553Y445218D01*
X365595Y445510D01*
X365512Y445843D01*
X365303Y446093D01*
X364928Y446343D01*
G01X366470Y449110D02*
X363970D01*
X365762Y447568D01*
Y449652D01*
G01X365970Y450793D02*
X366262Y451043D01*
X366428Y451377D01*
X366470Y451752D01*
X366428Y452085D01*
X366220Y452418D01*
X365970Y452627D01*
X365720Y452668D01*
X365428Y452585D01*
X365220Y452293D01*
X365137Y452002D01*
Y451627D01*
G01Y452002D02*
X365012Y452252D01*
X364803Y452460D01*
X364553Y452543D01*
X364303Y452460D01*
X364095Y452252D01*
X363970Y451877D01*
X364012Y451502D01*
X364178Y451127D01*
G01X365970Y453893D02*
X366262Y454143D01*
X366428Y454477D01*
X366470Y454852D01*
X366428Y455185D01*
X366220Y455518D01*
X365970Y455727D01*
X365720Y455768D01*
X365428Y455685D01*
X365220Y455393D01*
X365137Y455102D01*
Y454727D01*
G01Y455102D02*
X365012Y455352D01*
X364803Y455560D01*
X364553Y455643D01*
X364303Y455560D01*
X364095Y455352D01*
X363970Y454977D01*
X364012Y454602D01*
X364178Y454227D01*
G01X401017Y449592D02*
X400767Y449717D01*
X400475Y449800D01*
X400142D01*
X399767Y449675D01*
X399475Y449467D01*
X399267Y449217D01*
X399100Y448800D01*
X399058Y448425D01*
X399142Y448050D01*
X399267Y447800D01*
X399517Y447550D01*
X399808Y447383D01*
X400100Y447300D01*
X400392D01*
X400683Y447383D01*
X400933Y447508D01*
X401142Y447675D01*
G01X402492Y447592D02*
X402783Y447383D01*
X403117Y447300D01*
X403450Y447383D01*
X403742Y447633D01*
X403950Y448008D01*
X404033Y448383D01*
Y448842D01*
X403950Y449217D01*
X403742Y449550D01*
X403492Y449717D01*
X403200Y449800D01*
X402867Y449717D01*
X402617Y449550D01*
X402450Y449300D01*
X402367Y448967D01*
X402450Y448675D01*
X402658Y448383D01*
X402908Y448217D01*
X403200Y448175D01*
X403533Y448258D01*
X403783Y448467D01*
X404033Y448842D01*
G01X405383Y447800D02*
X405633Y447508D01*
X405967Y447342D01*
X406342Y447300D01*
X406675Y447342D01*
X407008Y447550D01*
X407217Y447800D01*
X407258Y448050D01*
X407175Y448342D01*
X406883Y448550D01*
X406592Y448633D01*
X406217D01*
G01X406592D02*
X406842Y448758D01*
X407050Y448967D01*
X407133Y449217D01*
X407050Y449467D01*
X406842Y449675D01*
X406467Y449800D01*
X406092Y449758D01*
X405717Y449592D01*
G01X409317Y447300D02*
X409400Y447842D01*
X409525Y448300D01*
X409692Y448717D01*
X409900Y449175D01*
X410233Y449800D01*
X408567D01*
G01X412500D02*
X412167Y449717D01*
X411917Y449508D01*
X411750Y449258D01*
X411625Y448925D01*
X411583Y448550D01*
X411625Y448175D01*
X411750Y447842D01*
X411917Y447592D01*
X412167Y447383D01*
X412500Y447300D01*
X412833Y447383D01*
X413083Y447592D01*
X413250Y447842D01*
X413375Y448175D01*
X413417Y448550D01*
X413375Y448925D01*
X413250Y449258D01*
X413083Y449508D01*
X412833Y449717D01*
X412500Y449800D01*
G01X368178Y443327D02*
X368053Y443077D01*
X367970Y442785D01*
Y442452D01*
X368095Y442077D01*
X368303Y441785D01*
X368553Y441577D01*
X368970Y441410D01*
X369345Y441368D01*
X369720Y441452D01*
X369970Y441577D01*
X370220Y441827D01*
X370387Y442118D01*
X370470Y442410D01*
Y442702D01*
X370387Y442993D01*
X370262Y443243D01*
X370095Y443452D01*
G01X370470Y445510D02*
X370428Y445802D01*
X370303Y446135D01*
X370095Y446343D01*
X369803Y446427D01*
X369512Y446343D01*
X369262Y446093D01*
X369137Y445718D01*
Y445302D01*
X369053Y445052D01*
X368845Y444843D01*
X368553Y444760D01*
X368262Y444885D01*
X368053Y445177D01*
X367970Y445510D01*
X368053Y445843D01*
X368262Y446135D01*
X368553Y446260D01*
X368845Y446177D01*
X369053Y445968D01*
X369137Y445718D01*
Y445302D01*
X369262Y444927D01*
X369512Y444677D01*
X369803Y444593D01*
X370095Y444677D01*
X370303Y444885D01*
X370428Y445218D01*
X370470Y445510D01*
G01Y448610D02*
X370428Y448902D01*
X370303Y449235D01*
X370095Y449443D01*
X369803Y449527D01*
X369512Y449443D01*
X369262Y449193D01*
X369137Y448818D01*
Y448402D01*
X369053Y448152D01*
X368845Y447943D01*
X368553Y447860D01*
X368262Y447985D01*
X368053Y448277D01*
X367970Y448610D01*
X368053Y448943D01*
X368262Y449235D01*
X368553Y449360D01*
X368845Y449277D01*
X369053Y449068D01*
X369137Y448818D01*
Y448402D01*
X369262Y448027D01*
X369512Y447777D01*
X369803Y447693D01*
X370095Y447777D01*
X370303Y447985D01*
X370428Y448318D01*
X370470Y448610D01*
G01Y451627D02*
X369928Y451710D01*
X369470Y451835D01*
X369053Y452002D01*
X368595Y452210D01*
X367970Y452543D01*
Y450877D01*
G01X369970Y453893D02*
X370262Y454143D01*
X370428Y454477D01*
X370470Y454852D01*
X370428Y455185D01*
X370220Y455518D01*
X369970Y455727D01*
X369720Y455768D01*
X369428Y455685D01*
X369220Y455393D01*
X369137Y455102D01*
Y454727D01*
G01Y455102D02*
X369012Y455352D01*
X368803Y455560D01*
X368553Y455643D01*
X368303Y455560D01*
X368095Y455352D01*
X367970Y454977D01*
X368012Y454602D01*
X368178Y454227D01*
G01X385300Y461000D02*
Y457000D01*
X392700D01*
G01X349800Y461000D02*
Y457000D01*
X357200D01*
G01X342500Y430300D02*
X346500D01*
Y437700D01*
G01X338500Y430300D02*
X342500D01*
Y437700D01*
G01X335470Y435977D02*
X332970D01*
Y437018D01*
X333095Y437352D01*
X333262Y437560D01*
X333595Y437643D01*
X333928Y437560D01*
X334137Y437310D01*
X334262Y437018D01*
Y435977D01*
G01Y437018D02*
X335470Y437643D01*
G01X335178Y439202D02*
X335387Y439493D01*
X335470Y439827D01*
X335387Y440160D01*
X335137Y440452D01*
X334762Y440660D01*
X334387Y440743D01*
X333928D01*
X333553Y440660D01*
X333220Y440452D01*
X333053Y440202D01*
X332970Y439910D01*
X333053Y439577D01*
X333220Y439327D01*
X333470Y439160D01*
X333803Y439077D01*
X334095Y439160D01*
X334387Y439368D01*
X334553Y439618D01*
X334595Y439910D01*
X334512Y440243D01*
X334303Y440493D01*
X333928Y440743D01*
G01X332970Y443010D02*
X333053Y442677D01*
X333262Y442427D01*
X333512Y442260D01*
X333845Y442135D01*
X334220Y442093D01*
X334595Y442135D01*
X334928Y442260D01*
X335178Y442427D01*
X335387Y442677D01*
X335470Y443010D01*
X335387Y443343D01*
X335178Y443593D01*
X334928Y443760D01*
X334595Y443885D01*
X334220Y443927D01*
X333845Y443885D01*
X333512Y443760D01*
X333262Y443593D01*
X333053Y443343D01*
X332970Y443010D01*
G01X334428Y445318D02*
X334137Y445610D01*
X333970Y445860D01*
X333887Y446193D01*
X333970Y446485D01*
X334137Y446693D01*
X334387Y446860D01*
X334678Y446902D01*
X334928Y446860D01*
X335178Y446693D01*
X335387Y446443D01*
X335470Y446152D01*
X335387Y445818D01*
X335137Y445527D01*
X334762Y445360D01*
X334345Y445318D01*
X333803Y445402D01*
X333512Y445527D01*
X333220Y445735D01*
X333012Y446027D01*
X332970Y446318D01*
X333053Y446610D01*
X333262Y446818D01*
G01X335470Y449210D02*
X332970D01*
X333470Y448710D01*
G01X335470D02*
Y449710D01*
G01X357500Y430300D02*
X361500D01*
Y437700D01*
G01X353500Y430300D02*
X357500D01*
Y437700D01*
G01X393000Y430300D02*
X397000D01*
Y437700D01*
G01X389000Y430300D02*
X393000D01*
Y437700D01*
G01X374000Y430300D02*
X378000D01*
Y437700D01*
G01Y430300D02*
X382000D01*
Y437700D01*
G01X399267Y455300D02*
Y457800D01*
X400308D01*
X400642Y457675D01*
X400850Y457508D01*
X400933Y457175D01*
X400850Y456842D01*
X400600Y456633D01*
X400308Y456508D01*
X399267D01*
G01X400308D02*
X400933Y455300D01*
G01X402492Y455592D02*
X402783Y455383D01*
X403117Y455300D01*
X403450Y455383D01*
X403742Y455633D01*
X403950Y456008D01*
X404033Y456383D01*
Y456842D01*
X403950Y457217D01*
X403742Y457550D01*
X403492Y457717D01*
X403200Y457800D01*
X402867Y457717D01*
X402617Y457550D01*
X402450Y457300D01*
X402367Y456967D01*
X402450Y456675D01*
X402658Y456383D01*
X402908Y456217D01*
X403200Y456175D01*
X403533Y456258D01*
X403783Y456467D01*
X404033Y456842D01*
G01X405383Y455675D02*
X405633Y455467D01*
X405925Y455342D01*
X406300Y455300D01*
X406675Y455383D01*
X406967Y455550D01*
X407175Y455842D01*
X407217Y456175D01*
X407133Y456508D01*
X406925Y456717D01*
X406633Y456883D01*
X406342Y456925D01*
X406050Y456883D01*
X405675Y456717D01*
X405800Y457800D01*
X406925D01*
G01X409400D02*
X409067Y457717D01*
X408817Y457508D01*
X408650Y457258D01*
X408525Y456925D01*
X408483Y456550D01*
X408525Y456175D01*
X408650Y455842D01*
X408817Y455592D01*
X409067Y455383D01*
X409400Y455300D01*
X409733Y455383D01*
X409983Y455592D01*
X410150Y455842D01*
X410275Y456175D01*
X410317Y456550D01*
X410275Y456925D01*
X410150Y457258D01*
X409983Y457508D01*
X409733Y457717D01*
X409400Y457800D01*
G01X411583Y455675D02*
X411833Y455467D01*
X412125Y455342D01*
X412500Y455300D01*
X412875Y455383D01*
X413167Y455550D01*
X413375Y455842D01*
X413417Y456175D01*
X413333Y456508D01*
X413125Y456717D01*
X412833Y456883D01*
X412542Y456925D01*
X412250Y456883D01*
X411875Y456717D01*
X412000Y457800D01*
X413125D01*
G01X377300Y461000D02*
Y457000D01*
X384700D01*
G01X341800Y461000D02*
Y457000D01*
X349200D01*
G01X409200Y424000D02*
X401400D01*
G01X395800Y417000D02*
X404500D01*
G01X395800Y424000D02*
Y417000D01*
G01X402200Y424000D02*
X395800D01*
G01X398967Y451167D02*
Y453667D01*
X400008D01*
X400342Y453542D01*
X400550Y453375D01*
X400633Y453042D01*
X400550Y452709D01*
X400300Y452500D01*
X400008Y452375D01*
X398967D01*
G01X400008D02*
X400633Y451167D01*
G01X402192Y451459D02*
X402483Y451250D01*
X402817Y451167D01*
X403150Y451250D01*
X403442Y451500D01*
X403650Y451875D01*
X403733Y452250D01*
Y452709D01*
X403650Y453084D01*
X403442Y453417D01*
X403192Y453584D01*
X402900Y453667D01*
X402567Y453584D01*
X402317Y453417D01*
X402150Y453167D01*
X402067Y452834D01*
X402150Y452542D01*
X402358Y452250D01*
X402608Y452084D01*
X402900Y452042D01*
X403233Y452125D01*
X403483Y452334D01*
X403733Y452709D01*
G01X405208Y452209D02*
X405500Y452500D01*
X405750Y452667D01*
X406083Y452750D01*
X406375Y452667D01*
X406583Y452500D01*
X406750Y452250D01*
X406792Y451959D01*
X406750Y451709D01*
X406583Y451459D01*
X406333Y451250D01*
X406042Y451167D01*
X405708Y451250D01*
X405417Y451500D01*
X405250Y451875D01*
X405208Y452292D01*
X405292Y452834D01*
X405417Y453125D01*
X405625Y453417D01*
X405917Y453625D01*
X406208Y453667D01*
X406500Y453584D01*
X406708Y453375D01*
G01X409100Y453667D02*
X408767Y453584D01*
X408517Y453375D01*
X408350Y453125D01*
X408225Y452792D01*
X408183Y452417D01*
X408225Y452042D01*
X408350Y451709D01*
X408517Y451459D01*
X408767Y451250D01*
X409100Y451167D01*
X409433Y451250D01*
X409683Y451459D01*
X409850Y451709D01*
X409975Y452042D01*
X410017Y452417D01*
X409975Y452792D01*
X409850Y453125D01*
X409683Y453375D01*
X409433Y453584D01*
X409100Y453667D01*
G01X411283Y451542D02*
X411533Y451334D01*
X411825Y451209D01*
X412200Y451167D01*
X412575Y451250D01*
X412867Y451417D01*
X413075Y451709D01*
X413117Y452042D01*
X413033Y452375D01*
X412825Y452584D01*
X412533Y452750D01*
X412242Y452792D01*
X411950Y452750D01*
X411575Y452584D01*
X411700Y453667D01*
X412825D01*
G01X384500Y456700D02*
X380500D01*
Y449300D01*
G01X349000Y456700D02*
X345000D01*
Y449300D01*
G01X392500Y456700D02*
X388500D01*
Y449300D01*
G01X357000Y456700D02*
X353000D01*
Y449300D01*
G01X391650Y416050D02*
Y421700D01*
X385700D01*
G01X382715Y420515D02*
Y423515D01*
G01X363000Y420515D02*
Y423515D01*
G01X372800Y422515D02*
Y420515D01*
G01X352717Y584792D02*
X352467Y584917D01*
X352175Y585000D01*
X351842D01*
X351467Y584875D01*
X351175Y584667D01*
X350967Y584417D01*
X350800Y584000D01*
X350758Y583625D01*
X350842Y583250D01*
X350967Y583000D01*
X351217Y582750D01*
X351508Y582583D01*
X351800Y582500D01*
X352092D01*
X352383Y582583D01*
X352633Y582708D01*
X352842Y582875D01*
G01X354192Y582792D02*
X354483Y582583D01*
X354817Y582500D01*
X355150Y582583D01*
X355442Y582833D01*
X355650Y583208D01*
X355733Y583583D01*
Y584042D01*
X355650Y584417D01*
X355442Y584750D01*
X355192Y584917D01*
X354900Y585000D01*
X354567Y584917D01*
X354317Y584750D01*
X354150Y584500D01*
X354067Y584167D01*
X354150Y583875D01*
X354358Y583583D01*
X354608Y583417D01*
X354900Y583375D01*
X355233Y583458D01*
X355483Y583667D01*
X355733Y584042D01*
G01X357083Y583000D02*
X357333Y582708D01*
X357667Y582542D01*
X358042Y582500D01*
X358375Y582542D01*
X358708Y582750D01*
X358917Y583000D01*
X358958Y583250D01*
X358875Y583542D01*
X358583Y583750D01*
X358292Y583833D01*
X357917D01*
G01X358292D02*
X358542Y583958D01*
X358750Y584167D01*
X358833Y584417D01*
X358750Y584667D01*
X358542Y584875D01*
X358167Y585000D01*
X357792Y584958D01*
X357417Y584792D01*
G01X360308Y584583D02*
X360558Y584833D01*
X360850Y584958D01*
X361183Y585000D01*
X361600Y584917D01*
X361892Y584708D01*
X361975Y584458D01*
X361933Y584208D01*
X361767Y584000D01*
X360933Y583583D01*
X360558Y583292D01*
X360308Y582875D01*
X360225Y582500D01*
X361975D01*
G01X363408Y584583D02*
X363658Y584833D01*
X363950Y584958D01*
X364283Y585000D01*
X364700Y584917D01*
X364992Y584708D01*
X365075Y584458D01*
X365033Y584208D01*
X364867Y584000D01*
X364033Y583583D01*
X363658Y583292D01*
X363408Y582875D01*
X363325Y582500D01*
X365075D01*
G01X353007Y607960D02*
Y610460D01*
X354007D01*
X354340Y610335D01*
X354590Y610043D01*
X354673Y609710D01*
X354590Y609377D01*
X354382Y609127D01*
X354007Y609002D01*
X353007D01*
G01X356107Y607960D02*
Y610460D01*
X357148D01*
X357482Y610335D01*
X357690Y610168D01*
X357773Y609835D01*
X357690Y609502D01*
X357440Y609293D01*
X357148Y609168D01*
X356107D01*
G01X357148D02*
X357773Y607960D01*
G01X359332Y608252D02*
X359623Y608043D01*
X359957Y607960D01*
X360290Y608043D01*
X360582Y608293D01*
X360790Y608668D01*
X360873Y609043D01*
Y609502D01*
X360790Y609877D01*
X360582Y610210D01*
X360332Y610377D01*
X360040Y610460D01*
X359707Y610377D01*
X359457Y610210D01*
X359290Y609960D01*
X359207Y609627D01*
X359290Y609335D01*
X359498Y609043D01*
X359748Y608877D01*
X360040Y608835D01*
X360373Y608918D01*
X360623Y609127D01*
X360873Y609502D01*
G01X363140Y610460D02*
X362807Y610377D01*
X362557Y610168D01*
X362390Y609918D01*
X362265Y609585D01*
X362223Y609210D01*
X362265Y608835D01*
X362390Y608502D01*
X362557Y608252D01*
X362807Y608043D01*
X363140Y607960D01*
X363473Y608043D01*
X363723Y608252D01*
X363890Y608502D01*
X364015Y608835D01*
X364057Y609210D01*
X364015Y609585D01*
X363890Y609918D01*
X363723Y610168D01*
X363473Y610377D01*
X363140Y610460D01*
G01X365323Y608335D02*
X365573Y608127D01*
X365865Y608002D01*
X366240Y607960D01*
X366615Y608043D01*
X366907Y608210D01*
X367115Y608502D01*
X367157Y608835D01*
X367073Y609168D01*
X366865Y609377D01*
X366573Y609543D01*
X366282Y609585D01*
X365990Y609543D01*
X365615Y609377D01*
X365740Y610460D01*
X366865D01*
G01X368632Y608252D02*
X368923Y608043D01*
X369257Y607960D01*
X369590Y608043D01*
X369882Y608293D01*
X370090Y608668D01*
X370173Y609043D01*
Y609502D01*
X370090Y609877D01*
X369882Y610210D01*
X369632Y610377D01*
X369340Y610460D01*
X369007Y610377D01*
X368757Y610210D01*
X368590Y609960D01*
X368507Y609627D01*
X368590Y609335D01*
X368798Y609043D01*
X369048Y608877D01*
X369340Y608835D01*
X369673Y608918D01*
X369923Y609127D01*
X370173Y609502D01*
G01X363017Y570500D02*
Y573000D01*
X364058D01*
X364392Y572875D01*
X364600Y572708D01*
X364683Y572375D01*
X364600Y572042D01*
X364350Y571833D01*
X364058Y571708D01*
X363017D01*
G01X364058D02*
X364683Y570500D01*
G01X366033Y571000D02*
X366283Y570708D01*
X366617Y570542D01*
X366992Y570500D01*
X367325Y570542D01*
X367658Y570750D01*
X367867Y571000D01*
X367908Y571250D01*
X367825Y571542D01*
X367533Y571750D01*
X367242Y571833D01*
X366867D01*
G01X367242D02*
X367492Y571958D01*
X367700Y572167D01*
X367783Y572417D01*
X367700Y572667D01*
X367492Y572875D01*
X367117Y573000D01*
X366742Y572958D01*
X366367Y572792D01*
G01X369967Y570500D02*
X370050Y571042D01*
X370175Y571500D01*
X370342Y571917D01*
X370550Y572375D01*
X370883Y573000D01*
X369217D01*
G01X373150Y570500D02*
Y573000D01*
X372650Y572500D01*
G01Y570500D02*
X373650D01*
G01X363017Y576000D02*
Y578500D01*
X364058D01*
X364392Y578375D01*
X364600Y578208D01*
X364683Y577875D01*
X364600Y577542D01*
X364350Y577333D01*
X364058Y577208D01*
X363017D01*
G01X364058D02*
X364683Y576000D01*
G01X366033Y576500D02*
X366283Y576208D01*
X366617Y576042D01*
X366992Y576000D01*
X367325Y576042D01*
X367658Y576250D01*
X367867Y576500D01*
X367908Y576750D01*
X367825Y577042D01*
X367533Y577250D01*
X367242Y577333D01*
X366867D01*
G01X367242D02*
X367492Y577458D01*
X367700Y577667D01*
X367783Y577917D01*
X367700Y578167D01*
X367492Y578375D01*
X367117Y578500D01*
X366742Y578458D01*
X366367Y578292D01*
G01X369967Y576000D02*
X370050Y576542D01*
X370175Y577000D01*
X370342Y577417D01*
X370550Y577875D01*
X370883Y578500D01*
X369217D01*
G01X372358Y578083D02*
X372608Y578333D01*
X372900Y578458D01*
X373233Y578500D01*
X373650Y578417D01*
X373942Y578208D01*
X374025Y577958D01*
X373983Y577708D01*
X373817Y577500D01*
X372983Y577083D01*
X372608Y576792D01*
X372358Y576375D01*
X372275Y576000D01*
X374025D01*
G01X353007Y603960D02*
Y606460D01*
X354007D01*
X354340Y606335D01*
X354590Y606043D01*
X354673Y605710D01*
X354590Y605377D01*
X354382Y605127D01*
X354007Y605002D01*
X353007D01*
G01X356107Y603960D02*
Y606460D01*
X357148D01*
X357482Y606335D01*
X357690Y606168D01*
X357773Y605835D01*
X357690Y605502D01*
X357440Y605293D01*
X357148Y605168D01*
X356107D01*
G01X357148D02*
X357773Y603960D01*
G01X359332Y604252D02*
X359623Y604043D01*
X359957Y603960D01*
X360290Y604043D01*
X360582Y604293D01*
X360790Y604668D01*
X360873Y605043D01*
Y605502D01*
X360790Y605877D01*
X360582Y606210D01*
X360332Y606377D01*
X360040Y606460D01*
X359707Y606377D01*
X359457Y606210D01*
X359290Y605960D01*
X359207Y605627D01*
X359290Y605335D01*
X359498Y605043D01*
X359748Y604877D01*
X360040Y604835D01*
X360373Y604918D01*
X360623Y605127D01*
X360873Y605502D01*
G01X363140Y606460D02*
X362807Y606377D01*
X362557Y606168D01*
X362390Y605918D01*
X362265Y605585D01*
X362223Y605210D01*
X362265Y604835D01*
X362390Y604502D01*
X362557Y604252D01*
X362807Y604043D01*
X363140Y603960D01*
X363473Y604043D01*
X363723Y604252D01*
X363890Y604502D01*
X364015Y604835D01*
X364057Y605210D01*
X364015Y605585D01*
X363890Y605918D01*
X363723Y606168D01*
X363473Y606377D01*
X363140Y606460D01*
G01X366740Y603960D02*
Y606460D01*
X365198Y604668D01*
X367282D01*
G01X369340Y603960D02*
X369632Y604002D01*
X369965Y604127D01*
X370173Y604335D01*
X370257Y604627D01*
X370173Y604918D01*
X369923Y605168D01*
X369548Y605293D01*
X369132D01*
X368882Y605377D01*
X368673Y605585D01*
X368590Y605877D01*
X368715Y606168D01*
X369007Y606377D01*
X369340Y606460D01*
X369673Y606377D01*
X369965Y606168D01*
X370090Y605877D01*
X370007Y605585D01*
X369798Y605377D01*
X369548Y605293D01*
X369132D01*
X368757Y605168D01*
X368507Y604918D01*
X368423Y604627D01*
X368507Y604335D01*
X368715Y604127D01*
X369048Y604002D01*
X369340Y603960D01*
G01X352965Y596293D02*
X353298Y596085D01*
X353673Y595960D01*
X354007D01*
X354340Y596085D01*
X354590Y596293D01*
X354715Y596585D01*
X354632Y596877D01*
X354423Y597127D01*
X354048Y597293D01*
X353548Y597377D01*
X353257Y597543D01*
X353132Y597835D01*
X353215Y598127D01*
X353423Y598335D01*
X353715Y598460D01*
X354007D01*
X354298Y598377D01*
X354548Y598168D01*
G01X356107Y595960D02*
Y598460D01*
X357148D01*
X357482Y598335D01*
X357690Y598168D01*
X357773Y597835D01*
X357690Y597502D01*
X357440Y597293D01*
X357148Y597168D01*
X356107D01*
G01X357148D02*
X357773Y595960D01*
G01X360040D02*
Y598460D01*
X359540Y597960D01*
G01Y595960D02*
X360540D01*
G01X363140Y598460D02*
X362807Y598377D01*
X362557Y598168D01*
X362390Y597918D01*
X362265Y597585D01*
X362223Y597210D01*
X362265Y596835D01*
X362390Y596502D01*
X362557Y596252D01*
X362807Y596043D01*
X363140Y595960D01*
X363473Y596043D01*
X363723Y596252D01*
X363890Y596502D01*
X364015Y596835D01*
X364057Y597210D01*
X364015Y597585D01*
X363890Y597918D01*
X363723Y598168D01*
X363473Y598377D01*
X363140Y598460D01*
G01X366740Y595960D02*
Y598460D01*
X365198Y596668D01*
X367282D01*
G01X369257Y595960D02*
X369340Y596502D01*
X369465Y596960D01*
X369632Y597377D01*
X369840Y597835D01*
X370173Y598460D01*
X368507D01*
G01X352875Y591833D02*
X353208Y591625D01*
X353583Y591500D01*
X353917D01*
X354250Y591625D01*
X354500Y591833D01*
X354625Y592125D01*
X354542Y592417D01*
X354333Y592667D01*
X353958Y592833D01*
X353458Y592917D01*
X353167Y593083D01*
X353042Y593375D01*
X353125Y593667D01*
X353333Y593875D01*
X353625Y594000D01*
X353917D01*
X354208Y593917D01*
X354458Y593708D01*
G01X356017Y591500D02*
Y594000D01*
X357058D01*
X357392Y593875D01*
X357600Y593708D01*
X357683Y593375D01*
X357600Y593042D01*
X357350Y592833D01*
X357058Y592708D01*
X356017D01*
G01X357058D02*
X357683Y591500D01*
G01X359950D02*
Y594000D01*
X359450Y593500D01*
G01Y591500D02*
X360450D01*
G01X363050Y594000D02*
X362717Y593917D01*
X362467Y593708D01*
X362300Y593458D01*
X362175Y593125D01*
X362133Y592750D01*
X362175Y592375D01*
X362300Y592042D01*
X362467Y591792D01*
X362717Y591583D01*
X363050Y591500D01*
X363383Y591583D01*
X363633Y591792D01*
X363800Y592042D01*
X363925Y592375D01*
X363967Y592750D01*
X363925Y593125D01*
X363800Y593458D01*
X363633Y593708D01*
X363383Y593917D01*
X363050Y594000D01*
G01X366650Y591500D02*
Y594000D01*
X365108Y592208D01*
X367192D01*
G01X368542Y591792D02*
X368833Y591583D01*
X369167Y591500D01*
X369500Y591583D01*
X369792Y591833D01*
X370000Y592208D01*
X370083Y592583D01*
Y593042D01*
X370000Y593417D01*
X369792Y593750D01*
X369542Y593917D01*
X369250Y594000D01*
X368917Y593917D01*
X368667Y593750D01*
X368500Y593500D01*
X368417Y593167D01*
X368500Y592875D01*
X368708Y592583D01*
X368958Y592417D01*
X369250Y592375D01*
X369583Y592458D01*
X369833Y592667D01*
X370083Y593042D01*
G01X349507Y571460D02*
Y573960D01*
X350548D01*
X350882Y573835D01*
X351090Y573668D01*
X351173Y573335D01*
X351090Y573002D01*
X350840Y572793D01*
X350548Y572668D01*
X349507D01*
G01X350548D02*
X351173Y571460D01*
G01X353940D02*
Y573960D01*
X352398Y572168D01*
X354482D01*
G01X355748Y573543D02*
X355998Y573793D01*
X356290Y573918D01*
X356623Y573960D01*
X357040Y573877D01*
X357332Y573668D01*
X357415Y573418D01*
X357373Y573168D01*
X357207Y572960D01*
X356373Y572543D01*
X355998Y572252D01*
X355748Y571835D01*
X355665Y571460D01*
X357415D01*
G01X359557D02*
X359640Y572002D01*
X359765Y572460D01*
X359932Y572877D01*
X360140Y573335D01*
X360473Y573960D01*
X358807D01*
G01X349507Y575460D02*
Y577960D01*
X350548D01*
X350882Y577835D01*
X351090Y577668D01*
X351173Y577335D01*
X351090Y577002D01*
X350840Y576793D01*
X350548Y576668D01*
X349507D01*
G01X350548D02*
X351173Y575460D01*
G01X353940D02*
Y577960D01*
X352398Y576168D01*
X354482D01*
G01X355748Y577543D02*
X355998Y577793D01*
X356290Y577918D01*
X356623Y577960D01*
X357040Y577877D01*
X357332Y577668D01*
X357415Y577418D01*
X357373Y577168D01*
X357207Y576960D01*
X356373Y576543D01*
X355998Y576252D01*
X355748Y575835D01*
X355665Y575460D01*
X357415D01*
G01X359640D02*
X359932Y575502D01*
X360265Y575627D01*
X360473Y575835D01*
X360557Y576127D01*
X360473Y576418D01*
X360223Y576668D01*
X359848Y576793D01*
X359432D01*
X359182Y576877D01*
X358973Y577085D01*
X358890Y577377D01*
X359015Y577668D01*
X359307Y577877D01*
X359640Y577960D01*
X359973Y577877D01*
X360265Y577668D01*
X360390Y577377D01*
X360307Y577085D01*
X360098Y576877D01*
X359848Y576793D01*
X359432D01*
X359057Y576668D01*
X358807Y576418D01*
X358723Y576127D01*
X358807Y575835D01*
X359015Y575627D01*
X359348Y575502D01*
X359640Y575460D01*
G01X352875Y587833D02*
X353208Y587625D01*
X353583Y587500D01*
X353917D01*
X354250Y587625D01*
X354500Y587833D01*
X354625Y588125D01*
X354542Y588417D01*
X354333Y588667D01*
X353958Y588833D01*
X353458Y588917D01*
X353167Y589083D01*
X353042Y589375D01*
X353125Y589667D01*
X353333Y589875D01*
X353625Y590000D01*
X353917D01*
X354208Y589917D01*
X354458Y589708D01*
G01X356017Y587500D02*
Y590000D01*
X357058D01*
X357392Y589875D01*
X357600Y589708D01*
X357683Y589375D01*
X357600Y589042D01*
X357350Y588833D01*
X357058Y588708D01*
X356017D01*
G01X357058D02*
X357683Y587500D01*
G01X359950D02*
Y590000D01*
X359450Y589500D01*
G01Y587500D02*
X360450D01*
G01X363050D02*
Y590000D01*
X362550Y589500D01*
G01Y587500D02*
X363550D01*
G01X365233Y587875D02*
X365483Y587667D01*
X365775Y587542D01*
X366150Y587500D01*
X366525Y587583D01*
X366817Y587750D01*
X367025Y588042D01*
X367067Y588375D01*
X366983Y588708D01*
X366775Y588917D01*
X366483Y589083D01*
X366192Y589125D01*
X365900Y589083D01*
X365525Y588917D01*
X365650Y590000D01*
X366775D01*
G01X368333Y588000D02*
X368583Y587708D01*
X368917Y587542D01*
X369292Y587500D01*
X369625Y587542D01*
X369958Y587750D01*
X370167Y588000D01*
X370208Y588250D01*
X370125Y588542D01*
X369833Y588750D01*
X369542Y588833D01*
X369167D01*
G01X369542D02*
X369792Y588958D01*
X370000Y589167D01*
X370083Y589417D01*
X370000Y589667D01*
X369792Y589875D01*
X369417Y590000D01*
X369042Y589958D01*
X368667Y589792D01*
G01X352875Y600333D02*
X353208Y600125D01*
X353583Y600000D01*
X353917D01*
X354250Y600125D01*
X354500Y600333D01*
X354625Y600625D01*
X354542Y600917D01*
X354333Y601167D01*
X353958Y601333D01*
X353458Y601417D01*
X353167Y601583D01*
X353042Y601875D01*
X353125Y602167D01*
X353333Y602375D01*
X353625Y602500D01*
X353917D01*
X354208Y602417D01*
X354458Y602208D01*
G01X356017Y600000D02*
Y602500D01*
X357058D01*
X357392Y602375D01*
X357600Y602208D01*
X357683Y601875D01*
X357600Y601542D01*
X357350Y601333D01*
X357058Y601208D01*
X356017D01*
G01X357058D02*
X357683Y600000D01*
G01X359950D02*
Y602500D01*
X359450Y602000D01*
G01Y600000D02*
X360450D01*
G01X363050D02*
Y602500D01*
X362550Y602000D01*
G01Y600000D02*
X363550D01*
G01X365233Y600375D02*
X365483Y600167D01*
X365775Y600042D01*
X366150Y600000D01*
X366525Y600083D01*
X366817Y600250D01*
X367025Y600542D01*
X367067Y600875D01*
X366983Y601208D01*
X366775Y601417D01*
X366483Y601583D01*
X366192Y601625D01*
X365900Y601583D01*
X365525Y601417D01*
X365650Y602500D01*
X366775D01*
G01X369250Y600000D02*
Y602500D01*
X368750Y602000D01*
G01Y600000D02*
X369750D01*
G01X352257Y764033D02*
X352007Y764158D01*
X351715Y764241D01*
X351382D01*
X351007Y764116D01*
X350715Y763908D01*
X350507Y763658D01*
X350340Y763241D01*
X350298Y762866D01*
X350382Y762491D01*
X350507Y762241D01*
X350757Y761991D01*
X351048Y761824D01*
X351340Y761741D01*
X351632D01*
X351923Y761824D01*
X352173Y761949D01*
X352382Y762116D01*
G01X353732Y762033D02*
X354023Y761824D01*
X354357Y761741D01*
X354690Y761824D01*
X354982Y762074D01*
X355190Y762449D01*
X355273Y762824D01*
Y763283D01*
X355190Y763658D01*
X354982Y763991D01*
X354732Y764158D01*
X354440Y764241D01*
X354107Y764158D01*
X353857Y763991D01*
X353690Y763741D01*
X353607Y763408D01*
X353690Y763116D01*
X353898Y762824D01*
X354148Y762658D01*
X354440Y762616D01*
X354773Y762699D01*
X355023Y762908D01*
X355273Y763283D01*
G01X356623Y762241D02*
X356873Y761949D01*
X357207Y761783D01*
X357582Y761741D01*
X357915Y761783D01*
X358248Y761991D01*
X358457Y762241D01*
X358498Y762491D01*
X358415Y762783D01*
X358123Y762991D01*
X357832Y763074D01*
X357457D01*
G01X357832D02*
X358082Y763199D01*
X358290Y763408D01*
X358373Y763658D01*
X358290Y763908D01*
X358082Y764116D01*
X357707Y764241D01*
X357332Y764199D01*
X356957Y764033D01*
G01X361140Y761741D02*
Y764241D01*
X359598Y762449D01*
X361682D01*
G01X363740Y761741D02*
Y764241D01*
X363240Y763741D01*
G01Y761741D02*
X364240D01*
G01X375707Y763333D02*
X375457Y763458D01*
X375165Y763541D01*
X374832D01*
X374457Y763416D01*
X374165Y763208D01*
X373957Y762958D01*
X373790Y762541D01*
X373748Y762166D01*
X373832Y761791D01*
X373957Y761541D01*
X374207Y761291D01*
X374498Y761124D01*
X374790Y761041D01*
X375082D01*
X375373Y761124D01*
X375623Y761249D01*
X375832Y761416D01*
G01X377182Y761333D02*
X377473Y761124D01*
X377807Y761041D01*
X378140Y761124D01*
X378432Y761374D01*
X378640Y761749D01*
X378723Y762124D01*
Y762583D01*
X378640Y762958D01*
X378432Y763291D01*
X378182Y763458D01*
X377890Y763541D01*
X377557Y763458D01*
X377307Y763291D01*
X377140Y763041D01*
X377057Y762708D01*
X377140Y762416D01*
X377348Y762124D01*
X377598Y761958D01*
X377890Y761916D01*
X378223Y761999D01*
X378473Y762208D01*
X378723Y762583D01*
G01X380073Y761541D02*
X380323Y761249D01*
X380657Y761083D01*
X381032Y761041D01*
X381365Y761083D01*
X381698Y761291D01*
X381907Y761541D01*
X381948Y761791D01*
X381865Y762083D01*
X381573Y762291D01*
X381282Y762374D01*
X380907D01*
G01X381282D02*
X381532Y762499D01*
X381740Y762708D01*
X381823Y762958D01*
X381740Y763208D01*
X381532Y763416D01*
X381157Y763541D01*
X380782Y763499D01*
X380407Y763333D01*
G01X383298Y762083D02*
X383590Y762374D01*
X383840Y762541D01*
X384173Y762624D01*
X384465Y762541D01*
X384673Y762374D01*
X384840Y762124D01*
X384882Y761833D01*
X384840Y761583D01*
X384673Y761333D01*
X384423Y761124D01*
X384132Y761041D01*
X383798Y761124D01*
X383507Y761374D01*
X383340Y761749D01*
X383298Y762166D01*
X383382Y762708D01*
X383507Y762999D01*
X383715Y763291D01*
X384007Y763499D01*
X384298Y763541D01*
X384590Y763458D01*
X384798Y763249D01*
G01X386398Y762083D02*
X386690Y762374D01*
X386940Y762541D01*
X387273Y762624D01*
X387565Y762541D01*
X387773Y762374D01*
X387940Y762124D01*
X387982Y761833D01*
X387940Y761583D01*
X387773Y761333D01*
X387523Y761124D01*
X387232Y761041D01*
X386898Y761124D01*
X386607Y761374D01*
X386440Y761749D01*
X386398Y762166D01*
X386482Y762708D01*
X386607Y762999D01*
X386815Y763291D01*
X387107Y763499D01*
X387398Y763541D01*
X387690Y763458D01*
X387898Y763249D01*
G01X350887Y740851D02*
Y743351D01*
X351928D01*
X352262Y743226D01*
X352470Y743059D01*
X352553Y742726D01*
X352470Y742393D01*
X352220Y742184D01*
X351928Y742059D01*
X350887D01*
G01X351928D02*
X352553Y740851D01*
G01X354112Y741143D02*
X354403Y740934D01*
X354737Y740851D01*
X355070Y740934D01*
X355362Y741184D01*
X355570Y741559D01*
X355653Y741934D01*
Y742393D01*
X355570Y742768D01*
X355362Y743101D01*
X355112Y743268D01*
X354820Y743351D01*
X354487Y743268D01*
X354237Y743101D01*
X354070Y742851D01*
X353987Y742518D01*
X354070Y742226D01*
X354278Y741934D01*
X354528Y741768D01*
X354820Y741726D01*
X355153Y741809D01*
X355403Y742018D01*
X355653Y742393D01*
G01X358420Y740851D02*
Y743351D01*
X356878Y741559D01*
X358962D01*
G01X361020Y743351D02*
X360687Y743268D01*
X360437Y743059D01*
X360270Y742809D01*
X360145Y742476D01*
X360103Y742101D01*
X360145Y741726D01*
X360270Y741393D01*
X360437Y741143D01*
X360687Y740934D01*
X361020Y740851D01*
X361353Y740934D01*
X361603Y741143D01*
X361770Y741393D01*
X361895Y741726D01*
X361937Y742101D01*
X361895Y742476D01*
X361770Y742809D01*
X361603Y743059D01*
X361353Y743268D01*
X361020Y743351D01*
G01X363412Y741143D02*
X363703Y740934D01*
X364037Y740851D01*
X364370Y740934D01*
X364662Y741184D01*
X364870Y741559D01*
X364953Y741934D01*
Y742393D01*
X364870Y742768D01*
X364662Y743101D01*
X364412Y743268D01*
X364120Y743351D01*
X363787Y743268D01*
X363537Y743101D01*
X363370Y742851D01*
X363287Y742518D01*
X363370Y742226D01*
X363578Y741934D01*
X363828Y741768D01*
X364120Y741726D01*
X364453Y741809D01*
X364703Y742018D01*
X364953Y742393D01*
G01X379200Y769000D02*
Y773000D01*
X371800D01*
G01X374337Y740151D02*
Y742651D01*
X375378D01*
X375712Y742526D01*
X375920Y742359D01*
X376003Y742026D01*
X375920Y741693D01*
X375670Y741484D01*
X375378Y741359D01*
X374337D01*
G01X375378D02*
X376003Y740151D01*
G01X377562Y740443D02*
X377853Y740234D01*
X378187Y740151D01*
X378520Y740234D01*
X378812Y740484D01*
X379020Y740859D01*
X379103Y741234D01*
Y741693D01*
X379020Y742068D01*
X378812Y742401D01*
X378562Y742568D01*
X378270Y742651D01*
X377937Y742568D01*
X377687Y742401D01*
X377520Y742151D01*
X377437Y741818D01*
X377520Y741526D01*
X377728Y741234D01*
X377978Y741068D01*
X378270Y741026D01*
X378603Y741109D01*
X378853Y741318D01*
X379103Y741693D01*
G01X381870Y740151D02*
Y742651D01*
X380328Y740859D01*
X382412D01*
G01X383762Y740443D02*
X384053Y740234D01*
X384387Y740151D01*
X384720Y740234D01*
X385012Y740484D01*
X385220Y740859D01*
X385303Y741234D01*
Y741693D01*
X385220Y742068D01*
X385012Y742401D01*
X384762Y742568D01*
X384470Y742651D01*
X384137Y742568D01*
X383887Y742401D01*
X383720Y742151D01*
X383637Y741818D01*
X383720Y741526D01*
X383928Y741234D01*
X384178Y741068D01*
X384470Y741026D01*
X384803Y741109D01*
X385053Y741318D01*
X385303Y741693D01*
G01X386778Y741193D02*
X387070Y741484D01*
X387320Y741651D01*
X387653Y741734D01*
X387945Y741651D01*
X388153Y741484D01*
X388320Y741234D01*
X388362Y740943D01*
X388320Y740693D01*
X388153Y740443D01*
X387903Y740234D01*
X387612Y740151D01*
X387278Y740234D01*
X386987Y740484D01*
X386820Y740859D01*
X386778Y741276D01*
X386862Y741818D01*
X386987Y742109D01*
X387195Y742401D01*
X387487Y742609D01*
X387778Y742651D01*
X388070Y742568D01*
X388278Y742359D01*
G01X387200Y769000D02*
Y773000D01*
X379800D01*
G01X379834Y744967D02*
X377334D01*
Y746008D01*
X377459Y746342D01*
X377626Y746550D01*
X377959Y746633D01*
X378292Y746550D01*
X378501Y746300D01*
X378626Y746008D01*
Y744967D01*
G01Y746008D02*
X379834Y746633D01*
G01X379542Y748192D02*
X379751Y748483D01*
X379834Y748817D01*
X379751Y749150D01*
X379501Y749442D01*
X379126Y749650D01*
X378751Y749733D01*
X378292D01*
X377917Y749650D01*
X377584Y749442D01*
X377417Y749192D01*
X377334Y748900D01*
X377417Y748567D01*
X377584Y748317D01*
X377834Y748150D01*
X378167Y748067D01*
X378459Y748150D01*
X378751Y748358D01*
X378917Y748608D01*
X378959Y748900D01*
X378876Y749233D01*
X378667Y749483D01*
X378292Y749733D01*
G01X379459Y751083D02*
X379667Y751333D01*
X379792Y751625D01*
X379834Y752000D01*
X379751Y752375D01*
X379584Y752667D01*
X379292Y752875D01*
X378959Y752917D01*
X378626Y752833D01*
X378417Y752625D01*
X378251Y752333D01*
X378209Y752042D01*
X378251Y751750D01*
X378417Y751375D01*
X377334Y751500D01*
Y752625D01*
G01X379542Y754392D02*
X379751Y754683D01*
X379834Y755017D01*
X379751Y755350D01*
X379501Y755642D01*
X379126Y755850D01*
X378751Y755933D01*
X378292D01*
X377917Y755850D01*
X377584Y755642D01*
X377417Y755392D01*
X377334Y755100D01*
X377417Y754767D01*
X377584Y754517D01*
X377834Y754350D01*
X378167Y754267D01*
X378459Y754350D01*
X378751Y754558D01*
X378917Y754808D01*
X378959Y755100D01*
X378876Y755433D01*
X378667Y755683D01*
X378292Y755933D01*
G01X379834Y758117D02*
X379292Y758200D01*
X378834Y758325D01*
X378417Y758492D01*
X377959Y758700D01*
X377334Y759033D01*
Y757367D01*
G01X380000Y773300D02*
X384000D01*
Y780700D01*
G01X357919Y745347D02*
X355419D01*
Y746388D01*
X355544Y746722D01*
X355711Y746930D01*
X356044Y747013D01*
X356377Y746930D01*
X356586Y746680D01*
X356711Y746388D01*
Y745347D01*
G01Y746388D02*
X357919Y747013D01*
G01X357627Y748572D02*
X357836Y748863D01*
X357919Y749197D01*
X357836Y749530D01*
X357586Y749822D01*
X357211Y750030D01*
X356836Y750113D01*
X356377D01*
X356002Y750030D01*
X355669Y749822D01*
X355502Y749572D01*
X355419Y749280D01*
X355502Y748947D01*
X355669Y748697D01*
X355919Y748530D01*
X356252Y748447D01*
X356544Y748530D01*
X356836Y748738D01*
X357002Y748988D01*
X357044Y749280D01*
X356961Y749613D01*
X356752Y749863D01*
X356377Y750113D01*
G01X357544Y751463D02*
X357752Y751713D01*
X357877Y752005D01*
X357919Y752380D01*
X357836Y752755D01*
X357669Y753047D01*
X357377Y753255D01*
X357044Y753297D01*
X356711Y753213D01*
X356502Y753005D01*
X356336Y752713D01*
X356294Y752422D01*
X356336Y752130D01*
X356502Y751755D01*
X355419Y751880D01*
Y753005D01*
G01X357627Y754772D02*
X357836Y755063D01*
X357919Y755397D01*
X357836Y755730D01*
X357586Y756022D01*
X357211Y756230D01*
X356836Y756313D01*
X356377D01*
X356002Y756230D01*
X355669Y756022D01*
X355502Y755772D01*
X355419Y755480D01*
X355502Y755147D01*
X355669Y754897D01*
X355919Y754730D01*
X356252Y754647D01*
X356544Y754730D01*
X356836Y754938D01*
X357002Y755188D01*
X357044Y755480D01*
X356961Y755813D01*
X356752Y756063D01*
X356377Y756313D01*
G01X356877Y757788D02*
X356586Y758080D01*
X356419Y758330D01*
X356336Y758663D01*
X356419Y758955D01*
X356586Y759163D01*
X356836Y759330D01*
X357127Y759372D01*
X357377Y759330D01*
X357627Y759163D01*
X357836Y758913D01*
X357919Y758622D01*
X357836Y758288D01*
X357586Y757997D01*
X357211Y757830D01*
X356794Y757788D01*
X356252Y757872D01*
X355961Y757997D01*
X355669Y758205D01*
X355461Y758497D01*
X355419Y758788D01*
X355502Y759080D01*
X355711Y759288D01*
G01X372000Y773300D02*
X376000D01*
Y780700D01*
G01X348887Y791507D02*
X348762Y791257D01*
X348679Y790965D01*
Y790632D01*
X348804Y790257D01*
X349012Y789965D01*
X349262Y789757D01*
X349679Y789590D01*
X350054Y789548D01*
X350429Y789632D01*
X350679Y789757D01*
X350929Y790007D01*
X351096Y790298D01*
X351179Y790590D01*
Y790882D01*
X351096Y791173D01*
X350971Y791423D01*
X350804Y791632D01*
G01X350887Y792982D02*
X351096Y793273D01*
X351179Y793607D01*
X351096Y793940D01*
X350846Y794232D01*
X350471Y794440D01*
X350096Y794523D01*
X349637D01*
X349262Y794440D01*
X348929Y794232D01*
X348762Y793982D01*
X348679Y793690D01*
X348762Y793357D01*
X348929Y793107D01*
X349179Y792940D01*
X349512Y792857D01*
X349804Y792940D01*
X350096Y793148D01*
X350262Y793398D01*
X350304Y793690D01*
X350221Y794023D01*
X350012Y794273D01*
X349637Y794523D01*
G01X351179Y797290D02*
X348679D01*
X350471Y795748D01*
Y797832D01*
G01X349096Y799098D02*
X348846Y799348D01*
X348721Y799640D01*
X348679Y799973D01*
X348762Y800390D01*
X348971Y800682D01*
X349221Y800765D01*
X349471Y800723D01*
X349679Y800557D01*
X350096Y799723D01*
X350387Y799348D01*
X350804Y799098D01*
X351179Y799015D01*
Y800765D01*
G01X350887Y802282D02*
X351096Y802573D01*
X351179Y802907D01*
X351096Y803240D01*
X350846Y803532D01*
X350471Y803740D01*
X350096Y803823D01*
X349637D01*
X349262Y803740D01*
X348929Y803532D01*
X348762Y803282D01*
X348679Y802990D01*
X348762Y802657D01*
X348929Y802407D01*
X349179Y802240D01*
X349512Y802157D01*
X349804Y802240D01*
X350096Y802448D01*
X350262Y802698D01*
X350304Y802990D01*
X350221Y803323D01*
X350012Y803573D01*
X349637Y803823D01*
G01X393717Y800792D02*
X393467Y800917D01*
X393175Y801000D01*
X392842D01*
X392467Y800875D01*
X392175Y800667D01*
X391967Y800417D01*
X391800Y800000D01*
X391758Y799625D01*
X391842Y799250D01*
X391967Y799000D01*
X392217Y798750D01*
X392508Y798583D01*
X392800Y798500D01*
X393092D01*
X393383Y798583D01*
X393633Y798708D01*
X393842Y798875D01*
G01X395900Y798500D02*
X396192Y798542D01*
X396525Y798667D01*
X396733Y798875D01*
X396817Y799167D01*
X396733Y799458D01*
X396483Y799708D01*
X396108Y799833D01*
X395692D01*
X395442Y799917D01*
X395233Y800125D01*
X395150Y800417D01*
X395275Y800708D01*
X395567Y800917D01*
X395900Y801000D01*
X396233Y800917D01*
X396525Y800708D01*
X396650Y800417D01*
X396567Y800125D01*
X396358Y799917D01*
X396108Y799833D01*
X395692D01*
X395317Y799708D01*
X395067Y799458D01*
X394983Y799167D01*
X395067Y798875D01*
X395275Y798667D01*
X395608Y798542D01*
X395900Y798500D01*
G01X399000D02*
X399292Y798542D01*
X399625Y798667D01*
X399833Y798875D01*
X399917Y799167D01*
X399833Y799458D01*
X399583Y799708D01*
X399208Y799833D01*
X398792D01*
X398542Y799917D01*
X398333Y800125D01*
X398250Y800417D01*
X398375Y800708D01*
X398667Y800917D01*
X399000Y801000D01*
X399333Y800917D01*
X399625Y800708D01*
X399750Y800417D01*
X399667Y800125D01*
X399458Y799917D01*
X399208Y799833D01*
X398792D01*
X398417Y799708D01*
X398167Y799458D01*
X398083Y799167D01*
X398167Y798875D01*
X398375Y798667D01*
X398708Y798542D01*
X399000Y798500D01*
G01X401308Y799542D02*
X401600Y799833D01*
X401850Y800000D01*
X402183Y800083D01*
X402475Y800000D01*
X402683Y799833D01*
X402850Y799583D01*
X402892Y799292D01*
X402850Y799042D01*
X402683Y798792D01*
X402433Y798583D01*
X402142Y798500D01*
X401808Y798583D01*
X401517Y798833D01*
X401350Y799208D01*
X401308Y799625D01*
X401392Y800167D01*
X401517Y800458D01*
X401725Y800750D01*
X402017Y800958D01*
X402308Y801000D01*
X402600Y800917D01*
X402808Y800708D01*
G01X404283Y799000D02*
X404533Y798708D01*
X404867Y798542D01*
X405242Y798500D01*
X405575Y798542D01*
X405908Y798750D01*
X406117Y799000D01*
X406158Y799250D01*
X406075Y799542D01*
X405783Y799750D01*
X405492Y799833D01*
X405117D01*
G01X405492D02*
X405742Y799958D01*
X405950Y800167D01*
X406033Y800417D01*
X405950Y800667D01*
X405742Y800875D01*
X405367Y801000D01*
X404992Y800958D01*
X404617Y800792D01*
G01X352927Y791427D02*
X352802Y791177D01*
X352719Y790885D01*
Y790552D01*
X352844Y790177D01*
X353052Y789885D01*
X353302Y789677D01*
X353719Y789510D01*
X354094Y789468D01*
X354469Y789552D01*
X354719Y789677D01*
X354969Y789927D01*
X355136Y790218D01*
X355219Y790510D01*
Y790802D01*
X355136Y791093D01*
X355011Y791343D01*
X354844Y791552D01*
G01X355219Y793610D02*
X355177Y793902D01*
X355052Y794235D01*
X354844Y794443D01*
X354552Y794527D01*
X354261Y794443D01*
X354011Y794193D01*
X353886Y793818D01*
Y793402D01*
X353802Y793152D01*
X353594Y792943D01*
X353302Y792860D01*
X353011Y792985D01*
X352802Y793277D01*
X352719Y793610D01*
X352802Y793943D01*
X353011Y794235D01*
X353302Y794360D01*
X353594Y794277D01*
X353802Y794068D01*
X353886Y793818D01*
Y793402D01*
X354011Y793027D01*
X354261Y792777D01*
X354552Y792693D01*
X354844Y792777D01*
X355052Y792985D01*
X355177Y793318D01*
X355219Y793610D01*
G01Y796710D02*
X355177Y797002D01*
X355052Y797335D01*
X354844Y797543D01*
X354552Y797627D01*
X354261Y797543D01*
X354011Y797293D01*
X353886Y796918D01*
Y796502D01*
X353802Y796252D01*
X353594Y796043D01*
X353302Y795960D01*
X353011Y796085D01*
X352802Y796377D01*
X352719Y796710D01*
X352802Y797043D01*
X353011Y797335D01*
X353302Y797460D01*
X353594Y797377D01*
X353802Y797168D01*
X353886Y796918D01*
Y796502D01*
X354011Y796127D01*
X354261Y795877D01*
X354552Y795793D01*
X354844Y795877D01*
X355052Y796085D01*
X355177Y796418D01*
X355219Y796710D01*
G01X354177Y799018D02*
X353886Y799310D01*
X353719Y799560D01*
X353636Y799893D01*
X353719Y800185D01*
X353886Y800393D01*
X354136Y800560D01*
X354427Y800602D01*
X354677Y800560D01*
X354927Y800393D01*
X355136Y800143D01*
X355219Y799852D01*
X355136Y799518D01*
X354886Y799227D01*
X354511Y799060D01*
X354094Y799018D01*
X353552Y799102D01*
X353261Y799227D01*
X352969Y799435D01*
X352761Y799727D01*
X352719Y800018D01*
X352802Y800310D01*
X353011Y800518D01*
G01X355219Y803410D02*
X352719D01*
X354511Y801868D01*
Y803952D01*
G01X340200Y821000D02*
Y825000D01*
X332800D01*
G01X400300Y822000D02*
Y818000D01*
X407700D01*
G01X400300Y807000D02*
Y803000D01*
X407700D01*
G01X400300Y826000D02*
Y822000D01*
X407700D01*
G01X395349Y782137D02*
X392849D01*
Y783178D01*
X392974Y783512D01*
X393141Y783720D01*
X393474Y783803D01*
X393807Y783720D01*
X394016Y783470D01*
X394141Y783178D01*
Y782137D01*
G01Y783178D02*
X395349Y783803D01*
G01X395057Y785362D02*
X395266Y785653D01*
X395349Y785987D01*
X395266Y786320D01*
X395016Y786612D01*
X394641Y786820D01*
X394266Y786903D01*
X393807D01*
X393432Y786820D01*
X393099Y786612D01*
X392932Y786362D01*
X392849Y786070D01*
X392932Y785737D01*
X393099Y785487D01*
X393349Y785320D01*
X393682Y785237D01*
X393974Y785320D01*
X394266Y785528D01*
X394432Y785778D01*
X394474Y786070D01*
X394391Y786403D01*
X394182Y786653D01*
X393807Y786903D01*
G01X392849Y789170D02*
X392932Y788837D01*
X393141Y788587D01*
X393391Y788420D01*
X393724Y788295D01*
X394099Y788253D01*
X394474Y788295D01*
X394807Y788420D01*
X395057Y788587D01*
X395266Y788837D01*
X395349Y789170D01*
X395266Y789503D01*
X395057Y789753D01*
X394807Y789920D01*
X394474Y790045D01*
X394099Y790087D01*
X393724Y790045D01*
X393391Y789920D01*
X393141Y789753D01*
X392932Y789503D01*
X392849Y789170D01*
G01X395349Y792270D02*
X395307Y792562D01*
X395182Y792895D01*
X394974Y793103D01*
X394682Y793187D01*
X394391Y793103D01*
X394141Y792853D01*
X394016Y792478D01*
Y792062D01*
X393932Y791812D01*
X393724Y791603D01*
X393432Y791520D01*
X393141Y791645D01*
X392932Y791937D01*
X392849Y792270D01*
X392932Y792603D01*
X393141Y792895D01*
X393432Y793020D01*
X393724Y792937D01*
X393932Y792728D01*
X394016Y792478D01*
Y792062D01*
X394141Y791687D01*
X394391Y791437D01*
X394682Y791353D01*
X394974Y791437D01*
X395182Y791645D01*
X395307Y791978D01*
X395349Y792270D01*
G01Y795870D02*
X392849D01*
X394641Y794328D01*
Y796412D01*
G01X386500Y799700D02*
X382500D01*
Y792300D01*
G01X400300Y811000D02*
Y807000D01*
X407700D01*
G01X399349Y782137D02*
X396849D01*
Y783178D01*
X396974Y783512D01*
X397141Y783720D01*
X397474Y783803D01*
X397807Y783720D01*
X398016Y783470D01*
X398141Y783178D01*
Y782137D01*
G01Y783178D02*
X399349Y783803D01*
G01X399057Y785362D02*
X399266Y785653D01*
X399349Y785987D01*
X399266Y786320D01*
X399016Y786612D01*
X398641Y786820D01*
X398266Y786903D01*
X397807D01*
X397432Y786820D01*
X397099Y786612D01*
X396932Y786362D01*
X396849Y786070D01*
X396932Y785737D01*
X397099Y785487D01*
X397349Y785320D01*
X397682Y785237D01*
X397974Y785320D01*
X398266Y785528D01*
X398432Y785778D01*
X398474Y786070D01*
X398391Y786403D01*
X398182Y786653D01*
X397807Y786903D01*
G01X396849Y789170D02*
X396932Y788837D01*
X397141Y788587D01*
X397391Y788420D01*
X397724Y788295D01*
X398099Y788253D01*
X398474Y788295D01*
X398807Y788420D01*
X399057Y788587D01*
X399266Y788837D01*
X399349Y789170D01*
X399266Y789503D01*
X399057Y789753D01*
X398807Y789920D01*
X398474Y790045D01*
X398099Y790087D01*
X397724Y790045D01*
X397391Y789920D01*
X397141Y789753D01*
X396932Y789503D01*
X396849Y789170D01*
G01X399349Y792270D02*
X399307Y792562D01*
X399182Y792895D01*
X398974Y793103D01*
X398682Y793187D01*
X398391Y793103D01*
X398141Y792853D01*
X398016Y792478D01*
Y792062D01*
X397932Y791812D01*
X397724Y791603D01*
X397432Y791520D01*
X397141Y791645D01*
X396932Y791937D01*
X396849Y792270D01*
X396932Y792603D01*
X397141Y792895D01*
X397432Y793020D01*
X397724Y792937D01*
X397932Y792728D01*
X398016Y792478D01*
Y792062D01*
X398141Y791687D01*
X398391Y791437D01*
X398682Y791353D01*
X398974Y791437D01*
X399182Y791645D01*
X399307Y791978D01*
X399349Y792270D01*
G01X398307Y794578D02*
X398016Y794870D01*
X397849Y795120D01*
X397766Y795453D01*
X397849Y795745D01*
X398016Y795953D01*
X398266Y796120D01*
X398557Y796162D01*
X398807Y796120D01*
X399057Y795953D01*
X399266Y795703D01*
X399349Y795412D01*
X399266Y795078D01*
X399016Y794787D01*
X398641Y794620D01*
X398224Y794578D01*
X397682Y794662D01*
X397391Y794787D01*
X397099Y794995D01*
X396891Y795287D01*
X396849Y795578D01*
X396932Y795870D01*
X397141Y796078D01*
G01X390500Y799700D02*
X386500D01*
Y792300D01*
G01X362179Y777007D02*
X359679D01*
Y778048D01*
X359804Y778382D01*
X359971Y778590D01*
X360304Y778673D01*
X360637Y778590D01*
X360846Y778340D01*
X360971Y778048D01*
Y777007D01*
G01Y778048D02*
X362179Y778673D01*
G01X361887Y780232D02*
X362096Y780523D01*
X362179Y780857D01*
X362096Y781190D01*
X361846Y781482D01*
X361471Y781690D01*
X361096Y781773D01*
X360637D01*
X360262Y781690D01*
X359929Y781482D01*
X359762Y781232D01*
X359679Y780940D01*
X359762Y780607D01*
X359929Y780357D01*
X360179Y780190D01*
X360512Y780107D01*
X360804Y780190D01*
X361096Y780398D01*
X361262Y780648D01*
X361304Y780940D01*
X361221Y781273D01*
X361012Y781523D01*
X360637Y781773D01*
G01X359679Y784040D02*
X359762Y783707D01*
X359971Y783457D01*
X360221Y783290D01*
X360554Y783165D01*
X360929Y783123D01*
X361304Y783165D01*
X361637Y783290D01*
X361887Y783457D01*
X362096Y783707D01*
X362179Y784040D01*
X362096Y784373D01*
X361887Y784623D01*
X361637Y784790D01*
X361304Y784915D01*
X360929Y784957D01*
X360554Y784915D01*
X360221Y784790D01*
X359971Y784623D01*
X359762Y784373D01*
X359679Y784040D01*
G01X362179Y787140D02*
X362137Y787432D01*
X362012Y787765D01*
X361804Y787973D01*
X361512Y788057D01*
X361221Y787973D01*
X360971Y787723D01*
X360846Y787348D01*
Y786932D01*
X360762Y786682D01*
X360554Y786473D01*
X360262Y786390D01*
X359971Y786515D01*
X359762Y786807D01*
X359679Y787140D01*
X359762Y787473D01*
X359971Y787765D01*
X360262Y787890D01*
X360554Y787807D01*
X360762Y787598D01*
X360846Y787348D01*
Y786932D01*
X360971Y786557D01*
X361221Y786307D01*
X361512Y786223D01*
X361804Y786307D01*
X362012Y786515D01*
X362137Y786848D01*
X362179Y787140D01*
G01Y790157D02*
X361637Y790240D01*
X361179Y790365D01*
X360762Y790532D01*
X360304Y790740D01*
X359679Y791073D01*
Y789407D01*
G01X371500Y799700D02*
X367500D01*
Y792300D01*
G01X366179Y777007D02*
X363679D01*
Y778048D01*
X363804Y778382D01*
X363971Y778590D01*
X364304Y778673D01*
X364637Y778590D01*
X364846Y778340D01*
X364971Y778048D01*
Y777007D01*
G01Y778048D02*
X366179Y778673D01*
G01X365887Y780232D02*
X366096Y780523D01*
X366179Y780857D01*
X366096Y781190D01*
X365846Y781482D01*
X365471Y781690D01*
X365096Y781773D01*
X364637D01*
X364262Y781690D01*
X363929Y781482D01*
X363762Y781232D01*
X363679Y780940D01*
X363762Y780607D01*
X363929Y780357D01*
X364179Y780190D01*
X364512Y780107D01*
X364804Y780190D01*
X365096Y780398D01*
X365262Y780648D01*
X365304Y780940D01*
X365221Y781273D01*
X365012Y781523D01*
X364637Y781773D01*
G01X363679Y784040D02*
X363762Y783707D01*
X363971Y783457D01*
X364221Y783290D01*
X364554Y783165D01*
X364929Y783123D01*
X365304Y783165D01*
X365637Y783290D01*
X365887Y783457D01*
X366096Y783707D01*
X366179Y784040D01*
X366096Y784373D01*
X365887Y784623D01*
X365637Y784790D01*
X365304Y784915D01*
X364929Y784957D01*
X364554Y784915D01*
X364221Y784790D01*
X363971Y784623D01*
X363762Y784373D01*
X363679Y784040D01*
G01X366179Y787140D02*
X366137Y787432D01*
X366012Y787765D01*
X365804Y787973D01*
X365512Y788057D01*
X365221Y787973D01*
X364971Y787723D01*
X364846Y787348D01*
Y786932D01*
X364762Y786682D01*
X364554Y786473D01*
X364262Y786390D01*
X363971Y786515D01*
X363762Y786807D01*
X363679Y787140D01*
X363762Y787473D01*
X363971Y787765D01*
X364262Y787890D01*
X364554Y787807D01*
X364762Y787598D01*
X364846Y787348D01*
Y786932D01*
X364971Y786557D01*
X365221Y786307D01*
X365512Y786223D01*
X365804Y786307D01*
X366012Y786515D01*
X366137Y786848D01*
X366179Y787140D01*
G01Y790240D02*
X366137Y790532D01*
X366012Y790865D01*
X365804Y791073D01*
X365512Y791157D01*
X365221Y791073D01*
X364971Y790823D01*
X364846Y790448D01*
Y790032D01*
X364762Y789782D01*
X364554Y789573D01*
X364262Y789490D01*
X363971Y789615D01*
X363762Y789907D01*
X363679Y790240D01*
X363762Y790573D01*
X363971Y790865D01*
X364262Y790990D01*
X364554Y790907D01*
X364762Y790698D01*
X364846Y790448D01*
Y790032D01*
X364971Y789657D01*
X365221Y789407D01*
X365512Y789323D01*
X365804Y789407D01*
X366012Y789615D01*
X366137Y789948D01*
X366179Y790240D01*
G01X375500Y799700D02*
X371500D01*
Y792300D01*
G01X332800Y821000D02*
Y817000D01*
X340200D01*
G01X402700Y838500D02*
Y842500D01*
X395300D01*
G01X395800Y847000D02*
X404500D01*
G01X395800Y854000D02*
Y847000D01*
G01X340463Y840480D02*
X338797D01*
Y842980D01*
X340463D01*
G01X339797Y841772D02*
X338797D01*
G01X341813Y842980D02*
Y841188D01*
X341980Y840813D01*
X342313Y840563D01*
X342730Y840480D01*
X343147Y840563D01*
X343480Y840813D01*
X343647Y841188D01*
Y842980D01*
G01X344913Y840980D02*
X345163Y840688D01*
X345497Y840522D01*
X345872Y840480D01*
X346205Y840522D01*
X346538Y840730D01*
X346747Y840980D01*
X346788Y841230D01*
X346705Y841522D01*
X346413Y841730D01*
X346122Y841813D01*
X345747D01*
G01X346122D02*
X346372Y841938D01*
X346580Y842147D01*
X346663Y842397D01*
X346580Y842647D01*
X346372Y842855D01*
X345997Y842980D01*
X345622Y842938D01*
X345247Y842772D01*
G01X391650Y846050D02*
Y851700D01*
X385700D01*
G01X386200Y808350D02*
X391700D01*
Y813450D01*
G01X348300Y814300D02*
Y808300D01*
X354550D01*
G01X380800Y806485D02*
Y809485D01*
G01X361100Y806485D02*
Y809485D01*
G01X371000D02*
Y807485D01*
G01X390515Y838800D02*
X392515D01*
G01X390515Y819200D02*
X392515D01*
G01X393515Y827100D02*
X390515D01*
G01X347485Y817150D02*
X349485D01*
G01X347485Y836900D02*
X349485D01*
G01Y827085D02*
X346485D01*
G01X364068Y869267D02*
X363943Y869017D01*
X363860Y868725D01*
Y868392D01*
X363985Y868017D01*
X364193Y867725D01*
X364443Y867517D01*
X364860Y867350D01*
X365235Y867308D01*
X365610Y867392D01*
X365860Y867517D01*
X366110Y867767D01*
X366277Y868058D01*
X366360Y868350D01*
Y868642D01*
X366277Y868933D01*
X366152Y869183D01*
X365985Y869392D01*
G01X366068Y870742D02*
X366277Y871033D01*
X366360Y871367D01*
X366277Y871700D01*
X366027Y871992D01*
X365652Y872200D01*
X365277Y872283D01*
X364818D01*
X364443Y872200D01*
X364110Y871992D01*
X363943Y871742D01*
X363860Y871450D01*
X363943Y871117D01*
X364110Y870867D01*
X364360Y870700D01*
X364693Y870617D01*
X364985Y870700D01*
X365277Y870908D01*
X365443Y871158D01*
X365485Y871450D01*
X365402Y871783D01*
X365193Y872033D01*
X364818Y872283D01*
G01X366360Y875050D02*
X363860D01*
X365652Y873508D01*
Y875592D01*
G01X364277Y876858D02*
X364027Y877108D01*
X363902Y877400D01*
X363860Y877733D01*
X363943Y878150D01*
X364152Y878442D01*
X364402Y878525D01*
X364652Y878483D01*
X364860Y878317D01*
X365277Y877483D01*
X365568Y877108D01*
X365985Y876858D01*
X366360Y876775D01*
Y878525D01*
G01Y880750D02*
X366318Y881042D01*
X366193Y881375D01*
X365985Y881583D01*
X365693Y881667D01*
X365402Y881583D01*
X365152Y881333D01*
X365027Y880958D01*
Y880542D01*
X364943Y880292D01*
X364735Y880083D01*
X364443Y880000D01*
X364152Y880125D01*
X363943Y880417D01*
X363860Y880750D01*
X363943Y881083D01*
X364152Y881375D01*
X364443Y881500D01*
X364735Y881417D01*
X364943Y881208D01*
X365027Y880958D01*
Y880542D01*
X365152Y880167D01*
X365402Y879917D01*
X365693Y879833D01*
X365985Y879917D01*
X366193Y880125D01*
X366318Y880458D01*
X366360Y880750D01*
G01X402117Y884492D02*
X401867Y884617D01*
X401575Y884700D01*
X401242D01*
X400867Y884575D01*
X400575Y884367D01*
X400367Y884117D01*
X400200Y883700D01*
X400158Y883325D01*
X400242Y882950D01*
X400367Y882700D01*
X400617Y882450D01*
X400908Y882283D01*
X401200Y882200D01*
X401492D01*
X401783Y882283D01*
X402033Y882408D01*
X402242Y882575D01*
G01X403592Y882492D02*
X403883Y882283D01*
X404217Y882200D01*
X404550Y882283D01*
X404842Y882533D01*
X405050Y882908D01*
X405133Y883283D01*
Y883742D01*
X405050Y884117D01*
X404842Y884450D01*
X404592Y884617D01*
X404300Y884700D01*
X403967Y884617D01*
X403717Y884450D01*
X403550Y884200D01*
X403467Y883867D01*
X403550Y883575D01*
X403758Y883283D01*
X404008Y883117D01*
X404300Y883075D01*
X404633Y883158D01*
X404883Y883367D01*
X405133Y883742D01*
G01X406483Y882700D02*
X406733Y882408D01*
X407067Y882242D01*
X407442Y882200D01*
X407775Y882242D01*
X408108Y882450D01*
X408317Y882700D01*
X408358Y882950D01*
X408275Y883242D01*
X407983Y883450D01*
X407692Y883533D01*
X407317D01*
G01X407692D02*
X407942Y883658D01*
X408150Y883867D01*
X408233Y884117D01*
X408150Y884367D01*
X407942Y884575D01*
X407567Y884700D01*
X407192Y884658D01*
X406817Y884492D01*
G01X409708Y883242D02*
X410000Y883533D01*
X410250Y883700D01*
X410583Y883783D01*
X410875Y883700D01*
X411083Y883533D01*
X411250Y883283D01*
X411292Y882992D01*
X411250Y882742D01*
X411083Y882492D01*
X410833Y882283D01*
X410542Y882200D01*
X410208Y882283D01*
X409917Y882533D01*
X409750Y882908D01*
X409708Y883325D01*
X409792Y883867D01*
X409917Y884158D01*
X410125Y884450D01*
X410417Y884658D01*
X410708Y884700D01*
X411000Y884617D01*
X411208Y884408D01*
G01X412892Y882492D02*
X413183Y882283D01*
X413517Y882200D01*
X413850Y882283D01*
X414142Y882533D01*
X414350Y882908D01*
X414433Y883283D01*
Y883742D01*
X414350Y884117D01*
X414142Y884450D01*
X413892Y884617D01*
X413600Y884700D01*
X413267Y884617D01*
X413017Y884450D01*
X412850Y884200D01*
X412767Y883867D01*
X412850Y883575D01*
X413058Y883283D01*
X413308Y883117D01*
X413600Y883075D01*
X413933Y883158D01*
X414183Y883367D01*
X414433Y883742D01*
G01X368068Y869267D02*
X367943Y869017D01*
X367860Y868725D01*
Y868392D01*
X367985Y868017D01*
X368193Y867725D01*
X368443Y867517D01*
X368860Y867350D01*
X369235Y867308D01*
X369610Y867392D01*
X369860Y867517D01*
X370110Y867767D01*
X370277Y868058D01*
X370360Y868350D01*
Y868642D01*
X370277Y868933D01*
X370152Y869183D01*
X369985Y869392D01*
G01X370360Y871450D02*
X370318Y871742D01*
X370193Y872075D01*
X369985Y872283D01*
X369693Y872367D01*
X369402Y872283D01*
X369152Y872033D01*
X369027Y871658D01*
Y871242D01*
X368943Y870992D01*
X368735Y870783D01*
X368443Y870700D01*
X368152Y870825D01*
X367943Y871117D01*
X367860Y871450D01*
X367943Y871783D01*
X368152Y872075D01*
X368443Y872200D01*
X368735Y872117D01*
X368943Y871908D01*
X369027Y871658D01*
Y871242D01*
X369152Y870867D01*
X369402Y870617D01*
X369693Y870533D01*
X369985Y870617D01*
X370193Y870825D01*
X370318Y871158D01*
X370360Y871450D01*
G01Y874550D02*
X370318Y874842D01*
X370193Y875175D01*
X369985Y875383D01*
X369693Y875467D01*
X369402Y875383D01*
X369152Y875133D01*
X369027Y874758D01*
Y874342D01*
X368943Y874092D01*
X368735Y873883D01*
X368443Y873800D01*
X368152Y873925D01*
X367943Y874217D01*
X367860Y874550D01*
X367943Y874883D01*
X368152Y875175D01*
X368443Y875300D01*
X368735Y875217D01*
X368943Y875008D01*
X369027Y874758D01*
Y874342D01*
X369152Y873967D01*
X369402Y873717D01*
X369693Y873633D01*
X369985Y873717D01*
X370193Y873925D01*
X370318Y874258D01*
X370360Y874550D01*
G01X369318Y876858D02*
X369027Y877150D01*
X368860Y877400D01*
X368777Y877733D01*
X368860Y878025D01*
X369027Y878233D01*
X369277Y878400D01*
X369568Y878442D01*
X369818Y878400D01*
X370068Y878233D01*
X370277Y877983D01*
X370360Y877692D01*
X370277Y877358D01*
X370027Y877067D01*
X369652Y876900D01*
X369235Y876858D01*
X368693Y876942D01*
X368402Y877067D01*
X368110Y877275D01*
X367902Y877567D01*
X367860Y877858D01*
X367943Y878150D01*
X368152Y878358D01*
G01X370360Y880750D02*
X367860D01*
X368360Y880250D01*
G01X370360D02*
Y881250D01*
G01X385300Y891000D02*
Y887000D01*
X392700D01*
G01X349800Y891000D02*
Y887000D01*
X357200D01*
G01X353500Y860300D02*
X357500D01*
Y867700D01*
G01X338500Y860300D02*
X342500D01*
Y867700D01*
G01Y860300D02*
X346500D01*
Y867700D01*
G01X335260Y866317D02*
X332760D01*
Y867358D01*
X332885Y867692D01*
X333052Y867900D01*
X333385Y867983D01*
X333718Y867900D01*
X333927Y867650D01*
X334052Y867358D01*
Y866317D01*
G01Y867358D02*
X335260Y867983D01*
G01X334968Y869542D02*
X335177Y869833D01*
X335260Y870167D01*
X335177Y870500D01*
X334927Y870792D01*
X334552Y871000D01*
X334177Y871083D01*
X333718D01*
X333343Y871000D01*
X333010Y870792D01*
X332843Y870542D01*
X332760Y870250D01*
X332843Y869917D01*
X333010Y869667D01*
X333260Y869500D01*
X333593Y869417D01*
X333885Y869500D01*
X334177Y869708D01*
X334343Y869958D01*
X334385Y870250D01*
X334302Y870583D01*
X334093Y870833D01*
X333718Y871083D01*
G01X332760Y873350D02*
X332843Y873017D01*
X333052Y872767D01*
X333302Y872600D01*
X333635Y872475D01*
X334010Y872433D01*
X334385Y872475D01*
X334718Y872600D01*
X334968Y872767D01*
X335177Y873017D01*
X335260Y873350D01*
X335177Y873683D01*
X334968Y873933D01*
X334718Y874100D01*
X334385Y874225D01*
X334010Y874267D01*
X333635Y874225D01*
X333302Y874100D01*
X333052Y873933D01*
X332843Y873683D01*
X332760Y873350D01*
G01X334968Y875742D02*
X335177Y876033D01*
X335260Y876367D01*
X335177Y876700D01*
X334927Y876992D01*
X334552Y877200D01*
X334177Y877283D01*
X333718D01*
X333343Y877200D01*
X333010Y876992D01*
X332843Y876742D01*
X332760Y876450D01*
X332843Y876117D01*
X333010Y875867D01*
X333260Y875700D01*
X333593Y875617D01*
X333885Y875700D01*
X334177Y875908D01*
X334343Y876158D01*
X334385Y876450D01*
X334302Y876783D01*
X334093Y877033D01*
X333718Y877283D01*
G01X335260Y879550D02*
X332760D01*
X333260Y879050D01*
G01X335260D02*
Y880050D01*
G01X357500Y860300D02*
X361500D01*
Y867700D01*
G01X378000Y860300D02*
X382000D01*
Y867700D01*
G01X393000Y860300D02*
X397000D01*
Y867700D01*
G01X374000Y860300D02*
X378000D01*
Y867700D01*
G01X389000Y860300D02*
X393000D01*
Y867700D01*
G01X400367Y890200D02*
Y892700D01*
X401408D01*
X401742Y892575D01*
X401950Y892408D01*
X402033Y892075D01*
X401950Y891742D01*
X401700Y891533D01*
X401408Y891408D01*
X400367D01*
G01X401408D02*
X402033Y890200D01*
G01X403592Y890492D02*
X403883Y890283D01*
X404217Y890200D01*
X404550Y890283D01*
X404842Y890533D01*
X405050Y890908D01*
X405133Y891283D01*
Y891742D01*
X405050Y892117D01*
X404842Y892450D01*
X404592Y892617D01*
X404300Y892700D01*
X403967Y892617D01*
X403717Y892450D01*
X403550Y892200D01*
X403467Y891867D01*
X403550Y891575D01*
X403758Y891283D01*
X404008Y891117D01*
X404300Y891075D01*
X404633Y891158D01*
X404883Y891367D01*
X405133Y891742D01*
G01X406483Y890575D02*
X406733Y890367D01*
X407025Y890242D01*
X407400Y890200D01*
X407775Y890283D01*
X408067Y890450D01*
X408275Y890742D01*
X408317Y891075D01*
X408233Y891408D01*
X408025Y891617D01*
X407733Y891783D01*
X407442Y891825D01*
X407150Y891783D01*
X406775Y891617D01*
X406900Y892700D01*
X408025D01*
G01X410500D02*
X410167Y892617D01*
X409917Y892408D01*
X409750Y892158D01*
X409625Y891825D01*
X409583Y891450D01*
X409625Y891075D01*
X409750Y890742D01*
X409917Y890492D01*
X410167Y890283D01*
X410500Y890200D01*
X410833Y890283D01*
X411083Y890492D01*
X411250Y890742D01*
X411375Y891075D01*
X411417Y891450D01*
X411375Y891825D01*
X411250Y892158D01*
X411083Y892408D01*
X410833Y892617D01*
X410500Y892700D01*
G01X414100Y890200D02*
Y892700D01*
X412558Y890908D01*
X414642D01*
G01X377300Y891000D02*
Y887000D01*
X384700D01*
G01X341800Y891000D02*
Y887000D01*
X349200D01*
G01X409200Y854000D02*
X401400D01*
G01X402200D02*
X395800D01*
G01X400467Y886167D02*
Y888667D01*
X401508D01*
X401842Y888542D01*
X402050Y888375D01*
X402133Y888042D01*
X402050Y887709D01*
X401800Y887500D01*
X401508Y887375D01*
X400467D01*
G01X401508D02*
X402133Y886167D01*
G01X403692Y886459D02*
X403983Y886250D01*
X404317Y886167D01*
X404650Y886250D01*
X404942Y886500D01*
X405150Y886875D01*
X405233Y887250D01*
Y887709D01*
X405150Y888084D01*
X404942Y888417D01*
X404692Y888584D01*
X404400Y888667D01*
X404067Y888584D01*
X403817Y888417D01*
X403650Y888167D01*
X403567Y887834D01*
X403650Y887542D01*
X403858Y887250D01*
X404108Y887084D01*
X404400Y887042D01*
X404733Y887125D01*
X404983Y887334D01*
X405233Y887709D01*
G01X406708Y887209D02*
X407000Y887500D01*
X407250Y887667D01*
X407583Y887750D01*
X407875Y887667D01*
X408083Y887500D01*
X408250Y887250D01*
X408292Y886959D01*
X408250Y886709D01*
X408083Y886459D01*
X407833Y886250D01*
X407542Y886167D01*
X407208Y886250D01*
X406917Y886500D01*
X406750Y886875D01*
X406708Y887292D01*
X406792Y887834D01*
X406917Y888125D01*
X407125Y888417D01*
X407417Y888625D01*
X407708Y888667D01*
X408000Y888584D01*
X408208Y888375D01*
G01X410600Y888667D02*
X410267Y888584D01*
X410017Y888375D01*
X409850Y888125D01*
X409725Y887792D01*
X409683Y887417D01*
X409725Y887042D01*
X409850Y886709D01*
X410017Y886459D01*
X410267Y886250D01*
X410600Y886167D01*
X410933Y886250D01*
X411183Y886459D01*
X411350Y886709D01*
X411475Y887042D01*
X411517Y887417D01*
X411475Y887792D01*
X411350Y888125D01*
X411183Y888375D01*
X410933Y888584D01*
X410600Y888667D01*
G01X412783Y886667D02*
X413033Y886375D01*
X413367Y886209D01*
X413742Y886167D01*
X414075Y886209D01*
X414408Y886417D01*
X414617Y886667D01*
X414658Y886917D01*
X414575Y887209D01*
X414283Y887417D01*
X413992Y887500D01*
X413617D01*
G01X413992D02*
X414242Y887625D01*
X414450Y887834D01*
X414533Y888084D01*
X414450Y888334D01*
X414242Y888542D01*
X413867Y888667D01*
X413492Y888625D01*
X413117Y888459D01*
G01X384500Y886700D02*
X380500D01*
Y879300D01*
G01X349000Y886700D02*
X345000D01*
Y879300D01*
G01X392500Y886700D02*
X388500D01*
Y879300D01*
G01X357000Y886700D02*
X353000D01*
Y879300D01*
G01X382715Y850515D02*
Y853515D01*
G01X363000Y850515D02*
Y853515D01*
G01X372800Y852515D02*
Y850515D01*
G01X362877Y1134293D02*
X362627Y1134418D01*
X362335Y1134501D01*
X362002D01*
X361627Y1134376D01*
X361335Y1134168D01*
X361127Y1133918D01*
X360960Y1133501D01*
X360918Y1133126D01*
X361002Y1132751D01*
X361127Y1132501D01*
X361377Y1132251D01*
X361668Y1132084D01*
X361960Y1132001D01*
X362252D01*
X362543Y1132084D01*
X362793Y1132209D01*
X363002Y1132376D01*
G01X364352Y1132293D02*
X364643Y1132084D01*
X364977Y1132001D01*
X365310Y1132084D01*
X365602Y1132334D01*
X365810Y1132709D01*
X365893Y1133084D01*
Y1133543D01*
X365810Y1133918D01*
X365602Y1134251D01*
X365352Y1134418D01*
X365060Y1134501D01*
X364727Y1134418D01*
X364477Y1134251D01*
X364310Y1134001D01*
X364227Y1133668D01*
X364310Y1133376D01*
X364518Y1133084D01*
X364768Y1132918D01*
X365060Y1132876D01*
X365393Y1132959D01*
X365643Y1133168D01*
X365893Y1133543D01*
G01X367243Y1132501D02*
X367493Y1132209D01*
X367827Y1132043D01*
X368202Y1132001D01*
X368535Y1132043D01*
X368868Y1132251D01*
X369077Y1132501D01*
X369118Y1132751D01*
X369035Y1133043D01*
X368743Y1133251D01*
X368452Y1133334D01*
X368077D01*
G01X368452D02*
X368702Y1133459D01*
X368910Y1133668D01*
X368993Y1133918D01*
X368910Y1134168D01*
X368702Y1134376D01*
X368327Y1134501D01*
X367952Y1134459D01*
X367577Y1134293D01*
G01X370552Y1132293D02*
X370843Y1132084D01*
X371177Y1132001D01*
X371510Y1132084D01*
X371802Y1132334D01*
X372010Y1132709D01*
X372093Y1133084D01*
Y1133543D01*
X372010Y1133918D01*
X371802Y1134251D01*
X371552Y1134418D01*
X371260Y1134501D01*
X370927Y1134418D01*
X370677Y1134251D01*
X370510Y1134001D01*
X370427Y1133668D01*
X370510Y1133376D01*
X370718Y1133084D01*
X370968Y1132918D01*
X371260Y1132876D01*
X371593Y1132959D01*
X371843Y1133168D01*
X372093Y1133543D01*
G01X382827Y1134333D02*
X382577Y1134458D01*
X382285Y1134541D01*
X381952D01*
X381577Y1134416D01*
X381285Y1134208D01*
X381077Y1133958D01*
X380910Y1133541D01*
X380868Y1133166D01*
X380952Y1132791D01*
X381077Y1132541D01*
X381327Y1132291D01*
X381618Y1132124D01*
X381910Y1132041D01*
X382202D01*
X382493Y1132124D01*
X382743Y1132249D01*
X382952Y1132416D01*
G01X384302Y1132333D02*
X384593Y1132124D01*
X384927Y1132041D01*
X385260Y1132124D01*
X385552Y1132374D01*
X385760Y1132749D01*
X385843Y1133124D01*
Y1133583D01*
X385760Y1133958D01*
X385552Y1134291D01*
X385302Y1134458D01*
X385010Y1134541D01*
X384677Y1134458D01*
X384427Y1134291D01*
X384260Y1134041D01*
X384177Y1133708D01*
X384260Y1133416D01*
X384468Y1133124D01*
X384718Y1132958D01*
X385010Y1132916D01*
X385343Y1132999D01*
X385593Y1133208D01*
X385843Y1133583D01*
G01X388610Y1132041D02*
Y1134541D01*
X387068Y1132749D01*
X389152D01*
G01X391210Y1134541D02*
X390877Y1134458D01*
X390627Y1134249D01*
X390460Y1133999D01*
X390335Y1133666D01*
X390293Y1133291D01*
X390335Y1132916D01*
X390460Y1132583D01*
X390627Y1132333D01*
X390877Y1132124D01*
X391210Y1132041D01*
X391543Y1132124D01*
X391793Y1132333D01*
X391960Y1132583D01*
X392085Y1132916D01*
X392127Y1133291D01*
X392085Y1133666D01*
X391960Y1133999D01*
X391793Y1134249D01*
X391543Y1134458D01*
X391210Y1134541D01*
G01X360347Y1111111D02*
Y1113611D01*
X361388D01*
X361722Y1113486D01*
X361930Y1113319D01*
X362013Y1112986D01*
X361930Y1112653D01*
X361680Y1112444D01*
X361388Y1112319D01*
X360347D01*
G01X361388D02*
X362013Y1111111D01*
G01X363572Y1111403D02*
X363863Y1111194D01*
X364197Y1111111D01*
X364530Y1111194D01*
X364822Y1111444D01*
X365030Y1111819D01*
X365113Y1112194D01*
Y1112653D01*
X365030Y1113028D01*
X364822Y1113361D01*
X364572Y1113528D01*
X364280Y1113611D01*
X363947Y1113528D01*
X363697Y1113361D01*
X363530Y1113111D01*
X363447Y1112778D01*
X363530Y1112486D01*
X363738Y1112194D01*
X363988Y1112028D01*
X364280Y1111986D01*
X364613Y1112069D01*
X364863Y1112278D01*
X365113Y1112653D01*
G01X367880Y1111111D02*
Y1113611D01*
X366338Y1111819D01*
X368422D01*
G01X370480Y1113611D02*
X370147Y1113528D01*
X369897Y1113319D01*
X369730Y1113069D01*
X369605Y1112736D01*
X369563Y1112361D01*
X369605Y1111986D01*
X369730Y1111653D01*
X369897Y1111403D01*
X370147Y1111194D01*
X370480Y1111111D01*
X370813Y1111194D01*
X371063Y1111403D01*
X371230Y1111653D01*
X371355Y1111986D01*
X371397Y1112361D01*
X371355Y1112736D01*
X371230Y1113069D01*
X371063Y1113319D01*
X370813Y1113528D01*
X370480Y1113611D01*
G01X372788Y1113194D02*
X373038Y1113444D01*
X373330Y1113569D01*
X373663Y1113611D01*
X374080Y1113528D01*
X374372Y1113319D01*
X374455Y1113069D01*
X374413Y1112819D01*
X374247Y1112611D01*
X373413Y1112194D01*
X373038Y1111903D01*
X372788Y1111486D01*
X372705Y1111111D01*
X374455D01*
G01X381497Y1112651D02*
Y1115151D01*
X382538D01*
X382872Y1115026D01*
X383080Y1114859D01*
X383163Y1114526D01*
X383080Y1114193D01*
X382830Y1113984D01*
X382538Y1113859D01*
X381497D01*
G01X382538D02*
X383163Y1112651D01*
G01X384722Y1112943D02*
X385013Y1112734D01*
X385347Y1112651D01*
X385680Y1112734D01*
X385972Y1112984D01*
X386180Y1113359D01*
X386263Y1113734D01*
Y1114193D01*
X386180Y1114568D01*
X385972Y1114901D01*
X385722Y1115068D01*
X385430Y1115151D01*
X385097Y1115068D01*
X384847Y1114901D01*
X384680Y1114651D01*
X384597Y1114318D01*
X384680Y1114026D01*
X384888Y1113734D01*
X385138Y1113568D01*
X385430Y1113526D01*
X385763Y1113609D01*
X386013Y1113818D01*
X386263Y1114193D01*
G01X389030Y1112651D02*
Y1115151D01*
X387488Y1113359D01*
X389572D01*
G01X391630Y1112651D02*
X391922Y1112693D01*
X392255Y1112818D01*
X392463Y1113026D01*
X392547Y1113318D01*
X392463Y1113609D01*
X392213Y1113859D01*
X391838Y1113984D01*
X391422D01*
X391172Y1114068D01*
X390963Y1114276D01*
X390880Y1114568D01*
X391005Y1114859D01*
X391297Y1115068D01*
X391630Y1115151D01*
X391963Y1115068D01*
X392255Y1114859D01*
X392380Y1114568D01*
X392297Y1114276D01*
X392088Y1114068D01*
X391838Y1113984D01*
X391422D01*
X391047Y1113859D01*
X390797Y1113609D01*
X390713Y1113318D01*
X390797Y1113026D01*
X391005Y1112818D01*
X391338Y1112693D01*
X391630Y1112651D01*
G01X394730D02*
X395022Y1112693D01*
X395355Y1112818D01*
X395563Y1113026D01*
X395647Y1113318D01*
X395563Y1113609D01*
X395313Y1113859D01*
X394938Y1113984D01*
X394522D01*
X394272Y1114068D01*
X394063Y1114276D01*
X393980Y1114568D01*
X394105Y1114859D01*
X394397Y1115068D01*
X394730Y1115151D01*
X395063Y1115068D01*
X395355Y1114859D01*
X395480Y1114568D01*
X395397Y1114276D01*
X395188Y1114068D01*
X394938Y1113984D01*
X394522D01*
X394147Y1113859D01*
X393897Y1113609D01*
X393813Y1113318D01*
X393897Y1113026D01*
X394105Y1112818D01*
X394438Y1112693D01*
X394730Y1112651D01*
G01X387834Y1116967D02*
X385334D01*
Y1118008D01*
X385459Y1118342D01*
X385626Y1118550D01*
X385959Y1118633D01*
X386292Y1118550D01*
X386501Y1118300D01*
X386626Y1118008D01*
Y1116967D01*
G01Y1118008D02*
X387834Y1118633D01*
G01X387542Y1120192D02*
X387751Y1120483D01*
X387834Y1120817D01*
X387751Y1121150D01*
X387501Y1121442D01*
X387126Y1121650D01*
X386751Y1121733D01*
X386292D01*
X385917Y1121650D01*
X385584Y1121442D01*
X385417Y1121192D01*
X385334Y1120900D01*
X385417Y1120567D01*
X385584Y1120317D01*
X385834Y1120150D01*
X386167Y1120067D01*
X386459Y1120150D01*
X386751Y1120358D01*
X386917Y1120608D01*
X386959Y1120900D01*
X386876Y1121233D01*
X386667Y1121483D01*
X386292Y1121733D01*
G01X387459Y1123083D02*
X387667Y1123333D01*
X387792Y1123625D01*
X387834Y1124000D01*
X387751Y1124375D01*
X387584Y1124667D01*
X387292Y1124875D01*
X386959Y1124917D01*
X386626Y1124833D01*
X386417Y1124625D01*
X386251Y1124333D01*
X386209Y1124042D01*
X386251Y1123750D01*
X386417Y1123375D01*
X385334Y1123500D01*
Y1124625D01*
G01X387542Y1126392D02*
X387751Y1126683D01*
X387834Y1127017D01*
X387751Y1127350D01*
X387501Y1127642D01*
X387126Y1127850D01*
X386751Y1127933D01*
X386292D01*
X385917Y1127850D01*
X385584Y1127642D01*
X385417Y1127392D01*
X385334Y1127100D01*
X385417Y1126767D01*
X385584Y1126517D01*
X385834Y1126350D01*
X386167Y1126267D01*
X386459Y1126350D01*
X386751Y1126558D01*
X386917Y1126808D01*
X386959Y1127100D01*
X386876Y1127433D01*
X386667Y1127683D01*
X386292Y1127933D01*
G01X387334Y1129283D02*
X387626Y1129533D01*
X387792Y1129867D01*
X387834Y1130242D01*
X387792Y1130575D01*
X387584Y1130908D01*
X387334Y1131117D01*
X387084Y1131158D01*
X386792Y1131075D01*
X386584Y1130783D01*
X386501Y1130492D01*
Y1130117D01*
G01Y1130492D02*
X386376Y1130742D01*
X386167Y1130950D01*
X385917Y1131033D01*
X385667Y1130950D01*
X385459Y1130742D01*
X385334Y1130367D01*
X385376Y1129992D01*
X385542Y1129617D01*
G01X367529Y1115607D02*
X365029D01*
Y1116648D01*
X365154Y1116982D01*
X365321Y1117190D01*
X365654Y1117273D01*
X365987Y1117190D01*
X366196Y1116940D01*
X366321Y1116648D01*
Y1115607D01*
G01Y1116648D02*
X367529Y1117273D01*
G01X367237Y1118832D02*
X367446Y1119123D01*
X367529Y1119457D01*
X367446Y1119790D01*
X367196Y1120082D01*
X366821Y1120290D01*
X366446Y1120373D01*
X365987D01*
X365612Y1120290D01*
X365279Y1120082D01*
X365112Y1119832D01*
X365029Y1119540D01*
X365112Y1119207D01*
X365279Y1118957D01*
X365529Y1118790D01*
X365862Y1118707D01*
X366154Y1118790D01*
X366446Y1118998D01*
X366612Y1119248D01*
X366654Y1119540D01*
X366571Y1119873D01*
X366362Y1120123D01*
X365987Y1120373D01*
G01X367154Y1121723D02*
X367362Y1121973D01*
X367487Y1122265D01*
X367529Y1122640D01*
X367446Y1123015D01*
X367279Y1123307D01*
X366987Y1123515D01*
X366654Y1123557D01*
X366321Y1123473D01*
X366112Y1123265D01*
X365946Y1122973D01*
X365904Y1122682D01*
X365946Y1122390D01*
X366112Y1122015D01*
X365029Y1122140D01*
Y1123265D01*
G01X367237Y1125032D02*
X367446Y1125323D01*
X367529Y1125657D01*
X367446Y1125990D01*
X367196Y1126282D01*
X366821Y1126490D01*
X366446Y1126573D01*
X365987D01*
X365612Y1126490D01*
X365279Y1126282D01*
X365112Y1126032D01*
X365029Y1125740D01*
X365112Y1125407D01*
X365279Y1125157D01*
X365529Y1124990D01*
X365862Y1124907D01*
X366154Y1124990D01*
X366446Y1125198D01*
X366612Y1125448D01*
X366654Y1125740D01*
X366571Y1126073D01*
X366362Y1126323D01*
X365987Y1126573D01*
G01X365446Y1128048D02*
X365196Y1128298D01*
X365071Y1128590D01*
X365029Y1128923D01*
X365112Y1129340D01*
X365321Y1129632D01*
X365571Y1129715D01*
X365821Y1129673D01*
X366029Y1129507D01*
X366446Y1128673D01*
X366737Y1128298D01*
X367154Y1128048D01*
X367529Y1127965D01*
Y1129715D01*
G01X356118Y1161167D02*
X355993Y1160917D01*
X355910Y1160625D01*
Y1160292D01*
X356035Y1159917D01*
X356243Y1159625D01*
X356493Y1159417D01*
X356910Y1159250D01*
X357285Y1159208D01*
X357660Y1159292D01*
X357910Y1159417D01*
X358160Y1159667D01*
X358327Y1159958D01*
X358410Y1160250D01*
Y1160542D01*
X358327Y1160833D01*
X358202Y1161083D01*
X358035Y1161292D01*
G01X358118Y1162642D02*
X358327Y1162933D01*
X358410Y1163267D01*
X358327Y1163600D01*
X358077Y1163892D01*
X357702Y1164100D01*
X357327Y1164183D01*
X356868D01*
X356493Y1164100D01*
X356160Y1163892D01*
X355993Y1163642D01*
X355910Y1163350D01*
X355993Y1163017D01*
X356160Y1162767D01*
X356410Y1162600D01*
X356743Y1162517D01*
X357035Y1162600D01*
X357327Y1162808D01*
X357493Y1163058D01*
X357535Y1163350D01*
X357452Y1163683D01*
X357243Y1163933D01*
X356868Y1164183D01*
G01X358410Y1166950D02*
X355910D01*
X357702Y1165408D01*
Y1167492D01*
G01X356327Y1168758D02*
X356077Y1169008D01*
X355952Y1169300D01*
X355910Y1169633D01*
X355993Y1170050D01*
X356202Y1170342D01*
X356452Y1170425D01*
X356702Y1170383D01*
X356910Y1170217D01*
X357327Y1169383D01*
X357618Y1169008D01*
X358035Y1168758D01*
X358410Y1168675D01*
Y1170425D01*
G01Y1173150D02*
X355910D01*
X357702Y1171608D01*
Y1173692D01*
G01X360118Y1161167D02*
X359993Y1160917D01*
X359910Y1160625D01*
Y1160292D01*
X360035Y1159917D01*
X360243Y1159625D01*
X360493Y1159417D01*
X360910Y1159250D01*
X361285Y1159208D01*
X361660Y1159292D01*
X361910Y1159417D01*
X362160Y1159667D01*
X362327Y1159958D01*
X362410Y1160250D01*
Y1160542D01*
X362327Y1160833D01*
X362202Y1161083D01*
X362035Y1161292D01*
G01X362410Y1163350D02*
X362368Y1163642D01*
X362243Y1163975D01*
X362035Y1164183D01*
X361743Y1164267D01*
X361452Y1164183D01*
X361202Y1163933D01*
X361077Y1163558D01*
Y1163142D01*
X360993Y1162892D01*
X360785Y1162683D01*
X360493Y1162600D01*
X360202Y1162725D01*
X359993Y1163017D01*
X359910Y1163350D01*
X359993Y1163683D01*
X360202Y1163975D01*
X360493Y1164100D01*
X360785Y1164017D01*
X360993Y1163808D01*
X361077Y1163558D01*
Y1163142D01*
X361202Y1162767D01*
X361452Y1162517D01*
X361743Y1162433D01*
X362035Y1162517D01*
X362243Y1162725D01*
X362368Y1163058D01*
X362410Y1163350D01*
G01Y1166450D02*
X362368Y1166742D01*
X362243Y1167075D01*
X362035Y1167283D01*
X361743Y1167367D01*
X361452Y1167283D01*
X361202Y1167033D01*
X361077Y1166658D01*
Y1166242D01*
X360993Y1165992D01*
X360785Y1165783D01*
X360493Y1165700D01*
X360202Y1165825D01*
X359993Y1166117D01*
X359910Y1166450D01*
X359993Y1166783D01*
X360202Y1167075D01*
X360493Y1167200D01*
X360785Y1167117D01*
X360993Y1166908D01*
X361077Y1166658D01*
Y1166242D01*
X361202Y1165867D01*
X361452Y1165617D01*
X361743Y1165533D01*
X362035Y1165617D01*
X362243Y1165825D01*
X362368Y1166158D01*
X362410Y1166450D01*
G01Y1170050D02*
X359910D01*
X361702Y1168508D01*
Y1170592D01*
G01X362118Y1171942D02*
X362327Y1172233D01*
X362410Y1172567D01*
X362327Y1172900D01*
X362077Y1173192D01*
X361702Y1173400D01*
X361327Y1173483D01*
X360868D01*
X360493Y1173400D01*
X360160Y1173192D01*
X359993Y1172942D01*
X359910Y1172650D01*
X359993Y1172317D01*
X360160Y1172067D01*
X360410Y1171900D01*
X360743Y1171817D01*
X361035Y1171900D01*
X361327Y1172108D01*
X361493Y1172358D01*
X361535Y1172650D01*
X361452Y1172983D01*
X361243Y1173233D01*
X360868Y1173483D01*
G01X399208Y1174217D02*
X399083Y1173967D01*
X399000Y1173675D01*
Y1173342D01*
X399125Y1172967D01*
X399333Y1172675D01*
X399583Y1172467D01*
X400000Y1172300D01*
X400375Y1172258D01*
X400750Y1172342D01*
X401000Y1172467D01*
X401250Y1172717D01*
X401417Y1173008D01*
X401500Y1173300D01*
Y1173592D01*
X401417Y1173883D01*
X401292Y1174133D01*
X401125Y1174342D01*
G01X401500Y1176400D02*
X401458Y1176692D01*
X401333Y1177025D01*
X401125Y1177233D01*
X400833Y1177317D01*
X400542Y1177233D01*
X400292Y1176983D01*
X400167Y1176608D01*
Y1176192D01*
X400083Y1175942D01*
X399875Y1175733D01*
X399583Y1175650D01*
X399292Y1175775D01*
X399083Y1176067D01*
X399000Y1176400D01*
X399083Y1176733D01*
X399292Y1177025D01*
X399583Y1177150D01*
X399875Y1177067D01*
X400083Y1176858D01*
X400167Y1176608D01*
Y1176192D01*
X400292Y1175817D01*
X400542Y1175567D01*
X400833Y1175483D01*
X401125Y1175567D01*
X401333Y1175775D01*
X401458Y1176108D01*
X401500Y1176400D01*
G01Y1179500D02*
X401458Y1179792D01*
X401333Y1180125D01*
X401125Y1180333D01*
X400833Y1180417D01*
X400542Y1180333D01*
X400292Y1180083D01*
X400167Y1179708D01*
Y1179292D01*
X400083Y1179042D01*
X399875Y1178833D01*
X399583Y1178750D01*
X399292Y1178875D01*
X399083Y1179167D01*
X399000Y1179500D01*
X399083Y1179833D01*
X399292Y1180125D01*
X399583Y1180250D01*
X399875Y1180167D01*
X400083Y1179958D01*
X400167Y1179708D01*
Y1179292D01*
X400292Y1178917D01*
X400542Y1178667D01*
X400833Y1178583D01*
X401125Y1178667D01*
X401333Y1178875D01*
X401458Y1179208D01*
X401500Y1179500D01*
G01X401125Y1181683D02*
X401333Y1181933D01*
X401458Y1182225D01*
X401500Y1182600D01*
X401417Y1182975D01*
X401250Y1183267D01*
X400958Y1183475D01*
X400625Y1183517D01*
X400292Y1183433D01*
X400083Y1183225D01*
X399917Y1182933D01*
X399875Y1182642D01*
X399917Y1182350D01*
X400083Y1181975D01*
X399000Y1182100D01*
Y1183225D01*
G01Y1185700D02*
X399083Y1185367D01*
X399292Y1185117D01*
X399542Y1184950D01*
X399875Y1184825D01*
X400250Y1184783D01*
X400625Y1184825D01*
X400958Y1184950D01*
X401208Y1185117D01*
X401417Y1185367D01*
X401500Y1185700D01*
X401417Y1186033D01*
X401208Y1186283D01*
X400958Y1186450D01*
X400625Y1186575D01*
X400250Y1186617D01*
X399875Y1186575D01*
X399542Y1186450D01*
X399292Y1186283D01*
X399083Y1186033D01*
X399000Y1185700D01*
G01X385700Y1140500D02*
Y1144500D01*
X378300D01*
G01X332800Y1192500D02*
Y1188500D01*
X340200D01*
G01X372410Y1149917D02*
X369910D01*
Y1150958D01*
X370035Y1151292D01*
X370202Y1151500D01*
X370535Y1151583D01*
X370868Y1151500D01*
X371077Y1151250D01*
X371202Y1150958D01*
Y1149917D01*
G01Y1150958D02*
X372410Y1151583D01*
G01X372118Y1153142D02*
X372327Y1153433D01*
X372410Y1153767D01*
X372327Y1154100D01*
X372077Y1154392D01*
X371702Y1154600D01*
X371327Y1154683D01*
X370868D01*
X370493Y1154600D01*
X370160Y1154392D01*
X369993Y1154142D01*
X369910Y1153850D01*
X369993Y1153517D01*
X370160Y1153267D01*
X370410Y1153100D01*
X370743Y1153017D01*
X371035Y1153100D01*
X371327Y1153308D01*
X371493Y1153558D01*
X371535Y1153850D01*
X371452Y1154183D01*
X371243Y1154433D01*
X370868Y1154683D01*
G01X369910Y1156950D02*
X369993Y1156617D01*
X370202Y1156367D01*
X370452Y1156200D01*
X370785Y1156075D01*
X371160Y1156033D01*
X371535Y1156075D01*
X371868Y1156200D01*
X372118Y1156367D01*
X372327Y1156617D01*
X372410Y1156950D01*
X372327Y1157283D01*
X372118Y1157533D01*
X371868Y1157700D01*
X371535Y1157825D01*
X371160Y1157867D01*
X370785Y1157825D01*
X370452Y1157700D01*
X370202Y1157533D01*
X369993Y1157283D01*
X369910Y1156950D01*
G01X371368Y1159258D02*
X371077Y1159550D01*
X370910Y1159800D01*
X370827Y1160133D01*
X370910Y1160425D01*
X371077Y1160633D01*
X371327Y1160800D01*
X371618Y1160842D01*
X371868Y1160800D01*
X372118Y1160633D01*
X372327Y1160383D01*
X372410Y1160092D01*
X372327Y1159758D01*
X372077Y1159467D01*
X371702Y1159300D01*
X371285Y1159258D01*
X370743Y1159342D01*
X370452Y1159467D01*
X370160Y1159675D01*
X369952Y1159967D01*
X369910Y1160258D01*
X369993Y1160550D01*
X370202Y1160758D01*
G01X372410Y1163067D02*
X371868Y1163150D01*
X371410Y1163275D01*
X370993Y1163442D01*
X370535Y1163650D01*
X369910Y1163983D01*
Y1162317D01*
G01X382000Y1171200D02*
X378000D01*
Y1163800D01*
G01X400300Y1209500D02*
Y1205500D01*
X407700D01*
G01X400300Y1213500D02*
Y1209500D01*
X407700D01*
G01X402410Y1155017D02*
X399910D01*
Y1156058D01*
X400035Y1156392D01*
X400202Y1156600D01*
X400535Y1156683D01*
X400868Y1156600D01*
X401077Y1156350D01*
X401202Y1156058D01*
Y1155017D01*
G01Y1156058D02*
X402410Y1156683D01*
G01X402118Y1158242D02*
X402327Y1158533D01*
X402410Y1158867D01*
X402327Y1159200D01*
X402077Y1159492D01*
X401702Y1159700D01*
X401327Y1159783D01*
X400868D01*
X400493Y1159700D01*
X400160Y1159492D01*
X399993Y1159242D01*
X399910Y1158950D01*
X399993Y1158617D01*
X400160Y1158367D01*
X400410Y1158200D01*
X400743Y1158117D01*
X401035Y1158200D01*
X401327Y1158408D01*
X401493Y1158658D01*
X401535Y1158950D01*
X401452Y1159283D01*
X401243Y1159533D01*
X400868Y1159783D01*
G01X399910Y1162050D02*
X399993Y1161717D01*
X400202Y1161467D01*
X400452Y1161300D01*
X400785Y1161175D01*
X401160Y1161133D01*
X401535Y1161175D01*
X401868Y1161300D01*
X402118Y1161467D01*
X402327Y1161717D01*
X402410Y1162050D01*
X402327Y1162383D01*
X402118Y1162633D01*
X401868Y1162800D01*
X401535Y1162925D01*
X401160Y1162967D01*
X400785Y1162925D01*
X400452Y1162800D01*
X400202Y1162633D01*
X399993Y1162383D01*
X399910Y1162050D01*
G01X402410Y1165067D02*
X401868Y1165150D01*
X401410Y1165275D01*
X400993Y1165442D01*
X400535Y1165650D01*
X399910Y1165983D01*
Y1164317D01*
G01X401368Y1167458D02*
X401077Y1167750D01*
X400910Y1168000D01*
X400827Y1168333D01*
X400910Y1168625D01*
X401077Y1168833D01*
X401327Y1169000D01*
X401618Y1169042D01*
X401868Y1169000D01*
X402118Y1168833D01*
X402327Y1168583D01*
X402410Y1168292D01*
X402327Y1167958D01*
X402077Y1167667D01*
X401702Y1167500D01*
X401285Y1167458D01*
X400743Y1167542D01*
X400452Y1167667D01*
X400160Y1167875D01*
X399952Y1168167D01*
X399910Y1168458D01*
X399993Y1168750D01*
X400202Y1168958D01*
G01X393000Y1171200D02*
X389000D01*
Y1163800D01*
G01X397000Y1171200D02*
X393000D01*
Y1163800D01*
G01X368410Y1149917D02*
X365910D01*
Y1150958D01*
X366035Y1151292D01*
X366202Y1151500D01*
X366535Y1151583D01*
X366868Y1151500D01*
X367077Y1151250D01*
X367202Y1150958D01*
Y1149917D01*
G01Y1150958D02*
X368410Y1151583D01*
G01X368118Y1153142D02*
X368327Y1153433D01*
X368410Y1153767D01*
X368327Y1154100D01*
X368077Y1154392D01*
X367702Y1154600D01*
X367327Y1154683D01*
X366868D01*
X366493Y1154600D01*
X366160Y1154392D01*
X365993Y1154142D01*
X365910Y1153850D01*
X365993Y1153517D01*
X366160Y1153267D01*
X366410Y1153100D01*
X366743Y1153017D01*
X367035Y1153100D01*
X367327Y1153308D01*
X367493Y1153558D01*
X367535Y1153850D01*
X367452Y1154183D01*
X367243Y1154433D01*
X366868Y1154683D01*
G01X365910Y1156950D02*
X365993Y1156617D01*
X366202Y1156367D01*
X366452Y1156200D01*
X366785Y1156075D01*
X367160Y1156033D01*
X367535Y1156075D01*
X367868Y1156200D01*
X368118Y1156367D01*
X368327Y1156617D01*
X368410Y1156950D01*
X368327Y1157283D01*
X368118Y1157533D01*
X367868Y1157700D01*
X367535Y1157825D01*
X367160Y1157867D01*
X366785Y1157825D01*
X366452Y1157700D01*
X366202Y1157533D01*
X365993Y1157283D01*
X365910Y1156950D01*
G01X368410Y1159967D02*
X367868Y1160050D01*
X367410Y1160175D01*
X366993Y1160342D01*
X366535Y1160550D01*
X365910Y1160883D01*
Y1159217D01*
G01X368410Y1163150D02*
X368368Y1163442D01*
X368243Y1163775D01*
X368035Y1163983D01*
X367743Y1164067D01*
X367452Y1163983D01*
X367202Y1163733D01*
X367077Y1163358D01*
Y1162942D01*
X366993Y1162692D01*
X366785Y1162483D01*
X366493Y1162400D01*
X366202Y1162525D01*
X365993Y1162817D01*
X365910Y1163150D01*
X365993Y1163483D01*
X366202Y1163775D01*
X366493Y1163900D01*
X366785Y1163817D01*
X366993Y1163608D01*
X367077Y1163358D01*
Y1162942D01*
X367202Y1162567D01*
X367452Y1162317D01*
X367743Y1162233D01*
X368035Y1162317D01*
X368243Y1162525D01*
X368368Y1162858D01*
X368410Y1163150D01*
G01X378000Y1171200D02*
X374000D01*
Y1163800D01*
G01X340200Y1192500D02*
Y1196500D01*
X332800D01*
G01X404200Y1190000D02*
Y1194000D01*
X396800D01*
G01X393700Y1140500D02*
Y1144500D01*
X386300D01*
G01X386500Y1144800D02*
X390500D01*
Y1152200D01*
G01X378500Y1144800D02*
X382500D01*
Y1152200D01*
G01X340613Y1211990D02*
X338947D01*
Y1214490D01*
X340613D01*
G01X339947Y1213282D02*
X338947D01*
G01X341963Y1214490D02*
Y1212698D01*
X342130Y1212323D01*
X342463Y1212073D01*
X342880Y1211990D01*
X343297Y1212073D01*
X343630Y1212323D01*
X343797Y1212698D01*
Y1214490D01*
G01X345188Y1214073D02*
X345438Y1214323D01*
X345730Y1214448D01*
X346063Y1214490D01*
X346480Y1214407D01*
X346772Y1214198D01*
X346855Y1213948D01*
X346813Y1213698D01*
X346647Y1213490D01*
X345813Y1213073D01*
X345438Y1212782D01*
X345188Y1212365D01*
X345105Y1211990D01*
X346855D01*
G01X386200Y1179850D02*
X391700D01*
Y1184950D01*
G01X348300Y1185800D02*
Y1179800D01*
X354550D01*
G01X380800Y1177985D02*
Y1180985D01*
G01X361100Y1177985D02*
Y1180985D01*
G01X371000D02*
Y1178985D01*
G01X390515Y1210300D02*
X392515D01*
G01X390515Y1190700D02*
X392515D01*
G01X393515Y1198600D02*
X390515D01*
G01X347485Y1188650D02*
X349485D01*
G01X347485Y1208400D02*
X349485D01*
G01Y1198585D02*
X346485D01*
G01X401417Y1265892D02*
X401167Y1266017D01*
X400875Y1266100D01*
X400542D01*
X400167Y1265975D01*
X399875Y1265767D01*
X399667Y1265517D01*
X399500Y1265100D01*
X399458Y1264725D01*
X399542Y1264350D01*
X399667Y1264100D01*
X399917Y1263850D01*
X400208Y1263683D01*
X400500Y1263600D01*
X400792D01*
X401083Y1263683D01*
X401333Y1263808D01*
X401542Y1263975D01*
G01X402892Y1263892D02*
X403183Y1263683D01*
X403517Y1263600D01*
X403850Y1263683D01*
X404142Y1263933D01*
X404350Y1264308D01*
X404433Y1264683D01*
Y1265142D01*
X404350Y1265517D01*
X404142Y1265850D01*
X403892Y1266017D01*
X403600Y1266100D01*
X403267Y1266017D01*
X403017Y1265850D01*
X402850Y1265600D01*
X402767Y1265267D01*
X402850Y1264975D01*
X403058Y1264683D01*
X403308Y1264517D01*
X403600Y1264475D01*
X403933Y1264558D01*
X404183Y1264767D01*
X404433Y1265142D01*
G01X405783Y1264100D02*
X406033Y1263808D01*
X406367Y1263642D01*
X406742Y1263600D01*
X407075Y1263642D01*
X407408Y1263850D01*
X407617Y1264100D01*
X407658Y1264350D01*
X407575Y1264642D01*
X407283Y1264850D01*
X406992Y1264933D01*
X406617D01*
G01X406992D02*
X407242Y1265058D01*
X407450Y1265267D01*
X407533Y1265517D01*
X407450Y1265767D01*
X407242Y1265975D01*
X406867Y1266100D01*
X406492Y1266058D01*
X406117Y1265892D01*
G01X409008Y1264642D02*
X409300Y1264933D01*
X409550Y1265100D01*
X409883Y1265183D01*
X410175Y1265100D01*
X410383Y1264933D01*
X410550Y1264683D01*
X410592Y1264392D01*
X410550Y1264142D01*
X410383Y1263892D01*
X410133Y1263683D01*
X409842Y1263600D01*
X409508Y1263683D01*
X409217Y1263933D01*
X409050Y1264308D01*
X409008Y1264725D01*
X409092Y1265267D01*
X409217Y1265558D01*
X409425Y1265850D01*
X409717Y1266058D01*
X410008Y1266100D01*
X410300Y1266017D01*
X410508Y1265808D01*
G01X412900Y1263600D02*
X413192Y1263642D01*
X413525Y1263767D01*
X413733Y1263975D01*
X413817Y1264267D01*
X413733Y1264558D01*
X413483Y1264808D01*
X413108Y1264933D01*
X412692D01*
X412442Y1265017D01*
X412233Y1265225D01*
X412150Y1265517D01*
X412275Y1265808D01*
X412567Y1266017D01*
X412900Y1266100D01*
X413233Y1266017D01*
X413525Y1265808D01*
X413650Y1265517D01*
X413567Y1265225D01*
X413358Y1265017D01*
X413108Y1264933D01*
X412692D01*
X412317Y1264808D01*
X412067Y1264558D01*
X411983Y1264267D01*
X412067Y1263975D01*
X412275Y1263767D01*
X412608Y1263642D01*
X412900Y1263600D01*
G01X385300Y1262500D02*
Y1258500D01*
X392700D01*
G01X349800Y1262500D02*
Y1258500D01*
X357200D01*
G01X400300Y1224500D02*
Y1220500D01*
X407700D01*
G01X400300Y1228500D02*
Y1224500D01*
X407700D01*
G01X353500Y1231800D02*
X357500D01*
Y1239200D01*
G01X332800Y1244917D02*
X330300D01*
Y1245958D01*
X330425Y1246292D01*
X330592Y1246500D01*
X330925Y1246583D01*
X331258Y1246500D01*
X331467Y1246250D01*
X331592Y1245958D01*
Y1244917D01*
G01Y1245958D02*
X332800Y1246583D01*
G01X332508Y1248142D02*
X332717Y1248433D01*
X332800Y1248767D01*
X332717Y1249100D01*
X332467Y1249392D01*
X332092Y1249600D01*
X331717Y1249683D01*
X331258D01*
X330883Y1249600D01*
X330550Y1249392D01*
X330383Y1249142D01*
X330300Y1248850D01*
X330383Y1248517D01*
X330550Y1248267D01*
X330800Y1248100D01*
X331133Y1248017D01*
X331425Y1248100D01*
X331717Y1248308D01*
X331883Y1248558D01*
X331925Y1248850D01*
X331842Y1249183D01*
X331633Y1249433D01*
X331258Y1249683D01*
G01X330300Y1251950D02*
X330383Y1251617D01*
X330592Y1251367D01*
X330842Y1251200D01*
X331175Y1251075D01*
X331550Y1251033D01*
X331925Y1251075D01*
X332258Y1251200D01*
X332508Y1251367D01*
X332717Y1251617D01*
X332800Y1251950D01*
X332717Y1252283D01*
X332508Y1252533D01*
X332258Y1252700D01*
X331925Y1252825D01*
X331550Y1252867D01*
X331175Y1252825D01*
X330842Y1252700D01*
X330592Y1252533D01*
X330383Y1252283D01*
X330300Y1251950D01*
G01X332508Y1254342D02*
X332717Y1254633D01*
X332800Y1254967D01*
X332717Y1255300D01*
X332467Y1255592D01*
X332092Y1255800D01*
X331717Y1255883D01*
X331258D01*
X330883Y1255800D01*
X330550Y1255592D01*
X330383Y1255342D01*
X330300Y1255050D01*
X330383Y1254717D01*
X330550Y1254467D01*
X330800Y1254300D01*
X331133Y1254217D01*
X331425Y1254300D01*
X331717Y1254508D01*
X331883Y1254758D01*
X331925Y1255050D01*
X331842Y1255383D01*
X331633Y1255633D01*
X331258Y1255883D01*
G01X332800Y1258067D02*
X332258Y1258150D01*
X331800Y1258275D01*
X331383Y1258442D01*
X330925Y1258650D01*
X330300Y1258983D01*
Y1257317D01*
G01X378000Y1231800D02*
X382000D01*
Y1239200D01*
G01X374000Y1231800D02*
X378000D01*
Y1239200D01*
G01X404309Y1240327D02*
X401809D01*
Y1241368D01*
X401934Y1241702D01*
X402101Y1241910D01*
X402434Y1241993D01*
X402767Y1241910D01*
X402976Y1241660D01*
X403101Y1241368D01*
Y1240327D01*
G01Y1241368D02*
X404309Y1241993D01*
G01X404017Y1243552D02*
X404226Y1243843D01*
X404309Y1244177D01*
X404226Y1244510D01*
X403976Y1244802D01*
X403601Y1245010D01*
X403226Y1245093D01*
X402767D01*
X402392Y1245010D01*
X402059Y1244802D01*
X401892Y1244552D01*
X401809Y1244260D01*
X401892Y1243927D01*
X402059Y1243677D01*
X402309Y1243510D01*
X402642Y1243427D01*
X402934Y1243510D01*
X403226Y1243718D01*
X403392Y1243968D01*
X403434Y1244260D01*
X403351Y1244593D01*
X403142Y1244843D01*
X402767Y1245093D01*
G01X404309Y1247360D02*
X401809D01*
X402309Y1246860D01*
G01X404309D02*
Y1247860D01*
G01X401809Y1250460D02*
X401892Y1250127D01*
X402101Y1249877D01*
X402351Y1249710D01*
X402684Y1249585D01*
X403059Y1249543D01*
X403434Y1249585D01*
X403767Y1249710D01*
X404017Y1249877D01*
X404226Y1250127D01*
X404309Y1250460D01*
X404226Y1250793D01*
X404017Y1251043D01*
X403767Y1251210D01*
X403434Y1251335D01*
X403059Y1251377D01*
X402684Y1251335D01*
X402351Y1251210D01*
X402101Y1251043D01*
X401892Y1250793D01*
X401809Y1250460D01*
G01Y1253560D02*
X401892Y1253227D01*
X402101Y1252977D01*
X402351Y1252810D01*
X402684Y1252685D01*
X403059Y1252643D01*
X403434Y1252685D01*
X403767Y1252810D01*
X404017Y1252977D01*
X404226Y1253227D01*
X404309Y1253560D01*
X404226Y1253893D01*
X404017Y1254143D01*
X403767Y1254310D01*
X403434Y1254435D01*
X403059Y1254477D01*
X402684Y1254435D01*
X402351Y1254310D01*
X402101Y1254143D01*
X401892Y1253893D01*
X401809Y1253560D01*
G01X393000Y1231800D02*
X397000D01*
Y1239200D01*
G01X400309Y1240327D02*
X397809D01*
Y1241368D01*
X397934Y1241702D01*
X398101Y1241910D01*
X398434Y1241993D01*
X398767Y1241910D01*
X398976Y1241660D01*
X399101Y1241368D01*
Y1240327D01*
G01Y1241368D02*
X400309Y1241993D01*
G01X400017Y1243552D02*
X400226Y1243843D01*
X400309Y1244177D01*
X400226Y1244510D01*
X399976Y1244802D01*
X399601Y1245010D01*
X399226Y1245093D01*
X398767D01*
X398392Y1245010D01*
X398059Y1244802D01*
X397892Y1244552D01*
X397809Y1244260D01*
X397892Y1243927D01*
X398059Y1243677D01*
X398309Y1243510D01*
X398642Y1243427D01*
X398934Y1243510D01*
X399226Y1243718D01*
X399392Y1243968D01*
X399434Y1244260D01*
X399351Y1244593D01*
X399142Y1244843D01*
X398767Y1245093D01*
G01X400309Y1247360D02*
X397809D01*
X398309Y1246860D01*
G01X400309D02*
Y1247860D01*
G01X397809Y1250460D02*
X397892Y1250127D01*
X398101Y1249877D01*
X398351Y1249710D01*
X398684Y1249585D01*
X399059Y1249543D01*
X399434Y1249585D01*
X399767Y1249710D01*
X400017Y1249877D01*
X400226Y1250127D01*
X400309Y1250460D01*
X400226Y1250793D01*
X400017Y1251043D01*
X399767Y1251210D01*
X399434Y1251335D01*
X399059Y1251377D01*
X398684Y1251335D01*
X398351Y1251210D01*
X398101Y1251043D01*
X397892Y1250793D01*
X397809Y1250460D01*
G01X400309Y1253560D02*
X397809D01*
X398309Y1253060D01*
G01X400309D02*
Y1254060D01*
G01X389000Y1231800D02*
X393000D01*
Y1239200D01*
G01X342500Y1231800D02*
X346500D01*
Y1239200D01*
G01X338500Y1231800D02*
X342500D01*
Y1239200D01*
G01X357500Y1231800D02*
X361500D01*
Y1239200D01*
G01X399667Y1271600D02*
Y1274100D01*
X400708D01*
X401042Y1273975D01*
X401250Y1273808D01*
X401333Y1273475D01*
X401250Y1273142D01*
X401000Y1272933D01*
X400708Y1272808D01*
X399667D01*
G01X400708D02*
X401333Y1271600D01*
G01X402892Y1271892D02*
X403183Y1271683D01*
X403517Y1271600D01*
X403850Y1271683D01*
X404142Y1271933D01*
X404350Y1272308D01*
X404433Y1272683D01*
Y1273142D01*
X404350Y1273517D01*
X404142Y1273850D01*
X403892Y1274017D01*
X403600Y1274100D01*
X403267Y1274017D01*
X403017Y1273850D01*
X402850Y1273600D01*
X402767Y1273267D01*
X402850Y1272975D01*
X403058Y1272683D01*
X403308Y1272517D01*
X403600Y1272475D01*
X403933Y1272558D01*
X404183Y1272767D01*
X404433Y1273142D01*
G01X405783Y1271975D02*
X406033Y1271767D01*
X406325Y1271642D01*
X406700Y1271600D01*
X407075Y1271683D01*
X407367Y1271850D01*
X407575Y1272142D01*
X407617Y1272475D01*
X407533Y1272808D01*
X407325Y1273017D01*
X407033Y1273183D01*
X406742Y1273225D01*
X406450Y1273183D01*
X406075Y1273017D01*
X406200Y1274100D01*
X407325D01*
G01X409800D02*
X409467Y1274017D01*
X409217Y1273808D01*
X409050Y1273558D01*
X408925Y1273225D01*
X408883Y1272850D01*
X408925Y1272475D01*
X409050Y1272142D01*
X409217Y1271892D01*
X409467Y1271683D01*
X409800Y1271600D01*
X410133Y1271683D01*
X410383Y1271892D01*
X410550Y1272142D01*
X410675Y1272475D01*
X410717Y1272850D01*
X410675Y1273225D01*
X410550Y1273558D01*
X410383Y1273808D01*
X410133Y1274017D01*
X409800Y1274100D01*
G01X412108Y1273683D02*
X412358Y1273933D01*
X412650Y1274058D01*
X412983Y1274100D01*
X413400Y1274017D01*
X413692Y1273808D01*
X413775Y1273558D01*
X413733Y1273308D01*
X413567Y1273100D01*
X412733Y1272683D01*
X412358Y1272392D01*
X412108Y1271975D01*
X412025Y1271600D01*
X413775D01*
G01X377300Y1262500D02*
Y1258500D01*
X384700D01*
G01X341800Y1262500D02*
Y1258500D01*
X349200D01*
G01X397800Y1229000D02*
X406500D01*
G01X397800Y1236000D02*
Y1229000D01*
G01X404200Y1236000D02*
X397800D01*
G01X399467Y1267667D02*
Y1270167D01*
X400508D01*
X400842Y1270042D01*
X401050Y1269875D01*
X401133Y1269542D01*
X401050Y1269209D01*
X400800Y1269000D01*
X400508Y1268875D01*
X399467D01*
G01X400508D02*
X401133Y1267667D01*
G01X402692Y1267959D02*
X402983Y1267750D01*
X403317Y1267667D01*
X403650Y1267750D01*
X403942Y1268000D01*
X404150Y1268375D01*
X404233Y1268750D01*
Y1269209D01*
X404150Y1269584D01*
X403942Y1269917D01*
X403692Y1270084D01*
X403400Y1270167D01*
X403067Y1270084D01*
X402817Y1269917D01*
X402650Y1269667D01*
X402567Y1269334D01*
X402650Y1269042D01*
X402858Y1268750D01*
X403108Y1268584D01*
X403400Y1268542D01*
X403733Y1268625D01*
X403983Y1268834D01*
X404233Y1269209D01*
G01X405708Y1268709D02*
X406000Y1269000D01*
X406250Y1269167D01*
X406583Y1269250D01*
X406875Y1269167D01*
X407083Y1269000D01*
X407250Y1268750D01*
X407292Y1268459D01*
X407250Y1268209D01*
X407083Y1267959D01*
X406833Y1267750D01*
X406542Y1267667D01*
X406208Y1267750D01*
X405917Y1268000D01*
X405750Y1268375D01*
X405708Y1268792D01*
X405792Y1269334D01*
X405917Y1269625D01*
X406125Y1269917D01*
X406417Y1270125D01*
X406708Y1270167D01*
X407000Y1270084D01*
X407208Y1269875D01*
G01X409600Y1270167D02*
X409267Y1270084D01*
X409017Y1269875D01*
X408850Y1269625D01*
X408725Y1269292D01*
X408683Y1268917D01*
X408725Y1268542D01*
X408850Y1268209D01*
X409017Y1267959D01*
X409267Y1267750D01*
X409600Y1267667D01*
X409933Y1267750D01*
X410183Y1267959D01*
X410350Y1268209D01*
X410475Y1268542D01*
X410517Y1268917D01*
X410475Y1269292D01*
X410350Y1269625D01*
X410183Y1269875D01*
X409933Y1270084D01*
X409600Y1270167D01*
G01X412700Y1267667D02*
Y1270167D01*
X412200Y1269667D01*
G01Y1267667D02*
X413200D01*
G01X384500Y1258200D02*
X380500D01*
Y1250800D01*
G01X349000Y1258200D02*
X345000D01*
Y1250800D01*
G01X392500Y1258200D02*
X388500D01*
Y1250800D01*
G01X357000Y1258200D02*
X353000D01*
Y1250800D01*
G01X391650Y1217550D02*
Y1223200D01*
X385700D01*
G01X382715Y1222015D02*
Y1225015D01*
G01X363000Y1222015D02*
Y1225015D01*
G01X372800Y1224015D02*
Y1222015D01*
G01X331205Y1428534D02*
X331538Y1428326D01*
X331913Y1428201D01*
X332247D01*
X332580Y1428326D01*
X332830Y1428534D01*
X332955Y1428826D01*
X332872Y1429118D01*
X332663Y1429368D01*
X332288Y1429534D01*
X331788Y1429618D01*
X331497Y1429784D01*
X331372Y1430076D01*
X331455Y1430368D01*
X331663Y1430576D01*
X331955Y1430701D01*
X332247D01*
X332538Y1430618D01*
X332788Y1430409D01*
G01X334347Y1428201D02*
Y1430701D01*
X335388D01*
X335722Y1430576D01*
X335930Y1430409D01*
X336013Y1430076D01*
X335930Y1429743D01*
X335680Y1429534D01*
X335388Y1429409D01*
X334347D01*
G01X335388D02*
X336013Y1428201D01*
G01X337572Y1428493D02*
X337863Y1428284D01*
X338197Y1428201D01*
X338530Y1428284D01*
X338822Y1428534D01*
X339030Y1428909D01*
X339113Y1429284D01*
Y1429743D01*
X339030Y1430118D01*
X338822Y1430451D01*
X338572Y1430618D01*
X338280Y1430701D01*
X337947Y1430618D01*
X337697Y1430451D01*
X337530Y1430201D01*
X337447Y1429868D01*
X337530Y1429576D01*
X337738Y1429284D01*
X337988Y1429118D01*
X338280Y1429076D01*
X338613Y1429159D01*
X338863Y1429368D01*
X339113Y1429743D01*
G01X341380Y1428201D02*
X341672Y1428243D01*
X342005Y1428368D01*
X342213Y1428576D01*
X342297Y1428868D01*
X342213Y1429159D01*
X341963Y1429409D01*
X341588Y1429534D01*
X341172D01*
X340922Y1429618D01*
X340713Y1429826D01*
X340630Y1430118D01*
X340755Y1430409D01*
X341047Y1430618D01*
X341380Y1430701D01*
X341713Y1430618D01*
X342005Y1430409D01*
X342130Y1430118D01*
X342047Y1429826D01*
X341838Y1429618D01*
X341588Y1429534D01*
X341172D01*
X340797Y1429409D01*
X340547Y1429159D01*
X340463Y1428868D01*
X340547Y1428576D01*
X340755Y1428368D01*
X341088Y1428243D01*
X341380Y1428201D01*
G01X344397D02*
X344480Y1428743D01*
X344605Y1429201D01*
X344772Y1429618D01*
X344980Y1430076D01*
X345313Y1430701D01*
X343647D01*
G01X331205Y1416334D02*
X331538Y1416126D01*
X331913Y1416001D01*
X332247D01*
X332580Y1416126D01*
X332830Y1416334D01*
X332955Y1416626D01*
X332872Y1416918D01*
X332663Y1417168D01*
X332288Y1417334D01*
X331788Y1417418D01*
X331497Y1417584D01*
X331372Y1417876D01*
X331455Y1418168D01*
X331663Y1418376D01*
X331955Y1418501D01*
X332247D01*
X332538Y1418418D01*
X332788Y1418209D01*
G01X334347Y1416001D02*
Y1418501D01*
X335388D01*
X335722Y1418376D01*
X335930Y1418209D01*
X336013Y1417876D01*
X335930Y1417543D01*
X335680Y1417334D01*
X335388Y1417209D01*
X334347D01*
G01X335388D02*
X336013Y1416001D01*
G01X337572Y1416293D02*
X337863Y1416084D01*
X338197Y1416001D01*
X338530Y1416084D01*
X338822Y1416334D01*
X339030Y1416709D01*
X339113Y1417084D01*
Y1417543D01*
X339030Y1417918D01*
X338822Y1418251D01*
X338572Y1418418D01*
X338280Y1418501D01*
X337947Y1418418D01*
X337697Y1418251D01*
X337530Y1418001D01*
X337447Y1417668D01*
X337530Y1417376D01*
X337738Y1417084D01*
X337988Y1416918D01*
X338280Y1416876D01*
X338613Y1416959D01*
X338863Y1417168D01*
X339113Y1417543D01*
G01X340672Y1416293D02*
X340963Y1416084D01*
X341297Y1416001D01*
X341630Y1416084D01*
X341922Y1416334D01*
X342130Y1416709D01*
X342213Y1417084D01*
Y1417543D01*
X342130Y1417918D01*
X341922Y1418251D01*
X341672Y1418418D01*
X341380Y1418501D01*
X341047Y1418418D01*
X340797Y1418251D01*
X340630Y1418001D01*
X340547Y1417668D01*
X340630Y1417376D01*
X340838Y1417084D01*
X341088Y1416918D01*
X341380Y1416876D01*
X341713Y1416959D01*
X341963Y1417168D01*
X342213Y1417543D01*
G01X344480Y1418501D02*
X344147Y1418418D01*
X343897Y1418209D01*
X343730Y1417959D01*
X343605Y1417626D01*
X343563Y1417251D01*
X343605Y1416876D01*
X343730Y1416543D01*
X343897Y1416293D01*
X344147Y1416084D01*
X344480Y1416001D01*
X344813Y1416084D01*
X345063Y1416293D01*
X345230Y1416543D01*
X345355Y1416876D01*
X345397Y1417251D01*
X345355Y1417626D01*
X345230Y1417959D01*
X345063Y1418209D01*
X344813Y1418418D01*
X344480Y1418501D01*
G01X331205Y1424534D02*
X331538Y1424326D01*
X331913Y1424201D01*
X332247D01*
X332580Y1424326D01*
X332830Y1424534D01*
X332955Y1424826D01*
X332872Y1425118D01*
X332663Y1425368D01*
X332288Y1425534D01*
X331788Y1425618D01*
X331497Y1425784D01*
X331372Y1426076D01*
X331455Y1426368D01*
X331663Y1426576D01*
X331955Y1426701D01*
X332247D01*
X332538Y1426618D01*
X332788Y1426409D01*
G01X334347Y1424201D02*
Y1426701D01*
X335388D01*
X335722Y1426576D01*
X335930Y1426409D01*
X336013Y1426076D01*
X335930Y1425743D01*
X335680Y1425534D01*
X335388Y1425409D01*
X334347D01*
G01X335388D02*
X336013Y1424201D01*
G01X337572Y1424493D02*
X337863Y1424284D01*
X338197Y1424201D01*
X338530Y1424284D01*
X338822Y1424534D01*
X339030Y1424909D01*
X339113Y1425284D01*
Y1425743D01*
X339030Y1426118D01*
X338822Y1426451D01*
X338572Y1426618D01*
X338280Y1426701D01*
X337947Y1426618D01*
X337697Y1426451D01*
X337530Y1426201D01*
X337447Y1425868D01*
X337530Y1425576D01*
X337738Y1425284D01*
X337988Y1425118D01*
X338280Y1425076D01*
X338613Y1425159D01*
X338863Y1425368D01*
X339113Y1425743D01*
G01X340672Y1424493D02*
X340963Y1424284D01*
X341297Y1424201D01*
X341630Y1424284D01*
X341922Y1424534D01*
X342130Y1424909D01*
X342213Y1425284D01*
Y1425743D01*
X342130Y1426118D01*
X341922Y1426451D01*
X341672Y1426618D01*
X341380Y1426701D01*
X341047Y1426618D01*
X340797Y1426451D01*
X340630Y1426201D01*
X340547Y1425868D01*
X340630Y1425576D01*
X340838Y1425284D01*
X341088Y1425118D01*
X341380Y1425076D01*
X341713Y1425159D01*
X341963Y1425368D01*
X342213Y1425743D01*
G01X344480Y1424201D02*
Y1426701D01*
X343980Y1426201D01*
G01Y1424201D02*
X344980D01*
G01X331205Y1404234D02*
X331538Y1404026D01*
X331913Y1403901D01*
X332247D01*
X332580Y1404026D01*
X332830Y1404234D01*
X332955Y1404526D01*
X332872Y1404818D01*
X332663Y1405068D01*
X332288Y1405234D01*
X331788Y1405318D01*
X331497Y1405484D01*
X331372Y1405776D01*
X331455Y1406068D01*
X331663Y1406276D01*
X331955Y1406401D01*
X332247D01*
X332538Y1406318D01*
X332788Y1406109D01*
G01X334347Y1403901D02*
Y1406401D01*
X335388D01*
X335722Y1406276D01*
X335930Y1406109D01*
X336013Y1405776D01*
X335930Y1405443D01*
X335680Y1405234D01*
X335388Y1405109D01*
X334347D01*
G01X335388D02*
X336013Y1403901D01*
G01X337572Y1404193D02*
X337863Y1403984D01*
X338197Y1403901D01*
X338530Y1403984D01*
X338822Y1404234D01*
X339030Y1404609D01*
X339113Y1404984D01*
Y1405443D01*
X339030Y1405818D01*
X338822Y1406151D01*
X338572Y1406318D01*
X338280Y1406401D01*
X337947Y1406318D01*
X337697Y1406151D01*
X337530Y1405901D01*
X337447Y1405568D01*
X337530Y1405276D01*
X337738Y1404984D01*
X337988Y1404818D01*
X338280Y1404776D01*
X338613Y1404859D01*
X338863Y1405068D01*
X339113Y1405443D01*
G01X340672Y1404193D02*
X340963Y1403984D01*
X341297Y1403901D01*
X341630Y1403984D01*
X341922Y1404234D01*
X342130Y1404609D01*
X342213Y1404984D01*
Y1405443D01*
X342130Y1405818D01*
X341922Y1406151D01*
X341672Y1406318D01*
X341380Y1406401D01*
X341047Y1406318D01*
X340797Y1406151D01*
X340630Y1405901D01*
X340547Y1405568D01*
X340630Y1405276D01*
X340838Y1404984D01*
X341088Y1404818D01*
X341380Y1404776D01*
X341713Y1404859D01*
X341963Y1405068D01*
X342213Y1405443D01*
G01X343688Y1405984D02*
X343938Y1406234D01*
X344230Y1406359D01*
X344563Y1406401D01*
X344980Y1406318D01*
X345272Y1406109D01*
X345355Y1405859D01*
X345313Y1405609D01*
X345147Y1405401D01*
X344313Y1404984D01*
X343938Y1404693D01*
X343688Y1404276D01*
X343605Y1403901D01*
X345355D01*
G01X331205Y1412334D02*
X331538Y1412126D01*
X331913Y1412001D01*
X332247D01*
X332580Y1412126D01*
X332830Y1412334D01*
X332955Y1412626D01*
X332872Y1412918D01*
X332663Y1413168D01*
X332288Y1413334D01*
X331788Y1413418D01*
X331497Y1413584D01*
X331372Y1413876D01*
X331455Y1414168D01*
X331663Y1414376D01*
X331955Y1414501D01*
X332247D01*
X332538Y1414418D01*
X332788Y1414209D01*
G01X334347Y1412001D02*
Y1414501D01*
X335388D01*
X335722Y1414376D01*
X335930Y1414209D01*
X336013Y1413876D01*
X335930Y1413543D01*
X335680Y1413334D01*
X335388Y1413209D01*
X334347D01*
G01X335388D02*
X336013Y1412001D01*
G01X337572Y1412293D02*
X337863Y1412084D01*
X338197Y1412001D01*
X338530Y1412084D01*
X338822Y1412334D01*
X339030Y1412709D01*
X339113Y1413084D01*
Y1413543D01*
X339030Y1413918D01*
X338822Y1414251D01*
X338572Y1414418D01*
X338280Y1414501D01*
X337947Y1414418D01*
X337697Y1414251D01*
X337530Y1414001D01*
X337447Y1413668D01*
X337530Y1413376D01*
X337738Y1413084D01*
X337988Y1412918D01*
X338280Y1412876D01*
X338613Y1412959D01*
X338863Y1413168D01*
X339113Y1413543D01*
G01X340672Y1412293D02*
X340963Y1412084D01*
X341297Y1412001D01*
X341630Y1412084D01*
X341922Y1412334D01*
X342130Y1412709D01*
X342213Y1413084D01*
Y1413543D01*
X342130Y1413918D01*
X341922Y1414251D01*
X341672Y1414418D01*
X341380Y1414501D01*
X341047Y1414418D01*
X340797Y1414251D01*
X340630Y1414001D01*
X340547Y1413668D01*
X340630Y1413376D01*
X340838Y1413084D01*
X341088Y1412918D01*
X341380Y1412876D01*
X341713Y1412959D01*
X341963Y1413168D01*
X342213Y1413543D01*
G01X343563Y1412501D02*
X343813Y1412209D01*
X344147Y1412043D01*
X344522Y1412001D01*
X344855Y1412043D01*
X345188Y1412251D01*
X345397Y1412501D01*
X345438Y1412751D01*
X345355Y1413043D01*
X345063Y1413251D01*
X344772Y1413334D01*
X344397D01*
G01X344772D02*
X345022Y1413459D01*
X345230Y1413668D01*
X345313Y1413918D01*
X345230Y1414168D01*
X345022Y1414376D01*
X344647Y1414501D01*
X344272Y1414459D01*
X343897Y1414293D01*
G01X331205Y1436534D02*
X331538Y1436326D01*
X331913Y1436201D01*
X332247D01*
X332580Y1436326D01*
X332830Y1436534D01*
X332955Y1436826D01*
X332872Y1437118D01*
X332663Y1437368D01*
X332288Y1437534D01*
X331788Y1437618D01*
X331497Y1437784D01*
X331372Y1438076D01*
X331455Y1438368D01*
X331663Y1438576D01*
X331955Y1438701D01*
X332247D01*
X332538Y1438618D01*
X332788Y1438409D01*
G01X334347Y1436201D02*
Y1438701D01*
X335388D01*
X335722Y1438576D01*
X335930Y1438409D01*
X336013Y1438076D01*
X335930Y1437743D01*
X335680Y1437534D01*
X335388Y1437409D01*
X334347D01*
G01X335388D02*
X336013Y1436201D01*
G01X337572Y1436493D02*
X337863Y1436284D01*
X338197Y1436201D01*
X338530Y1436284D01*
X338822Y1436534D01*
X339030Y1436909D01*
X339113Y1437284D01*
Y1437743D01*
X339030Y1438118D01*
X338822Y1438451D01*
X338572Y1438618D01*
X338280Y1438701D01*
X337947Y1438618D01*
X337697Y1438451D01*
X337530Y1438201D01*
X337447Y1437868D01*
X337530Y1437576D01*
X337738Y1437284D01*
X337988Y1437118D01*
X338280Y1437076D01*
X338613Y1437159D01*
X338863Y1437368D01*
X339113Y1437743D01*
G01X341380Y1436201D02*
X341672Y1436243D01*
X342005Y1436368D01*
X342213Y1436576D01*
X342297Y1436868D01*
X342213Y1437159D01*
X341963Y1437409D01*
X341588Y1437534D01*
X341172D01*
X340922Y1437618D01*
X340713Y1437826D01*
X340630Y1438118D01*
X340755Y1438409D01*
X341047Y1438618D01*
X341380Y1438701D01*
X341713Y1438618D01*
X342005Y1438409D01*
X342130Y1438118D01*
X342047Y1437826D01*
X341838Y1437618D01*
X341588Y1437534D01*
X341172D01*
X340797Y1437409D01*
X340547Y1437159D01*
X340463Y1436868D01*
X340547Y1436576D01*
X340755Y1436368D01*
X341088Y1436243D01*
X341380Y1436201D01*
G01X343772Y1436493D02*
X344063Y1436284D01*
X344397Y1436201D01*
X344730Y1436284D01*
X345022Y1436534D01*
X345230Y1436909D01*
X345313Y1437284D01*
Y1437743D01*
X345230Y1438118D01*
X345022Y1438451D01*
X344772Y1438618D01*
X344480Y1438701D01*
X344147Y1438618D01*
X343897Y1438451D01*
X343730Y1438201D01*
X343647Y1437868D01*
X343730Y1437576D01*
X343938Y1437284D01*
X344188Y1437118D01*
X344480Y1437076D01*
X344813Y1437159D01*
X345063Y1437368D01*
X345313Y1437743D01*
G01X364551Y1630342D02*
Y1632842D01*
X365592D01*
X365926Y1632717D01*
X366134Y1632550D01*
X366217Y1632217D01*
X366134Y1631884D01*
X365884Y1631675D01*
X365592Y1631550D01*
X364551D01*
G01X365592D02*
X366217Y1630342D01*
G01X368484D02*
Y1632842D01*
X367984Y1632342D01*
G01Y1630342D02*
X368984D01*
G01X370792Y1632425D02*
X371042Y1632675D01*
X371334Y1632800D01*
X371667Y1632842D01*
X372084Y1632759D01*
X372376Y1632550D01*
X372459Y1632300D01*
X372417Y1632050D01*
X372251Y1631842D01*
X371417Y1631425D01*
X371042Y1631134D01*
X370792Y1630717D01*
X370709Y1630342D01*
X372459D01*
G01X373767Y1630842D02*
X374017Y1630550D01*
X374351Y1630384D01*
X374726Y1630342D01*
X375059Y1630384D01*
X375392Y1630592D01*
X375601Y1630842D01*
X375642Y1631092D01*
X375559Y1631384D01*
X375267Y1631592D01*
X374976Y1631675D01*
X374601D01*
G01X374976D02*
X375226Y1631800D01*
X375434Y1632009D01*
X375517Y1632259D01*
X375434Y1632509D01*
X375226Y1632717D01*
X374851Y1632842D01*
X374476Y1632800D01*
X374101Y1632634D01*
G01X350200Y1639000D02*
Y1643000D01*
X342800D01*
G01X378291Y1630192D02*
Y1632692D01*
X379332D01*
X379666Y1632567D01*
X379874Y1632400D01*
X379957Y1632067D01*
X379874Y1631734D01*
X379624Y1631525D01*
X379332Y1631400D01*
X378291D01*
G01X379332D02*
X379957Y1630192D01*
G01X382224D02*
Y1632692D01*
X381724Y1632192D01*
G01Y1630192D02*
X382724D01*
G01X384532Y1632275D02*
X384782Y1632525D01*
X385074Y1632650D01*
X385407Y1632692D01*
X385824Y1632609D01*
X386116Y1632400D01*
X386199Y1632150D01*
X386157Y1631900D01*
X385991Y1631692D01*
X385157Y1631275D01*
X384782Y1630984D01*
X384532Y1630567D01*
X384449Y1630192D01*
X386199D01*
G01X388924D02*
Y1632692D01*
X387382Y1630900D01*
X389466D01*
G01X358200Y1639000D02*
Y1643000D01*
X350800D01*
G01X380834Y1634967D02*
X378334D01*
Y1636008D01*
X378459Y1636342D01*
X378626Y1636550D01*
X378959Y1636633D01*
X379292Y1636550D01*
X379501Y1636300D01*
X379626Y1636008D01*
Y1634967D01*
G01Y1636008D02*
X380834Y1636633D01*
G01X380542Y1638192D02*
X380751Y1638483D01*
X380834Y1638817D01*
X380751Y1639150D01*
X380501Y1639442D01*
X380126Y1639650D01*
X379751Y1639733D01*
X379292D01*
X378917Y1639650D01*
X378584Y1639442D01*
X378417Y1639192D01*
X378334Y1638900D01*
X378417Y1638567D01*
X378584Y1638317D01*
X378834Y1638150D01*
X379167Y1638067D01*
X379459Y1638150D01*
X379751Y1638358D01*
X379917Y1638608D01*
X379959Y1638900D01*
X379876Y1639233D01*
X379667Y1639483D01*
X379292Y1639733D01*
G01X379792Y1641208D02*
X379501Y1641500D01*
X379334Y1641750D01*
X379251Y1642083D01*
X379334Y1642375D01*
X379501Y1642583D01*
X379751Y1642750D01*
X380042Y1642792D01*
X380292Y1642750D01*
X380542Y1642583D01*
X380751Y1642333D01*
X380834Y1642042D01*
X380751Y1641708D01*
X380501Y1641417D01*
X380126Y1641250D01*
X379709Y1641208D01*
X379167Y1641292D01*
X378876Y1641417D01*
X378584Y1641625D01*
X378376Y1641917D01*
X378334Y1642208D01*
X378417Y1642500D01*
X378626Y1642708D01*
G01X378334Y1645100D02*
X378417Y1644767D01*
X378626Y1644517D01*
X378876Y1644350D01*
X379209Y1644225D01*
X379584Y1644183D01*
X379959Y1644225D01*
X380292Y1644350D01*
X380542Y1644517D01*
X380751Y1644767D01*
X380834Y1645100D01*
X380751Y1645433D01*
X380542Y1645683D01*
X380292Y1645850D01*
X379959Y1645975D01*
X379584Y1646017D01*
X379209Y1645975D01*
X378876Y1645850D01*
X378626Y1645683D01*
X378417Y1645433D01*
X378334Y1645100D01*
G01X380542Y1647492D02*
X380751Y1647783D01*
X380834Y1648117D01*
X380751Y1648450D01*
X380501Y1648742D01*
X380126Y1648950D01*
X379751Y1649033D01*
X379292D01*
X378917Y1648950D01*
X378584Y1648742D01*
X378417Y1648492D01*
X378334Y1648200D01*
X378417Y1647867D01*
X378584Y1647617D01*
X378834Y1647450D01*
X379167Y1647367D01*
X379459Y1647450D01*
X379751Y1647658D01*
X379917Y1647908D01*
X379959Y1648200D01*
X379876Y1648533D01*
X379667Y1648783D01*
X379292Y1649033D01*
G01X351000Y1643300D02*
X355000D01*
Y1650700D01*
G01X373834Y1634818D02*
X371334D01*
Y1635859D01*
X371459Y1636193D01*
X371626Y1636401D01*
X371959Y1636484D01*
X372292Y1636401D01*
X372501Y1636151D01*
X372626Y1635859D01*
Y1634818D01*
G01Y1635859D02*
X373834Y1636484D01*
G01X373542Y1638043D02*
X373751Y1638334D01*
X373834Y1638668D01*
X373751Y1639001D01*
X373501Y1639293D01*
X373126Y1639501D01*
X372751Y1639584D01*
X372292D01*
X371917Y1639501D01*
X371584Y1639293D01*
X371417Y1639043D01*
X371334Y1638751D01*
X371417Y1638418D01*
X371584Y1638168D01*
X371834Y1638001D01*
X372167Y1637918D01*
X372459Y1638001D01*
X372751Y1638209D01*
X372917Y1638459D01*
X372959Y1638751D01*
X372876Y1639084D01*
X372667Y1639334D01*
X372292Y1639584D01*
G01X372792Y1641059D02*
X372501Y1641351D01*
X372334Y1641601D01*
X372251Y1641934D01*
X372334Y1642226D01*
X372501Y1642434D01*
X372751Y1642601D01*
X373042Y1642643D01*
X373292Y1642601D01*
X373542Y1642434D01*
X373751Y1642184D01*
X373834Y1641893D01*
X373751Y1641559D01*
X373501Y1641268D01*
X373126Y1641101D01*
X372709Y1641059D01*
X372167Y1641143D01*
X371876Y1641268D01*
X371584Y1641476D01*
X371376Y1641768D01*
X371334Y1642059D01*
X371417Y1642351D01*
X371626Y1642559D01*
G01X371334Y1644951D02*
X371417Y1644618D01*
X371626Y1644368D01*
X371876Y1644201D01*
X372209Y1644076D01*
X372584Y1644034D01*
X372959Y1644076D01*
X373292Y1644201D01*
X373542Y1644368D01*
X373751Y1644618D01*
X373834Y1644951D01*
X373751Y1645284D01*
X373542Y1645534D01*
X373292Y1645701D01*
X372959Y1645826D01*
X372584Y1645868D01*
X372209Y1645826D01*
X371876Y1645701D01*
X371626Y1645534D01*
X371417Y1645284D01*
X371334Y1644951D01*
G01X373834Y1648051D02*
X373792Y1648343D01*
X373667Y1648676D01*
X373459Y1648884D01*
X373167Y1648968D01*
X372876Y1648884D01*
X372626Y1648634D01*
X372501Y1648259D01*
Y1647843D01*
X372417Y1647593D01*
X372209Y1647384D01*
X371917Y1647301D01*
X371626Y1647426D01*
X371417Y1647718D01*
X371334Y1648051D01*
X371417Y1648384D01*
X371626Y1648676D01*
X371917Y1648801D01*
X372209Y1648718D01*
X372417Y1648509D01*
X372501Y1648259D01*
Y1647843D01*
X372626Y1647468D01*
X372876Y1647218D01*
X373167Y1647134D01*
X373459Y1647218D01*
X373667Y1647426D01*
X373792Y1647759D01*
X373834Y1648051D01*
G01X343000Y1643300D02*
X347000D01*
Y1650700D01*
G01X366221Y1653294D02*
X365971Y1653419D01*
X365679Y1653502D01*
X365346D01*
X364971Y1653377D01*
X364679Y1653169D01*
X364471Y1652919D01*
X364304Y1652502D01*
X364262Y1652127D01*
X364346Y1651752D01*
X364471Y1651502D01*
X364721Y1651252D01*
X365012Y1651085D01*
X365304Y1651002D01*
X365596D01*
X365887Y1651085D01*
X366137Y1651210D01*
X366346Y1651377D01*
G01X368404Y1651002D02*
Y1653502D01*
X367904Y1653002D01*
G01Y1651002D02*
X368904D01*
G01X370587Y1651502D02*
X370837Y1651210D01*
X371171Y1651044D01*
X371546Y1651002D01*
X371879Y1651044D01*
X372212Y1651252D01*
X372421Y1651502D01*
X372462Y1651752D01*
X372379Y1652044D01*
X372087Y1652252D01*
X371796Y1652335D01*
X371421D01*
G01X371796D02*
X372046Y1652460D01*
X372254Y1652669D01*
X372337Y1652919D01*
X372254Y1653169D01*
X372046Y1653377D01*
X371671Y1653502D01*
X371296Y1653460D01*
X370921Y1653294D01*
G01X374604Y1651002D02*
Y1653502D01*
X374104Y1653002D01*
G01Y1651002D02*
X375104D01*
G01X379961Y1653144D02*
X379711Y1653269D01*
X379419Y1653352D01*
X379086D01*
X378711Y1653227D01*
X378419Y1653019D01*
X378211Y1652769D01*
X378044Y1652352D01*
X378002Y1651977D01*
X378086Y1651602D01*
X378211Y1651352D01*
X378461Y1651102D01*
X378752Y1650935D01*
X379044Y1650852D01*
X379336D01*
X379627Y1650935D01*
X379877Y1651060D01*
X380086Y1651227D01*
G01X382144Y1650852D02*
Y1653352D01*
X381644Y1652852D01*
G01Y1650852D02*
X382644D01*
G01X384327Y1651352D02*
X384577Y1651060D01*
X384911Y1650894D01*
X385286Y1650852D01*
X385619Y1650894D01*
X385952Y1651102D01*
X386161Y1651352D01*
X386202Y1651602D01*
X386119Y1651894D01*
X385827Y1652102D01*
X385536Y1652185D01*
X385161D01*
G01X385536D02*
X385786Y1652310D01*
X385994Y1652519D01*
X386077Y1652769D01*
X385994Y1653019D01*
X385786Y1653227D01*
X385411Y1653352D01*
X385036Y1653310D01*
X384661Y1653144D01*
G01X387552Y1652935D02*
X387802Y1653185D01*
X388094Y1653310D01*
X388427Y1653352D01*
X388844Y1653269D01*
X389136Y1653060D01*
X389219Y1652810D01*
X389177Y1652560D01*
X389011Y1652352D01*
X388177Y1651935D01*
X387802Y1651644D01*
X387552Y1651227D01*
X387469Y1650852D01*
X389219D01*
G01X387388Y1659367D02*
X387263Y1659117D01*
X387180Y1658825D01*
Y1658492D01*
X387305Y1658117D01*
X387513Y1657825D01*
X387763Y1657617D01*
X388180Y1657450D01*
X388555Y1657408D01*
X388930Y1657492D01*
X389180Y1657617D01*
X389430Y1657867D01*
X389597Y1658158D01*
X389680Y1658450D01*
Y1658742D01*
X389597Y1659033D01*
X389472Y1659283D01*
X389305Y1659492D01*
G01X389680Y1661550D02*
X389638Y1661842D01*
X389513Y1662175D01*
X389305Y1662383D01*
X389013Y1662467D01*
X388722Y1662383D01*
X388472Y1662133D01*
X388347Y1661758D01*
Y1661342D01*
X388263Y1661092D01*
X388055Y1660883D01*
X387763Y1660800D01*
X387472Y1660925D01*
X387263Y1661217D01*
X387180Y1661550D01*
X387263Y1661883D01*
X387472Y1662175D01*
X387763Y1662300D01*
X388055Y1662217D01*
X388263Y1662008D01*
X388347Y1661758D01*
Y1661342D01*
X388472Y1660967D01*
X388722Y1660717D01*
X389013Y1660633D01*
X389305Y1660717D01*
X389513Y1660925D01*
X389638Y1661258D01*
X389680Y1661550D01*
G01Y1664650D02*
X389638Y1664942D01*
X389513Y1665275D01*
X389305Y1665483D01*
X389013Y1665567D01*
X388722Y1665483D01*
X388472Y1665233D01*
X388347Y1664858D01*
Y1664442D01*
X388263Y1664192D01*
X388055Y1663983D01*
X387763Y1663900D01*
X387472Y1664025D01*
X387263Y1664317D01*
X387180Y1664650D01*
X387263Y1664983D01*
X387472Y1665275D01*
X387763Y1665400D01*
X388055Y1665317D01*
X388263Y1665108D01*
X388347Y1664858D01*
Y1664442D01*
X388472Y1664067D01*
X388722Y1663817D01*
X389013Y1663733D01*
X389305Y1663817D01*
X389513Y1664025D01*
X389638Y1664358D01*
X389680Y1664650D01*
G01X389180Y1666833D02*
X389472Y1667083D01*
X389638Y1667417D01*
X389680Y1667792D01*
X389638Y1668125D01*
X389430Y1668458D01*
X389180Y1668667D01*
X388930Y1668708D01*
X388638Y1668625D01*
X388430Y1668333D01*
X388347Y1668042D01*
Y1667667D01*
G01Y1668042D02*
X388222Y1668292D01*
X388013Y1668500D01*
X387763Y1668583D01*
X387513Y1668500D01*
X387305Y1668292D01*
X387180Y1667917D01*
X387222Y1667542D01*
X387388Y1667167D01*
G01X389680Y1670767D02*
X389138Y1670850D01*
X388680Y1670975D01*
X388263Y1671142D01*
X387805Y1671350D01*
X387180Y1671683D01*
Y1670017D01*
G01X394217Y1677292D02*
X393967Y1677417D01*
X393675Y1677500D01*
X393342D01*
X392967Y1677375D01*
X392675Y1677167D01*
X392467Y1676917D01*
X392300Y1676500D01*
X392258Y1676125D01*
X392342Y1675750D01*
X392467Y1675500D01*
X392717Y1675250D01*
X393008Y1675083D01*
X393300Y1675000D01*
X393592D01*
X393883Y1675083D01*
X394133Y1675208D01*
X394342Y1675375D01*
G01X396400Y1675000D02*
X396692Y1675042D01*
X397025Y1675167D01*
X397233Y1675375D01*
X397317Y1675667D01*
X397233Y1675958D01*
X396983Y1676208D01*
X396608Y1676333D01*
X396192D01*
X395942Y1676417D01*
X395733Y1676625D01*
X395650Y1676917D01*
X395775Y1677208D01*
X396067Y1677417D01*
X396400Y1677500D01*
X396733Y1677417D01*
X397025Y1677208D01*
X397150Y1676917D01*
X397067Y1676625D01*
X396858Y1676417D01*
X396608Y1676333D01*
X396192D01*
X395817Y1676208D01*
X395567Y1675958D01*
X395483Y1675667D01*
X395567Y1675375D01*
X395775Y1675167D01*
X396108Y1675042D01*
X396400Y1675000D01*
G01X399500D02*
X399792Y1675042D01*
X400125Y1675167D01*
X400333Y1675375D01*
X400417Y1675667D01*
X400333Y1675958D01*
X400083Y1676208D01*
X399708Y1676333D01*
X399292D01*
X399042Y1676417D01*
X398833Y1676625D01*
X398750Y1676917D01*
X398875Y1677208D01*
X399167Y1677417D01*
X399500Y1677500D01*
X399833Y1677417D01*
X400125Y1677208D01*
X400250Y1676917D01*
X400167Y1676625D01*
X399958Y1676417D01*
X399708Y1676333D01*
X399292D01*
X398917Y1676208D01*
X398667Y1675958D01*
X398583Y1675667D01*
X398667Y1675375D01*
X398875Y1675167D01*
X399208Y1675042D01*
X399500Y1675000D01*
G01X401683Y1675500D02*
X401933Y1675208D01*
X402267Y1675042D01*
X402642Y1675000D01*
X402975Y1675042D01*
X403308Y1675250D01*
X403517Y1675500D01*
X403558Y1675750D01*
X403475Y1676042D01*
X403183Y1676250D01*
X402892Y1676333D01*
X402517D01*
G01X402892D02*
X403142Y1676458D01*
X403350Y1676667D01*
X403433Y1676917D01*
X403350Y1677167D01*
X403142Y1677375D01*
X402767Y1677500D01*
X402392Y1677458D01*
X402017Y1677292D01*
G01X405700Y1675000D02*
X405992Y1675042D01*
X406325Y1675167D01*
X406533Y1675375D01*
X406617Y1675667D01*
X406533Y1675958D01*
X406283Y1676208D01*
X405908Y1676333D01*
X405492D01*
X405242Y1676417D01*
X405033Y1676625D01*
X404950Y1676917D01*
X405075Y1677208D01*
X405367Y1677417D01*
X405700Y1677500D01*
X406033Y1677417D01*
X406325Y1677208D01*
X406450Y1676917D01*
X406367Y1676625D01*
X406158Y1676417D01*
X405908Y1676333D01*
X405492D01*
X405117Y1676208D01*
X404867Y1675958D01*
X404783Y1675667D01*
X404867Y1675375D01*
X405075Y1675167D01*
X405408Y1675042D01*
X405700Y1675000D01*
G01X382637Y1659157D02*
X382512Y1658907D01*
X382429Y1658615D01*
Y1658282D01*
X382554Y1657907D01*
X382762Y1657615D01*
X383012Y1657407D01*
X383429Y1657240D01*
X383804Y1657198D01*
X384179Y1657282D01*
X384429Y1657407D01*
X384679Y1657657D01*
X384846Y1657948D01*
X384929Y1658240D01*
Y1658532D01*
X384846Y1658823D01*
X384721Y1659073D01*
X384554Y1659282D01*
G01X384637Y1660632D02*
X384846Y1660923D01*
X384929Y1661257D01*
X384846Y1661590D01*
X384596Y1661882D01*
X384221Y1662090D01*
X383846Y1662173D01*
X383387D01*
X383012Y1662090D01*
X382679Y1661882D01*
X382512Y1661632D01*
X382429Y1661340D01*
X382512Y1661007D01*
X382679Y1660757D01*
X382929Y1660590D01*
X383262Y1660507D01*
X383554Y1660590D01*
X383846Y1660798D01*
X384012Y1661048D01*
X384054Y1661340D01*
X383971Y1661673D01*
X383762Y1661923D01*
X383387Y1662173D01*
G01X384554Y1663523D02*
X384762Y1663773D01*
X384887Y1664065D01*
X384929Y1664440D01*
X384846Y1664815D01*
X384679Y1665107D01*
X384387Y1665315D01*
X384054Y1665357D01*
X383721Y1665273D01*
X383512Y1665065D01*
X383346Y1664773D01*
X383304Y1664482D01*
X383346Y1664190D01*
X383512Y1663815D01*
X382429Y1663940D01*
Y1665065D01*
G01X384929Y1667540D02*
X382429D01*
X382929Y1667040D01*
G01X384929D02*
Y1668040D01*
G01Y1671140D02*
X382429D01*
X384221Y1669598D01*
Y1671682D01*
G01X332800Y1693000D02*
Y1689000D01*
X340200D01*
G01Y1693000D02*
Y1697000D01*
X332800D01*
G01X400300Y1723000D02*
Y1719000D01*
X407700D01*
G01X400300Y1708000D02*
Y1704000D01*
X407700D01*
G01X400300Y1712000D02*
Y1708000D01*
X407700D01*
G01X351297Y1655438D02*
X348797D01*
Y1656479D01*
X348922Y1656813D01*
X349089Y1657021D01*
X349422Y1657104D01*
X349755Y1657021D01*
X349964Y1656771D01*
X350089Y1656479D01*
Y1655438D01*
G01Y1656479D02*
X351297Y1657104D01*
G01X351005Y1658663D02*
X351214Y1658954D01*
X351297Y1659288D01*
X351214Y1659621D01*
X350964Y1659913D01*
X350589Y1660121D01*
X350214Y1660204D01*
X349755D01*
X349380Y1660121D01*
X349047Y1659913D01*
X348880Y1659663D01*
X348797Y1659371D01*
X348880Y1659038D01*
X349047Y1658788D01*
X349297Y1658621D01*
X349630Y1658538D01*
X349922Y1658621D01*
X350214Y1658829D01*
X350380Y1659079D01*
X350422Y1659371D01*
X350339Y1659704D01*
X350130Y1659954D01*
X349755Y1660204D01*
G01X348797Y1662471D02*
X348880Y1662138D01*
X349089Y1661888D01*
X349339Y1661721D01*
X349672Y1661596D01*
X350047Y1661554D01*
X350422Y1661596D01*
X350755Y1661721D01*
X351005Y1661888D01*
X351214Y1662138D01*
X351297Y1662471D01*
X351214Y1662804D01*
X351005Y1663054D01*
X350755Y1663221D01*
X350422Y1663346D01*
X350047Y1663388D01*
X349672Y1663346D01*
X349339Y1663221D01*
X349089Y1663054D01*
X348880Y1662804D01*
X348797Y1662471D01*
G01X350255Y1664779D02*
X349964Y1665071D01*
X349797Y1665321D01*
X349714Y1665654D01*
X349797Y1665946D01*
X349964Y1666154D01*
X350214Y1666321D01*
X350505Y1666363D01*
X350755Y1666321D01*
X351005Y1666154D01*
X351214Y1665904D01*
X351297Y1665613D01*
X351214Y1665279D01*
X350964Y1664988D01*
X350589Y1664821D01*
X350172Y1664779D01*
X349630Y1664863D01*
X349339Y1664988D01*
X349047Y1665196D01*
X348839Y1665488D01*
X348797Y1665779D01*
X348880Y1666071D01*
X349089Y1666279D01*
G01X351297Y1668671D02*
X351255Y1668963D01*
X351130Y1669296D01*
X350922Y1669504D01*
X350630Y1669588D01*
X350339Y1669504D01*
X350089Y1669254D01*
X349964Y1668879D01*
Y1668463D01*
X349880Y1668213D01*
X349672Y1668004D01*
X349380Y1667921D01*
X349089Y1668046D01*
X348880Y1668338D01*
X348797Y1668671D01*
X348880Y1669004D01*
X349089Y1669296D01*
X349380Y1669421D01*
X349672Y1669338D01*
X349880Y1669129D01*
X349964Y1668879D01*
Y1668463D01*
X350089Y1668088D01*
X350339Y1667838D01*
X350630Y1667754D01*
X350922Y1667838D01*
X351130Y1668046D01*
X351255Y1668379D01*
X351297Y1668671D01*
G01X357500Y1669700D02*
X353500D01*
Y1662300D01*
G01X342500Y1669700D02*
X338500D01*
Y1662300D01*
G01X365500Y1657467D02*
X363000D01*
Y1658508D01*
X363125Y1658842D01*
X363292Y1659050D01*
X363625Y1659133D01*
X363958Y1659050D01*
X364167Y1658800D01*
X364292Y1658508D01*
Y1657467D01*
G01Y1658508D02*
X365500Y1659133D01*
G01X365208Y1660692D02*
X365417Y1660983D01*
X365500Y1661317D01*
X365417Y1661650D01*
X365167Y1661942D01*
X364792Y1662150D01*
X364417Y1662233D01*
X363958D01*
X363583Y1662150D01*
X363250Y1661942D01*
X363083Y1661692D01*
X363000Y1661400D01*
X363083Y1661067D01*
X363250Y1660817D01*
X363500Y1660650D01*
X363833Y1660567D01*
X364125Y1660650D01*
X364417Y1660858D01*
X364583Y1661108D01*
X364625Y1661400D01*
X364542Y1661733D01*
X364333Y1661983D01*
X363958Y1662233D01*
G01X363000Y1664500D02*
X363083Y1664167D01*
X363292Y1663917D01*
X363542Y1663750D01*
X363875Y1663625D01*
X364250Y1663583D01*
X364625Y1663625D01*
X364958Y1663750D01*
X365208Y1663917D01*
X365417Y1664167D01*
X365500Y1664500D01*
X365417Y1664833D01*
X365208Y1665083D01*
X364958Y1665250D01*
X364625Y1665375D01*
X364250Y1665417D01*
X363875Y1665375D01*
X363542Y1665250D01*
X363292Y1665083D01*
X363083Y1664833D01*
X363000Y1664500D01*
G01X365500Y1667517D02*
X364958Y1667600D01*
X364500Y1667725D01*
X364083Y1667892D01*
X363625Y1668100D01*
X363000Y1668433D01*
Y1666767D01*
G01Y1670700D02*
X363083Y1670367D01*
X363292Y1670117D01*
X363542Y1669950D01*
X363875Y1669825D01*
X364250Y1669783D01*
X364625Y1669825D01*
X364958Y1669950D01*
X365208Y1670117D01*
X365417Y1670367D01*
X365500Y1670700D01*
X365417Y1671033D01*
X365208Y1671283D01*
X364958Y1671450D01*
X364625Y1671575D01*
X364250Y1671617D01*
X363875Y1671575D01*
X363542Y1671450D01*
X363292Y1671283D01*
X363083Y1671033D01*
X363000Y1670700D01*
G01X361500Y1669700D02*
X357500D01*
Y1662300D01*
G01X346500Y1669700D02*
X342500D01*
Y1662300D01*
G01X395793Y1679920D02*
X394127D01*
Y1682420D01*
X395793D01*
G01X395127Y1681212D02*
X394127D01*
G01X397143Y1682420D02*
Y1680628D01*
X397310Y1680253D01*
X397643Y1680003D01*
X398060Y1679920D01*
X398477Y1680003D01*
X398810Y1680253D01*
X398977Y1680628D01*
Y1682420D01*
G01X401160Y1679920D02*
Y1682420D01*
X400660Y1681920D01*
G01Y1679920D02*
X401660D01*
G01X391650Y1716050D02*
Y1721700D01*
X385700D01*
G01X386200Y1678350D02*
X391700D01*
Y1683450D01*
G01X348300Y1684300D02*
Y1678300D01*
X354550D01*
G01X382715Y1720515D02*
Y1723515D01*
G01X363000Y1720515D02*
Y1723515D01*
G01X380800Y1676485D02*
Y1679485D01*
G01X361100Y1676485D02*
Y1679485D01*
G01X371000D02*
Y1677485D01*
G01X390515Y1708800D02*
X392515D01*
G01X390515Y1689200D02*
X392515D01*
G01X393515Y1697100D02*
X390515D01*
G01X347485Y1687150D02*
X349485D01*
G01X347485Y1706900D02*
X349485D01*
G01Y1697085D02*
X346485D01*
G01X372800Y1722515D02*
Y1720515D01*
G01X365367Y1767983D02*
X365117Y1768108D01*
X364825Y1768191D01*
X364492D01*
X364117Y1768066D01*
X363825Y1767858D01*
X363617Y1767608D01*
X363450Y1767191D01*
X363408Y1766816D01*
X363492Y1766441D01*
X363617Y1766191D01*
X363867Y1765941D01*
X364158Y1765774D01*
X364450Y1765691D01*
X364742D01*
X365033Y1765774D01*
X365283Y1765899D01*
X365492Y1766066D01*
G01X366842Y1765983D02*
X367133Y1765774D01*
X367467Y1765691D01*
X367800Y1765774D01*
X368092Y1766024D01*
X368300Y1766399D01*
X368383Y1766774D01*
Y1767233D01*
X368300Y1767608D01*
X368092Y1767941D01*
X367842Y1768108D01*
X367550Y1768191D01*
X367217Y1768108D01*
X366967Y1767941D01*
X366800Y1767691D01*
X366717Y1767358D01*
X366800Y1767066D01*
X367008Y1766774D01*
X367258Y1766608D01*
X367550Y1766566D01*
X367883Y1766649D01*
X368133Y1766858D01*
X368383Y1767233D01*
G01X369733Y1766191D02*
X369983Y1765899D01*
X370317Y1765733D01*
X370692Y1765691D01*
X371025Y1765733D01*
X371358Y1765941D01*
X371567Y1766191D01*
X371608Y1766441D01*
X371525Y1766733D01*
X371233Y1766941D01*
X370942Y1767024D01*
X370567D01*
G01X370942D02*
X371192Y1767149D01*
X371400Y1767358D01*
X371483Y1767608D01*
X371400Y1767858D01*
X371192Y1768066D01*
X370817Y1768191D01*
X370442Y1768149D01*
X370067Y1767983D01*
G01X374250Y1765691D02*
Y1768191D01*
X372708Y1766399D01*
X374792D01*
G01X375933Y1766191D02*
X376183Y1765899D01*
X376517Y1765733D01*
X376892Y1765691D01*
X377225Y1765733D01*
X377558Y1765941D01*
X377767Y1766191D01*
X377808Y1766441D01*
X377725Y1766733D01*
X377433Y1766941D01*
X377142Y1767024D01*
X376767D01*
G01X377142D02*
X377392Y1767149D01*
X377600Y1767358D01*
X377683Y1767608D01*
X377600Y1767858D01*
X377392Y1768066D01*
X377017Y1768191D01*
X376642Y1768149D01*
X376267Y1767983D01*
G01X371543Y1740596D02*
X371418Y1740346D01*
X371335Y1740054D01*
Y1739721D01*
X371460Y1739346D01*
X371668Y1739054D01*
X371918Y1738846D01*
X372335Y1738679D01*
X372710Y1738637D01*
X373085Y1738721D01*
X373335Y1738846D01*
X373585Y1739096D01*
X373752Y1739387D01*
X373835Y1739679D01*
Y1739971D01*
X373752Y1740262D01*
X373627Y1740512D01*
X373460Y1740721D01*
G01X373543Y1742071D02*
X373752Y1742362D01*
X373835Y1742696D01*
X373752Y1743029D01*
X373502Y1743321D01*
X373127Y1743529D01*
X372752Y1743612D01*
X372293D01*
X371918Y1743529D01*
X371585Y1743321D01*
X371418Y1743071D01*
X371335Y1742779D01*
X371418Y1742446D01*
X371585Y1742196D01*
X371835Y1742029D01*
X372168Y1741946D01*
X372460Y1742029D01*
X372752Y1742237D01*
X372918Y1742487D01*
X372960Y1742779D01*
X372877Y1743112D01*
X372668Y1743362D01*
X372293Y1743612D01*
G01X373835Y1746379D02*
X371335D01*
X373127Y1744837D01*
Y1746921D01*
G01X373835Y1748979D02*
X371335D01*
X371835Y1748479D01*
G01X373835D02*
Y1749479D01*
G01Y1752079D02*
X373793Y1752371D01*
X373668Y1752704D01*
X373460Y1752912D01*
X373168Y1752996D01*
X372877Y1752912D01*
X372627Y1752662D01*
X372502Y1752287D01*
Y1751871D01*
X372418Y1751621D01*
X372210Y1751412D01*
X371918Y1751329D01*
X371627Y1751454D01*
X371418Y1751746D01*
X371335Y1752079D01*
X371418Y1752412D01*
X371627Y1752704D01*
X371918Y1752829D01*
X372210Y1752746D01*
X372418Y1752537D01*
X372502Y1752287D01*
Y1751871D01*
X372627Y1751496D01*
X372877Y1751246D01*
X373168Y1751162D01*
X373460Y1751246D01*
X373668Y1751454D01*
X373793Y1751787D01*
X373835Y1752079D01*
G01X343834Y1768419D02*
X343584Y1768544D01*
X343292Y1768627D01*
X342959D01*
X342584Y1768502D01*
X342292Y1768294D01*
X342084Y1768044D01*
X341917Y1767627D01*
X341875Y1767252D01*
X341959Y1766877D01*
X342084Y1766627D01*
X342334Y1766377D01*
X342625Y1766210D01*
X342917Y1766127D01*
X343209D01*
X343500Y1766210D01*
X343750Y1766335D01*
X343959Y1766502D01*
G01X345309Y1766419D02*
X345600Y1766210D01*
X345934Y1766127D01*
X346267Y1766210D01*
X346559Y1766460D01*
X346767Y1766835D01*
X346850Y1767210D01*
Y1767669D01*
X346767Y1768044D01*
X346559Y1768377D01*
X346309Y1768544D01*
X346017Y1768627D01*
X345684Y1768544D01*
X345434Y1768377D01*
X345267Y1768127D01*
X345184Y1767794D01*
X345267Y1767502D01*
X345475Y1767210D01*
X345725Y1767044D01*
X346017Y1767002D01*
X346350Y1767085D01*
X346600Y1767294D01*
X346850Y1767669D01*
G01X348200Y1766627D02*
X348450Y1766335D01*
X348784Y1766169D01*
X349159Y1766127D01*
X349492Y1766169D01*
X349825Y1766377D01*
X350034Y1766627D01*
X350075Y1766877D01*
X349992Y1767169D01*
X349700Y1767377D01*
X349409Y1767460D01*
X349034D01*
G01X349409D02*
X349659Y1767585D01*
X349867Y1767794D01*
X349950Y1768044D01*
X349867Y1768294D01*
X349659Y1768502D01*
X349284Y1768627D01*
X348909Y1768585D01*
X348534Y1768419D01*
G01X351425Y1767169D02*
X351717Y1767460D01*
X351967Y1767627D01*
X352300Y1767710D01*
X352592Y1767627D01*
X352800Y1767460D01*
X352967Y1767210D01*
X353009Y1766919D01*
X352967Y1766669D01*
X352800Y1766419D01*
X352550Y1766210D01*
X352259Y1766127D01*
X351925Y1766210D01*
X351634Y1766460D01*
X351467Y1766835D01*
X351425Y1767252D01*
X351509Y1767794D01*
X351634Y1768085D01*
X351842Y1768377D01*
X352134Y1768585D01*
X352425Y1768627D01*
X352717Y1768544D01*
X352925Y1768335D01*
G01X355234Y1766127D02*
X355317Y1766669D01*
X355442Y1767127D01*
X355609Y1767544D01*
X355817Y1768002D01*
X356150Y1768627D01*
X354484D01*
G01X375543Y1740596D02*
X375418Y1740346D01*
X375335Y1740054D01*
Y1739721D01*
X375460Y1739346D01*
X375668Y1739054D01*
X375918Y1738846D01*
X376335Y1738679D01*
X376710Y1738637D01*
X377085Y1738721D01*
X377335Y1738846D01*
X377585Y1739096D01*
X377752Y1739387D01*
X377835Y1739679D01*
Y1739971D01*
X377752Y1740262D01*
X377627Y1740512D01*
X377460Y1740721D01*
G01X377835Y1742779D02*
X377793Y1743071D01*
X377668Y1743404D01*
X377460Y1743612D01*
X377168Y1743696D01*
X376877Y1743612D01*
X376627Y1743362D01*
X376502Y1742987D01*
Y1742571D01*
X376418Y1742321D01*
X376210Y1742112D01*
X375918Y1742029D01*
X375627Y1742154D01*
X375418Y1742446D01*
X375335Y1742779D01*
X375418Y1743112D01*
X375627Y1743404D01*
X375918Y1743529D01*
X376210Y1743446D01*
X376418Y1743237D01*
X376502Y1742987D01*
Y1742571D01*
X376627Y1742196D01*
X376877Y1741946D01*
X377168Y1741862D01*
X377460Y1741946D01*
X377668Y1742154D01*
X377793Y1742487D01*
X377835Y1742779D01*
G01Y1745879D02*
X377793Y1746171D01*
X377668Y1746504D01*
X377460Y1746712D01*
X377168Y1746796D01*
X376877Y1746712D01*
X376627Y1746462D01*
X376502Y1746087D01*
Y1745671D01*
X376418Y1745421D01*
X376210Y1745212D01*
X375918Y1745129D01*
X375627Y1745254D01*
X375418Y1745546D01*
X375335Y1745879D01*
X375418Y1746212D01*
X375627Y1746504D01*
X375918Y1746629D01*
X376210Y1746546D01*
X376418Y1746337D01*
X376502Y1746087D01*
Y1745671D01*
X376627Y1745296D01*
X376877Y1745046D01*
X377168Y1744962D01*
X377460Y1745046D01*
X377668Y1745254D01*
X377793Y1745587D01*
X377835Y1745879D01*
G01X377335Y1748062D02*
X377627Y1748312D01*
X377793Y1748646D01*
X377835Y1749021D01*
X377793Y1749354D01*
X377585Y1749687D01*
X377335Y1749896D01*
X377085Y1749937D01*
X376793Y1749854D01*
X376585Y1749562D01*
X376502Y1749271D01*
Y1748896D01*
G01Y1749271D02*
X376377Y1749521D01*
X376168Y1749729D01*
X375918Y1749812D01*
X375668Y1749729D01*
X375460Y1749521D01*
X375335Y1749146D01*
X375377Y1748771D01*
X375543Y1748396D01*
G01X377543Y1751371D02*
X377752Y1751662D01*
X377835Y1751996D01*
X377752Y1752329D01*
X377502Y1752621D01*
X377127Y1752829D01*
X376752Y1752912D01*
X376293D01*
X375918Y1752829D01*
X375585Y1752621D01*
X375418Y1752371D01*
X375335Y1752079D01*
X375418Y1751746D01*
X375585Y1751496D01*
X375835Y1751329D01*
X376168Y1751246D01*
X376460Y1751329D01*
X376752Y1751537D01*
X376918Y1751787D01*
X376960Y1752079D01*
X376877Y1752412D01*
X376668Y1752662D01*
X376293Y1752912D01*
G01X387217Y1744292D02*
X386967Y1744417D01*
X386675Y1744500D01*
X386342D01*
X385967Y1744375D01*
X385675Y1744167D01*
X385467Y1743917D01*
X385300Y1743500D01*
X385258Y1743125D01*
X385342Y1742750D01*
X385467Y1742500D01*
X385717Y1742250D01*
X386008Y1742083D01*
X386300Y1742000D01*
X386592D01*
X386883Y1742083D01*
X387133Y1742208D01*
X387342Y1742375D01*
G01X389400Y1742000D02*
X389692Y1742042D01*
X390025Y1742167D01*
X390233Y1742375D01*
X390317Y1742667D01*
X390233Y1742958D01*
X389983Y1743208D01*
X389608Y1743333D01*
X389192D01*
X388942Y1743417D01*
X388733Y1743625D01*
X388650Y1743917D01*
X388775Y1744208D01*
X389067Y1744417D01*
X389400Y1744500D01*
X389733Y1744417D01*
X390025Y1744208D01*
X390150Y1743917D01*
X390067Y1743625D01*
X389858Y1743417D01*
X389608Y1743333D01*
X389192D01*
X388817Y1743208D01*
X388567Y1742958D01*
X388483Y1742667D01*
X388567Y1742375D01*
X388775Y1742167D01*
X389108Y1742042D01*
X389400Y1742000D01*
G01X392500D02*
X392792Y1742042D01*
X393125Y1742167D01*
X393333Y1742375D01*
X393417Y1742667D01*
X393333Y1742958D01*
X393083Y1743208D01*
X392708Y1743333D01*
X392292D01*
X392042Y1743417D01*
X391833Y1743625D01*
X391750Y1743917D01*
X391875Y1744208D01*
X392167Y1744417D01*
X392500Y1744500D01*
X392833Y1744417D01*
X393125Y1744208D01*
X393250Y1743917D01*
X393167Y1743625D01*
X392958Y1743417D01*
X392708Y1743333D01*
X392292D01*
X391917Y1743208D01*
X391667Y1742958D01*
X391583Y1742667D01*
X391667Y1742375D01*
X391875Y1742167D01*
X392208Y1742042D01*
X392500Y1742000D01*
G01X396100D02*
Y1744500D01*
X394558Y1742708D01*
X396642D01*
G01X398700Y1744500D02*
X398367Y1744417D01*
X398117Y1744208D01*
X397950Y1743958D01*
X397825Y1743625D01*
X397783Y1743250D01*
X397825Y1742875D01*
X397950Y1742542D01*
X398117Y1742292D01*
X398367Y1742083D01*
X398700Y1742000D01*
X399033Y1742083D01*
X399283Y1742292D01*
X399450Y1742542D01*
X399575Y1742875D01*
X399617Y1743250D01*
X399575Y1743625D01*
X399450Y1743958D01*
X399283Y1744208D01*
X399033Y1744417D01*
X398700Y1744500D01*
G01X363537Y1786041D02*
Y1788541D01*
X364578D01*
X364912Y1788416D01*
X365120Y1788249D01*
X365203Y1787916D01*
X365120Y1787583D01*
X364870Y1787374D01*
X364578Y1787249D01*
X363537D01*
G01X364578D02*
X365203Y1786041D01*
G01X366762Y1786333D02*
X367053Y1786124D01*
X367387Y1786041D01*
X367720Y1786124D01*
X368012Y1786374D01*
X368220Y1786749D01*
X368303Y1787124D01*
Y1787583D01*
X368220Y1787958D01*
X368012Y1788291D01*
X367762Y1788458D01*
X367470Y1788541D01*
X367137Y1788458D01*
X366887Y1788291D01*
X366720Y1788041D01*
X366637Y1787708D01*
X366720Y1787416D01*
X366928Y1787124D01*
X367178Y1786958D01*
X367470Y1786916D01*
X367803Y1786999D01*
X368053Y1787208D01*
X368303Y1787583D01*
G01X371070Y1786041D02*
Y1788541D01*
X369528Y1786749D01*
X371612D01*
G01X373670Y1786041D02*
Y1788541D01*
X373170Y1788041D01*
G01Y1786041D02*
X374170D01*
G01X375978Y1787083D02*
X376270Y1787374D01*
X376520Y1787541D01*
X376853Y1787624D01*
X377145Y1787541D01*
X377353Y1787374D01*
X377520Y1787124D01*
X377562Y1786833D01*
X377520Y1786583D01*
X377353Y1786333D01*
X377103Y1786124D01*
X376812Y1786041D01*
X376478Y1786124D01*
X376187Y1786374D01*
X376020Y1786749D01*
X375978Y1787166D01*
X376062Y1787708D01*
X376187Y1787999D01*
X376395Y1788291D01*
X376687Y1788499D01*
X376978Y1788541D01*
X377270Y1788458D01*
X377478Y1788249D01*
G01X349800Y1761000D02*
Y1757000D01*
X357200D01*
G01X400300Y1727000D02*
Y1723000D01*
X407700D01*
G01X342500Y1730300D02*
X346500D01*
Y1737700D01*
G01X338500Y1730300D02*
X342500D01*
Y1737700D01*
G01X369022Y1740346D02*
X366522D01*
Y1741387D01*
X366647Y1741721D01*
X366814Y1741929D01*
X367147Y1742012D01*
X367480Y1741929D01*
X367689Y1741679D01*
X367814Y1741387D01*
Y1740346D01*
G01Y1741387D02*
X369022Y1742012D01*
G01X368730Y1743571D02*
X368939Y1743862D01*
X369022Y1744196D01*
X368939Y1744529D01*
X368689Y1744821D01*
X368314Y1745029D01*
X367939Y1745112D01*
X367480D01*
X367105Y1745029D01*
X366772Y1744821D01*
X366605Y1744571D01*
X366522Y1744279D01*
X366605Y1743946D01*
X366772Y1743696D01*
X367022Y1743529D01*
X367355Y1743446D01*
X367647Y1743529D01*
X367939Y1743737D01*
X368105Y1743987D01*
X368147Y1744279D01*
X368064Y1744612D01*
X367855Y1744862D01*
X367480Y1745112D01*
G01X366522Y1747379D02*
X366605Y1747046D01*
X366814Y1746796D01*
X367064Y1746629D01*
X367397Y1746504D01*
X367772Y1746462D01*
X368147Y1746504D01*
X368480Y1746629D01*
X368730Y1746796D01*
X368939Y1747046D01*
X369022Y1747379D01*
X368939Y1747712D01*
X368730Y1747962D01*
X368480Y1748129D01*
X368147Y1748254D01*
X367772Y1748296D01*
X367397Y1748254D01*
X367064Y1748129D01*
X366814Y1747962D01*
X366605Y1747712D01*
X366522Y1747379D01*
G01X367980Y1749687D02*
X367689Y1749979D01*
X367522Y1750229D01*
X367439Y1750562D01*
X367522Y1750854D01*
X367689Y1751062D01*
X367939Y1751229D01*
X368230Y1751271D01*
X368480Y1751229D01*
X368730Y1751062D01*
X368939Y1750812D01*
X369022Y1750521D01*
X368939Y1750187D01*
X368689Y1749896D01*
X368314Y1749729D01*
X367897Y1749687D01*
X367355Y1749771D01*
X367064Y1749896D01*
X366772Y1750104D01*
X366564Y1750396D01*
X366522Y1750687D01*
X366605Y1750979D01*
X366814Y1751187D01*
G01X368647Y1752662D02*
X368855Y1752912D01*
X368980Y1753204D01*
X369022Y1753579D01*
X368939Y1753954D01*
X368772Y1754246D01*
X368480Y1754454D01*
X368147Y1754496D01*
X367814Y1754412D01*
X367605Y1754204D01*
X367439Y1753912D01*
X367397Y1753621D01*
X367439Y1753329D01*
X367605Y1752954D01*
X366522Y1753079D01*
Y1754204D01*
G01X357500Y1730300D02*
X361500D01*
Y1737700D01*
G01X365022Y1740346D02*
X362522D01*
Y1741387D01*
X362647Y1741721D01*
X362814Y1741929D01*
X363147Y1742012D01*
X363480Y1741929D01*
X363689Y1741679D01*
X363814Y1741387D01*
Y1740346D01*
G01Y1741387D02*
X365022Y1742012D01*
G01X364730Y1743571D02*
X364939Y1743862D01*
X365022Y1744196D01*
X364939Y1744529D01*
X364689Y1744821D01*
X364314Y1745029D01*
X363939Y1745112D01*
X363480D01*
X363105Y1745029D01*
X362772Y1744821D01*
X362605Y1744571D01*
X362522Y1744279D01*
X362605Y1743946D01*
X362772Y1743696D01*
X363022Y1743529D01*
X363355Y1743446D01*
X363647Y1743529D01*
X363939Y1743737D01*
X364105Y1743987D01*
X364147Y1744279D01*
X364064Y1744612D01*
X363855Y1744862D01*
X363480Y1745112D01*
G01X362522Y1747379D02*
X362605Y1747046D01*
X362814Y1746796D01*
X363064Y1746629D01*
X363397Y1746504D01*
X363772Y1746462D01*
X364147Y1746504D01*
X364480Y1746629D01*
X364730Y1746796D01*
X364939Y1747046D01*
X365022Y1747379D01*
X364939Y1747712D01*
X364730Y1747962D01*
X364480Y1748129D01*
X364147Y1748254D01*
X363772Y1748296D01*
X363397Y1748254D01*
X363064Y1748129D01*
X362814Y1747962D01*
X362605Y1747712D01*
X362522Y1747379D01*
G01X363980Y1749687D02*
X363689Y1749979D01*
X363522Y1750229D01*
X363439Y1750562D01*
X363522Y1750854D01*
X363689Y1751062D01*
X363939Y1751229D01*
X364230Y1751271D01*
X364480Y1751229D01*
X364730Y1751062D01*
X364939Y1750812D01*
X365022Y1750521D01*
X364939Y1750187D01*
X364689Y1749896D01*
X364314Y1749729D01*
X363897Y1749687D01*
X363355Y1749771D01*
X363064Y1749896D01*
X362772Y1750104D01*
X362564Y1750396D01*
X362522Y1750687D01*
X362605Y1750979D01*
X362814Y1751187D01*
G01X363980Y1752787D02*
X363689Y1753079D01*
X363522Y1753329D01*
X363439Y1753662D01*
X363522Y1753954D01*
X363689Y1754162D01*
X363939Y1754329D01*
X364230Y1754371D01*
X364480Y1754329D01*
X364730Y1754162D01*
X364939Y1753912D01*
X365022Y1753621D01*
X364939Y1753287D01*
X364689Y1752996D01*
X364314Y1752829D01*
X363897Y1752787D01*
X363355Y1752871D01*
X363064Y1752996D01*
X362772Y1753204D01*
X362564Y1753496D01*
X362522Y1753787D01*
X362605Y1754079D01*
X362814Y1754287D01*
G01X353500Y1730300D02*
X357500D01*
Y1737700D01*
G01X381835Y1738846D02*
X379335D01*
Y1739887D01*
X379460Y1740221D01*
X379627Y1740429D01*
X379960Y1740512D01*
X380293Y1740429D01*
X380502Y1740179D01*
X380627Y1739887D01*
Y1738846D01*
G01Y1739887D02*
X381835Y1740512D01*
G01X381543Y1742071D02*
X381752Y1742362D01*
X381835Y1742696D01*
X381752Y1743029D01*
X381502Y1743321D01*
X381127Y1743529D01*
X380752Y1743612D01*
X380293D01*
X379918Y1743529D01*
X379585Y1743321D01*
X379418Y1743071D01*
X379335Y1742779D01*
X379418Y1742446D01*
X379585Y1742196D01*
X379835Y1742029D01*
X380168Y1741946D01*
X380460Y1742029D01*
X380752Y1742237D01*
X380918Y1742487D01*
X380960Y1742779D01*
X380877Y1743112D01*
X380668Y1743362D01*
X380293Y1743612D01*
G01X381460Y1744962D02*
X381668Y1745212D01*
X381793Y1745504D01*
X381835Y1745879D01*
X381752Y1746254D01*
X381585Y1746546D01*
X381293Y1746754D01*
X380960Y1746796D01*
X380627Y1746712D01*
X380418Y1746504D01*
X380252Y1746212D01*
X380210Y1745921D01*
X380252Y1745629D01*
X380418Y1745254D01*
X379335Y1745379D01*
Y1746504D01*
G01X381835Y1748979D02*
X379335D01*
X379835Y1748479D01*
G01X381835D02*
Y1749479D01*
G01Y1752079D02*
X379335D01*
X379835Y1751579D01*
G01X381835D02*
Y1752579D01*
G01X381000Y1734700D02*
X377000D01*
Y1727300D01*
G01X341347Y1786571D02*
Y1789071D01*
X342388D01*
X342722Y1788946D01*
X342930Y1788779D01*
X343013Y1788446D01*
X342930Y1788113D01*
X342680Y1787904D01*
X342388Y1787779D01*
X341347D01*
G01X342388D02*
X343013Y1786571D01*
G01X344572Y1786863D02*
X344863Y1786654D01*
X345197Y1786571D01*
X345530Y1786654D01*
X345822Y1786904D01*
X346030Y1787279D01*
X346113Y1787654D01*
Y1788113D01*
X346030Y1788488D01*
X345822Y1788821D01*
X345572Y1788988D01*
X345280Y1789071D01*
X344947Y1788988D01*
X344697Y1788821D01*
X344530Y1788571D01*
X344447Y1788238D01*
X344530Y1787946D01*
X344738Y1787654D01*
X344988Y1787488D01*
X345280Y1787446D01*
X345613Y1787529D01*
X345863Y1787738D01*
X346113Y1788113D01*
G01X347463Y1786946D02*
X347713Y1786738D01*
X348005Y1786613D01*
X348380Y1786571D01*
X348755Y1786654D01*
X349047Y1786821D01*
X349255Y1787113D01*
X349297Y1787446D01*
X349213Y1787779D01*
X349005Y1787988D01*
X348713Y1788154D01*
X348422Y1788196D01*
X348130Y1788154D01*
X347755Y1787988D01*
X347880Y1789071D01*
X349005D01*
G01X351480D02*
X351147Y1788988D01*
X350897Y1788779D01*
X350730Y1788529D01*
X350605Y1788196D01*
X350563Y1787821D01*
X350605Y1787446D01*
X350730Y1787113D01*
X350897Y1786863D01*
X351147Y1786654D01*
X351480Y1786571D01*
X351813Y1786654D01*
X352063Y1786863D01*
X352230Y1787113D01*
X352355Y1787446D01*
X352397Y1787821D01*
X352355Y1788196D01*
X352230Y1788529D01*
X352063Y1788779D01*
X351813Y1788988D01*
X351480Y1789071D01*
G01X354580D02*
X354247Y1788988D01*
X353997Y1788779D01*
X353830Y1788529D01*
X353705Y1788196D01*
X353663Y1787821D01*
X353705Y1787446D01*
X353830Y1787113D01*
X353997Y1786863D01*
X354247Y1786654D01*
X354580Y1786571D01*
X354913Y1786654D01*
X355163Y1786863D01*
X355330Y1787113D01*
X355455Y1787446D01*
X355497Y1787821D01*
X355455Y1788196D01*
X355330Y1788529D01*
X355163Y1788779D01*
X354913Y1788988D01*
X354580Y1789071D01*
G01X341800Y1761000D02*
Y1757000D01*
X349200D01*
G01X389000Y1746967D02*
X386500D01*
Y1748008D01*
X386625Y1748342D01*
X386792Y1748550D01*
X387125Y1748633D01*
X387458Y1748550D01*
X387667Y1748300D01*
X387792Y1748008D01*
Y1746967D01*
G01Y1748008D02*
X389000Y1748633D01*
G01X388708Y1750192D02*
X388917Y1750483D01*
X389000Y1750817D01*
X388917Y1751150D01*
X388667Y1751442D01*
X388292Y1751650D01*
X387917Y1751733D01*
X387458D01*
X387083Y1751650D01*
X386750Y1751442D01*
X386583Y1751192D01*
X386500Y1750900D01*
X386583Y1750567D01*
X386750Y1750317D01*
X387000Y1750150D01*
X387333Y1750067D01*
X387625Y1750150D01*
X387917Y1750358D01*
X388083Y1750608D01*
X388125Y1750900D01*
X388042Y1751233D01*
X387833Y1751483D01*
X387458Y1751733D01*
G01X388625Y1753083D02*
X388833Y1753333D01*
X388958Y1753625D01*
X389000Y1754000D01*
X388917Y1754375D01*
X388750Y1754667D01*
X388458Y1754875D01*
X388125Y1754917D01*
X387792Y1754833D01*
X387583Y1754625D01*
X387417Y1754333D01*
X387375Y1754042D01*
X387417Y1753750D01*
X387583Y1753375D01*
X386500Y1753500D01*
Y1754625D01*
G01X389000Y1757100D02*
X388958Y1757392D01*
X388833Y1757725D01*
X388625Y1757933D01*
X388333Y1758017D01*
X388042Y1757933D01*
X387792Y1757683D01*
X387667Y1757308D01*
Y1756892D01*
X387583Y1756642D01*
X387375Y1756433D01*
X387083Y1756350D01*
X386792Y1756475D01*
X386583Y1756767D01*
X386500Y1757100D01*
X386583Y1757433D01*
X386792Y1757725D01*
X387083Y1757850D01*
X387375Y1757767D01*
X387583Y1757558D01*
X387667Y1757308D01*
Y1756892D01*
X387792Y1756517D01*
X388042Y1756267D01*
X388333Y1756183D01*
X388625Y1756267D01*
X388833Y1756475D01*
X388958Y1756808D01*
X389000Y1757100D01*
G01X386917Y1759408D02*
X386667Y1759658D01*
X386542Y1759950D01*
X386500Y1760283D01*
X386583Y1760700D01*
X386792Y1760992D01*
X387042Y1761075D01*
X387292Y1761033D01*
X387500Y1760867D01*
X387917Y1760033D01*
X388208Y1759658D01*
X388625Y1759408D01*
X389000Y1759325D01*
Y1761075D01*
G01X391500Y1739200D02*
Y1734000D01*
G01X384500Y1739200D02*
Y1731400D01*
G01X391500Y1739200D02*
X384500D01*
G01X391500Y1725800D02*
Y1734500D01*
G01X384500Y1725800D02*
X391500D01*
G01X384500Y1732200D02*
Y1725800D01*
G01X347334Y1770467D02*
X344834D01*
Y1771508D01*
X344959Y1771842D01*
X345126Y1772050D01*
X345459Y1772133D01*
X345792Y1772050D01*
X346001Y1771800D01*
X346126Y1771508D01*
Y1770467D01*
G01Y1771508D02*
X347334Y1772133D01*
G01X347042Y1773692D02*
X347251Y1773983D01*
X347334Y1774317D01*
X347251Y1774650D01*
X347001Y1774942D01*
X346626Y1775150D01*
X346251Y1775233D01*
X345792D01*
X345417Y1775150D01*
X345084Y1774942D01*
X344917Y1774692D01*
X344834Y1774400D01*
X344917Y1774067D01*
X345084Y1773817D01*
X345334Y1773650D01*
X345667Y1773567D01*
X345959Y1773650D01*
X346251Y1773858D01*
X346417Y1774108D01*
X346459Y1774400D01*
X346376Y1774733D01*
X346167Y1774983D01*
X345792Y1775233D01*
G01X346959Y1776583D02*
X347167Y1776833D01*
X347292Y1777125D01*
X347334Y1777500D01*
X347251Y1777875D01*
X347084Y1778167D01*
X346792Y1778375D01*
X346459Y1778417D01*
X346126Y1778333D01*
X345917Y1778125D01*
X345751Y1777833D01*
X345709Y1777542D01*
X345751Y1777250D01*
X345917Y1776875D01*
X344834Y1777000D01*
Y1778125D01*
G01X347042Y1779892D02*
X347251Y1780183D01*
X347334Y1780517D01*
X347251Y1780850D01*
X347001Y1781142D01*
X346626Y1781350D01*
X346251Y1781433D01*
X345792D01*
X345417Y1781350D01*
X345084Y1781142D01*
X344917Y1780892D01*
X344834Y1780600D01*
X344917Y1780267D01*
X345084Y1780017D01*
X345334Y1779850D01*
X345667Y1779767D01*
X345959Y1779850D01*
X346251Y1780058D01*
X346417Y1780308D01*
X346459Y1780600D01*
X346376Y1780933D01*
X346167Y1781183D01*
X345792Y1781433D01*
G01X347042Y1782992D02*
X347251Y1783283D01*
X347334Y1783617D01*
X347251Y1783950D01*
X347001Y1784242D01*
X346626Y1784450D01*
X346251Y1784533D01*
X345792D01*
X345417Y1784450D01*
X345084Y1784242D01*
X344917Y1783992D01*
X344834Y1783700D01*
X344917Y1783367D01*
X345084Y1783117D01*
X345334Y1782950D01*
X345667Y1782867D01*
X345959Y1782950D01*
X346251Y1783158D01*
X346417Y1783408D01*
X346459Y1783700D01*
X346376Y1784033D01*
X346167Y1784283D01*
X345792Y1784533D01*
G01X349000Y1756700D02*
X345000D01*
Y1749300D01*
G01X368649Y1770257D02*
X366149D01*
Y1771298D01*
X366274Y1771632D01*
X366441Y1771840D01*
X366774Y1771923D01*
X367107Y1771840D01*
X367316Y1771590D01*
X367441Y1771298D01*
Y1770257D01*
G01Y1771298D02*
X368649Y1771923D01*
G01X368357Y1773482D02*
X368566Y1773773D01*
X368649Y1774107D01*
X368566Y1774440D01*
X368316Y1774732D01*
X367941Y1774940D01*
X367566Y1775023D01*
X367107D01*
X366732Y1774940D01*
X366399Y1774732D01*
X366232Y1774482D01*
X366149Y1774190D01*
X366232Y1773857D01*
X366399Y1773607D01*
X366649Y1773440D01*
X366982Y1773357D01*
X367274Y1773440D01*
X367566Y1773648D01*
X367732Y1773898D01*
X367774Y1774190D01*
X367691Y1774523D01*
X367482Y1774773D01*
X367107Y1775023D01*
G01X368274Y1776373D02*
X368482Y1776623D01*
X368607Y1776915D01*
X368649Y1777290D01*
X368566Y1777665D01*
X368399Y1777957D01*
X368107Y1778165D01*
X367774Y1778207D01*
X367441Y1778123D01*
X367232Y1777915D01*
X367066Y1777623D01*
X367024Y1777332D01*
X367066Y1777040D01*
X367232Y1776665D01*
X366149Y1776790D01*
Y1777915D01*
G01X368357Y1779682D02*
X368566Y1779973D01*
X368649Y1780307D01*
X368566Y1780640D01*
X368316Y1780932D01*
X367941Y1781140D01*
X367566Y1781223D01*
X367107D01*
X366732Y1781140D01*
X366399Y1780932D01*
X366232Y1780682D01*
X366149Y1780390D01*
X366232Y1780057D01*
X366399Y1779807D01*
X366649Y1779640D01*
X366982Y1779557D01*
X367274Y1779640D01*
X367566Y1779848D01*
X367732Y1780098D01*
X367774Y1780390D01*
X367691Y1780723D01*
X367482Y1780973D01*
X367107Y1781223D01*
G01X368649Y1783490D02*
X368607Y1783782D01*
X368482Y1784115D01*
X368274Y1784323D01*
X367982Y1784407D01*
X367691Y1784323D01*
X367441Y1784073D01*
X367316Y1783698D01*
Y1783282D01*
X367232Y1783032D01*
X367024Y1782823D01*
X366732Y1782740D01*
X366441Y1782865D01*
X366232Y1783157D01*
X366149Y1783490D01*
X366232Y1783823D01*
X366441Y1784115D01*
X366732Y1784240D01*
X367024Y1784157D01*
X367232Y1783948D01*
X367316Y1783698D01*
Y1783282D01*
X367441Y1782907D01*
X367691Y1782657D01*
X367982Y1782573D01*
X368274Y1782657D01*
X368482Y1782865D01*
X368607Y1783198D01*
X368649Y1783490D01*
G01X357000Y1756700D02*
X353000D01*
Y1749300D01*
G01X404687Y331743D02*
X404437Y331868D01*
X404145Y331951D01*
X403812D01*
X403437Y331826D01*
X403145Y331618D01*
X402937Y331368D01*
X402770Y330951D01*
X402728Y330576D01*
X402812Y330201D01*
X402937Y329951D01*
X403187Y329701D01*
X403478Y329534D01*
X403770Y329451D01*
X404062D01*
X404353Y329534D01*
X404603Y329659D01*
X404812Y329826D01*
G01X406162Y329743D02*
X406453Y329534D01*
X406787Y329451D01*
X407120Y329534D01*
X407412Y329784D01*
X407620Y330159D01*
X407703Y330534D01*
Y330993D01*
X407620Y331368D01*
X407412Y331701D01*
X407162Y331868D01*
X406870Y331951D01*
X406537Y331868D01*
X406287Y331701D01*
X406120Y331451D01*
X406037Y331118D01*
X406120Y330826D01*
X406328Y330534D01*
X406578Y330368D01*
X406870Y330326D01*
X407203Y330409D01*
X407453Y330618D01*
X407703Y330993D01*
G01X409053Y329951D02*
X409303Y329659D01*
X409637Y329493D01*
X410012Y329451D01*
X410345Y329493D01*
X410678Y329701D01*
X410887Y329951D01*
X410928Y330201D01*
X410845Y330493D01*
X410553Y330701D01*
X410262Y330784D01*
X409887D01*
G01X410262D02*
X410512Y330909D01*
X410720Y331118D01*
X410803Y331368D01*
X410720Y331618D01*
X410512Y331826D01*
X410137Y331951D01*
X409762Y331909D01*
X409387Y331743D01*
G01X412987Y329451D02*
X413070Y329993D01*
X413195Y330451D01*
X413362Y330868D01*
X413570Y331326D01*
X413903Y331951D01*
X412237D01*
G01X416670Y329451D02*
Y331951D01*
X415128Y330159D01*
X417212D01*
G01X402937Y309021D02*
Y311521D01*
X403978D01*
X404312Y311396D01*
X404520Y311229D01*
X404603Y310896D01*
X404520Y310563D01*
X404270Y310354D01*
X403978Y310229D01*
X402937D01*
G01X403978D02*
X404603Y309021D01*
G01X406162Y309313D02*
X406453Y309104D01*
X406787Y309021D01*
X407120Y309104D01*
X407412Y309354D01*
X407620Y309729D01*
X407703Y310104D01*
Y310563D01*
X407620Y310938D01*
X407412Y311271D01*
X407162Y311438D01*
X406870Y311521D01*
X406537Y311438D01*
X406287Y311271D01*
X406120Y311021D01*
X406037Y310688D01*
X406120Y310396D01*
X406328Y310104D01*
X406578Y309938D01*
X406870Y309896D01*
X407203Y309979D01*
X407453Y310188D01*
X407703Y310563D01*
G01X409053Y309396D02*
X409303Y309188D01*
X409595Y309063D01*
X409970Y309021D01*
X410345Y309104D01*
X410637Y309271D01*
X410845Y309563D01*
X410887Y309896D01*
X410803Y310229D01*
X410595Y310438D01*
X410303Y310604D01*
X410012Y310646D01*
X409720Y310604D01*
X409345Y310438D01*
X409470Y311521D01*
X410595D01*
G01X413070Y309021D02*
X413362Y309063D01*
X413695Y309188D01*
X413903Y309396D01*
X413987Y309688D01*
X413903Y309979D01*
X413653Y310229D01*
X413278Y310354D01*
X412862D01*
X412612Y310438D01*
X412403Y310646D01*
X412320Y310938D01*
X412445Y311229D01*
X412737Y311438D01*
X413070Y311521D01*
X413403Y311438D01*
X413695Y311229D01*
X413820Y310938D01*
X413737Y310646D01*
X413528Y310438D01*
X413278Y310354D01*
X412862D01*
X412487Y310229D01*
X412237Y309979D01*
X412153Y309688D01*
X412237Y309396D01*
X412445Y309188D01*
X412778Y309063D01*
X413070Y309021D01*
G01X415462Y309313D02*
X415753Y309104D01*
X416087Y309021D01*
X416420Y309104D01*
X416712Y309354D01*
X416920Y309729D01*
X417003Y310104D01*
Y310563D01*
X416920Y310938D01*
X416712Y311271D01*
X416462Y311438D01*
X416170Y311521D01*
X415837Y311438D01*
X415587Y311271D01*
X415420Y311021D01*
X415337Y310688D01*
X415420Y310396D01*
X415628Y310104D01*
X415878Y309938D01*
X416170Y309896D01*
X416503Y309979D01*
X416753Y310188D01*
X417003Y310563D01*
G01X407834Y313967D02*
X405334D01*
Y315008D01*
X405459Y315342D01*
X405626Y315550D01*
X405959Y315633D01*
X406292Y315550D01*
X406501Y315300D01*
X406626Y315008D01*
Y313967D01*
G01Y315008D02*
X407834Y315633D01*
G01X407542Y317192D02*
X407751Y317483D01*
X407834Y317817D01*
X407751Y318150D01*
X407501Y318442D01*
X407126Y318650D01*
X406751Y318733D01*
X406292D01*
X405917Y318650D01*
X405584Y318442D01*
X405417Y318192D01*
X405334Y317900D01*
X405417Y317567D01*
X405584Y317317D01*
X405834Y317150D01*
X406167Y317067D01*
X406459Y317150D01*
X406751Y317358D01*
X406917Y317608D01*
X406959Y317900D01*
X406876Y318233D01*
X406667Y318483D01*
X406292Y318733D01*
G01X406792Y320208D02*
X406501Y320500D01*
X406334Y320750D01*
X406251Y321083D01*
X406334Y321375D01*
X406501Y321583D01*
X406751Y321750D01*
X407042Y321792D01*
X407292Y321750D01*
X407542Y321583D01*
X407751Y321333D01*
X407834Y321042D01*
X407751Y320708D01*
X407501Y320417D01*
X407126Y320250D01*
X406709Y320208D01*
X406167Y320292D01*
X405876Y320417D01*
X405584Y320625D01*
X405376Y320917D01*
X405334Y321208D01*
X405417Y321500D01*
X405626Y321708D01*
G01X407834Y324100D02*
X405334D01*
X405834Y323600D01*
G01X407834D02*
Y324600D01*
G01Y327117D02*
X407292Y327200D01*
X406834Y327325D01*
X406417Y327492D01*
X405959Y327700D01*
X405334Y328033D01*
Y326367D01*
G01X411508Y382817D02*
X411383Y382567D01*
X411300Y382275D01*
Y381942D01*
X411425Y381567D01*
X411633Y381275D01*
X411883Y381067D01*
X412300Y380900D01*
X412675Y380858D01*
X413050Y380942D01*
X413300Y381067D01*
X413550Y381317D01*
X413717Y381608D01*
X413800Y381900D01*
Y382192D01*
X413717Y382483D01*
X413592Y382733D01*
X413425Y382942D01*
G01X413508Y384292D02*
X413717Y384583D01*
X413800Y384917D01*
X413717Y385250D01*
X413467Y385542D01*
X413092Y385750D01*
X412717Y385833D01*
X412258D01*
X411883Y385750D01*
X411550Y385542D01*
X411383Y385292D01*
X411300Y385000D01*
X411383Y384667D01*
X411550Y384417D01*
X411800Y384250D01*
X412133Y384167D01*
X412425Y384250D01*
X412717Y384458D01*
X412883Y384708D01*
X412925Y385000D01*
X412842Y385333D01*
X412633Y385583D01*
X412258Y385833D01*
G01X413800Y388600D02*
X411300D01*
X413092Y387058D01*
Y389142D01*
G01X413300Y390283D02*
X413592Y390533D01*
X413758Y390867D01*
X413800Y391242D01*
X413758Y391575D01*
X413550Y391908D01*
X413300Y392117D01*
X413050Y392158D01*
X412758Y392075D01*
X412550Y391783D01*
X412467Y391492D01*
Y391117D01*
G01Y391492D02*
X412342Y391742D01*
X412133Y391950D01*
X411883Y392033D01*
X411633Y391950D01*
X411425Y391742D01*
X411300Y391367D01*
X411342Y390992D01*
X411508Y390617D01*
G01X411717Y393508D02*
X411467Y393758D01*
X411342Y394050D01*
X411300Y394383D01*
X411383Y394800D01*
X411592Y395092D01*
X411842Y395175D01*
X412092Y395133D01*
X412300Y394967D01*
X412717Y394133D01*
X413008Y393758D01*
X413425Y393508D01*
X413800Y393425D01*
Y395175D01*
G01X406708Y403217D02*
X406583Y402967D01*
X406500Y402675D01*
Y402342D01*
X406625Y401967D01*
X406833Y401675D01*
X407083Y401467D01*
X407500Y401300D01*
X407875Y401258D01*
X408250Y401342D01*
X408500Y401467D01*
X408750Y401717D01*
X408917Y402008D01*
X409000Y402300D01*
Y402592D01*
X408917Y402883D01*
X408792Y403133D01*
X408625Y403342D01*
G01X409000Y405400D02*
X408958Y405692D01*
X408833Y406025D01*
X408625Y406233D01*
X408333Y406317D01*
X408042Y406233D01*
X407792Y405983D01*
X407667Y405608D01*
Y405192D01*
X407583Y404942D01*
X407375Y404733D01*
X407083Y404650D01*
X406792Y404775D01*
X406583Y405067D01*
X406500Y405400D01*
X406583Y405733D01*
X406792Y406025D01*
X407083Y406150D01*
X407375Y406067D01*
X407583Y405858D01*
X407667Y405608D01*
Y405192D01*
X407792Y404817D01*
X408042Y404567D01*
X408333Y404483D01*
X408625Y404567D01*
X408833Y404775D01*
X408958Y405108D01*
X409000Y405400D01*
G01Y408500D02*
X408958Y408792D01*
X408833Y409125D01*
X408625Y409333D01*
X408333Y409417D01*
X408042Y409333D01*
X407792Y409083D01*
X407667Y408708D01*
Y408292D01*
X407583Y408042D01*
X407375Y407833D01*
X407083Y407750D01*
X406792Y407875D01*
X406583Y408167D01*
X406500Y408500D01*
X406583Y408833D01*
X406792Y409125D01*
X407083Y409250D01*
X407375Y409167D01*
X407583Y408958D01*
X407667Y408708D01*
Y408292D01*
X407792Y407917D01*
X408042Y407667D01*
X408333Y407583D01*
X408625Y407667D01*
X408833Y407875D01*
X408958Y408208D01*
X409000Y408500D01*
G01Y411517D02*
X408458Y411600D01*
X408000Y411725D01*
X407583Y411892D01*
X407125Y412100D01*
X406500Y412433D01*
Y410767D01*
G01X409000Y415200D02*
X406500D01*
X408292Y413658D01*
Y415742D01*
G01X426418Y364117D02*
X426293Y363867D01*
X426210Y363575D01*
Y363242D01*
X426335Y362867D01*
X426543Y362575D01*
X426793Y362367D01*
X427210Y362200D01*
X427585Y362158D01*
X427960Y362242D01*
X428210Y362367D01*
X428460Y362617D01*
X428627Y362908D01*
X428710Y363200D01*
Y363492D01*
X428627Y363783D01*
X428502Y364033D01*
X428335Y364242D01*
G01X428710Y366300D02*
X428668Y366592D01*
X428543Y366925D01*
X428335Y367133D01*
X428043Y367217D01*
X427752Y367133D01*
X427502Y366883D01*
X427377Y366508D01*
Y366092D01*
X427293Y365842D01*
X427085Y365633D01*
X426793Y365550D01*
X426502Y365675D01*
X426293Y365967D01*
X426210Y366300D01*
X426293Y366633D01*
X426502Y366925D01*
X426793Y367050D01*
X427085Y366967D01*
X427293Y366758D01*
X427377Y366508D01*
Y366092D01*
X427502Y365717D01*
X427752Y365467D01*
X428043Y365383D01*
X428335Y365467D01*
X428543Y365675D01*
X428668Y366008D01*
X428710Y366300D01*
G01Y369400D02*
X428668Y369692D01*
X428543Y370025D01*
X428335Y370233D01*
X428043Y370317D01*
X427752Y370233D01*
X427502Y369983D01*
X427377Y369608D01*
Y369192D01*
X427293Y368942D01*
X427085Y368733D01*
X426793Y368650D01*
X426502Y368775D01*
X426293Y369067D01*
X426210Y369400D01*
X426293Y369733D01*
X426502Y370025D01*
X426793Y370150D01*
X427085Y370067D01*
X427293Y369858D01*
X427377Y369608D01*
Y369192D01*
X427502Y368817D01*
X427752Y368567D01*
X428043Y368483D01*
X428335Y368567D01*
X428543Y368775D01*
X428668Y369108D01*
X428710Y369400D01*
G01Y372417D02*
X428168Y372500D01*
X427710Y372625D01*
X427293Y372792D01*
X426835Y373000D01*
X426210Y373333D01*
Y371667D01*
G01X427668Y374808D02*
X427377Y375100D01*
X427210Y375350D01*
X427127Y375683D01*
X427210Y375975D01*
X427377Y376183D01*
X427627Y376350D01*
X427918Y376392D01*
X428168Y376350D01*
X428418Y376183D01*
X428627Y375933D01*
X428710Y375642D01*
X428627Y375308D01*
X428377Y375017D01*
X428002Y374850D01*
X427585Y374808D01*
X427043Y374892D01*
X426752Y375017D01*
X426460Y375225D01*
X426252Y375517D01*
X426210Y375808D01*
X426293Y376100D01*
X426502Y376308D01*
G01X422418Y364117D02*
X422293Y363867D01*
X422210Y363575D01*
Y363242D01*
X422335Y362867D01*
X422543Y362575D01*
X422793Y362367D01*
X423210Y362200D01*
X423585Y362158D01*
X423960Y362242D01*
X424210Y362367D01*
X424460Y362617D01*
X424627Y362908D01*
X424710Y363200D01*
Y363492D01*
X424627Y363783D01*
X424502Y364033D01*
X424335Y364242D01*
G01X424418Y365592D02*
X424627Y365883D01*
X424710Y366217D01*
X424627Y366550D01*
X424377Y366842D01*
X424002Y367050D01*
X423627Y367133D01*
X423168D01*
X422793Y367050D01*
X422460Y366842D01*
X422293Y366592D01*
X422210Y366300D01*
X422293Y365967D01*
X422460Y365717D01*
X422710Y365550D01*
X423043Y365467D01*
X423335Y365550D01*
X423627Y365758D01*
X423793Y366008D01*
X423835Y366300D01*
X423752Y366633D01*
X423543Y366883D01*
X423168Y367133D01*
G01X424335Y368483D02*
X424543Y368733D01*
X424668Y369025D01*
X424710Y369400D01*
X424627Y369775D01*
X424460Y370067D01*
X424168Y370275D01*
X423835Y370317D01*
X423502Y370233D01*
X423293Y370025D01*
X423127Y369733D01*
X423085Y369442D01*
X423127Y369150D01*
X423293Y368775D01*
X422210Y368900D01*
Y370025D01*
G01X424710Y372500D02*
X422210D01*
X422710Y372000D01*
G01X424710D02*
Y373000D01*
G01Y375517D02*
X424168Y375600D01*
X423710Y375725D01*
X423293Y375892D01*
X422835Y376100D01*
X422210Y376433D01*
Y374767D01*
G01X407710Y354867D02*
X405210D01*
Y355908D01*
X405335Y356242D01*
X405502Y356450D01*
X405835Y356533D01*
X406168Y356450D01*
X406377Y356200D01*
X406502Y355908D01*
Y354867D01*
G01Y355908D02*
X407710Y356533D01*
G01X407418Y358092D02*
X407627Y358383D01*
X407710Y358717D01*
X407627Y359050D01*
X407377Y359342D01*
X407002Y359550D01*
X406627Y359633D01*
X406168D01*
X405793Y359550D01*
X405460Y359342D01*
X405293Y359092D01*
X405210Y358800D01*
X405293Y358467D01*
X405460Y358217D01*
X405710Y358050D01*
X406043Y357967D01*
X406335Y358050D01*
X406627Y358258D01*
X406793Y358508D01*
X406835Y358800D01*
X406752Y359133D01*
X406543Y359383D01*
X406168Y359633D01*
G01X407710Y361900D02*
X405210D01*
X405710Y361400D01*
G01X407710D02*
Y362400D01*
G01X405627Y364208D02*
X405377Y364458D01*
X405252Y364750D01*
X405210Y365083D01*
X405293Y365500D01*
X405502Y365792D01*
X405752Y365875D01*
X406002Y365833D01*
X406210Y365667D01*
X406627Y364833D01*
X406918Y364458D01*
X407335Y364208D01*
X407710Y364125D01*
Y365875D01*
G01X405210Y368100D02*
X405293Y367767D01*
X405502Y367517D01*
X405752Y367350D01*
X406085Y367225D01*
X406460Y367183D01*
X406835Y367225D01*
X407168Y367350D01*
X407418Y367517D01*
X407627Y367767D01*
X407710Y368100D01*
X407627Y368433D01*
X407418Y368683D01*
X407168Y368850D01*
X406835Y368975D01*
X406460Y369017D01*
X406085Y368975D01*
X405752Y368850D01*
X405502Y368683D01*
X405293Y368433D01*
X405210Y368100D01*
G01X417210Y354867D02*
X414710D01*
Y355908D01*
X414835Y356242D01*
X415002Y356450D01*
X415335Y356533D01*
X415668Y356450D01*
X415877Y356200D01*
X416002Y355908D01*
Y354867D01*
G01Y355908D02*
X417210Y356533D01*
G01X416918Y358092D02*
X417127Y358383D01*
X417210Y358717D01*
X417127Y359050D01*
X416877Y359342D01*
X416502Y359550D01*
X416127Y359633D01*
X415668D01*
X415293Y359550D01*
X414960Y359342D01*
X414793Y359092D01*
X414710Y358800D01*
X414793Y358467D01*
X414960Y358217D01*
X415210Y358050D01*
X415543Y357967D01*
X415835Y358050D01*
X416127Y358258D01*
X416293Y358508D01*
X416335Y358800D01*
X416252Y359133D01*
X416043Y359383D01*
X415668Y359633D01*
G01X417210Y361900D02*
X414710D01*
X415210Y361400D01*
G01X417210D02*
Y362400D01*
G01X415127Y364208D02*
X414877Y364458D01*
X414752Y364750D01*
X414710Y365083D01*
X414793Y365500D01*
X415002Y365792D01*
X415252Y365875D01*
X415502Y365833D01*
X415710Y365667D01*
X416127Y364833D01*
X416418Y364458D01*
X416835Y364208D01*
X417210Y364125D01*
Y365875D01*
G01X416710Y367183D02*
X417002Y367433D01*
X417168Y367767D01*
X417210Y368142D01*
X417168Y368475D01*
X416960Y368808D01*
X416710Y369017D01*
X416460Y369058D01*
X416168Y368975D01*
X415960Y368683D01*
X415877Y368392D01*
Y368017D01*
G01Y368392D02*
X415752Y368642D01*
X415543Y368850D01*
X415293Y368933D01*
X415043Y368850D01*
X414835Y368642D01*
X414710Y368267D01*
X414752Y367892D01*
X414918Y367517D01*
G01X436710Y362367D02*
X434210D01*
Y363408D01*
X434335Y363742D01*
X434502Y363950D01*
X434835Y364033D01*
X435168Y363950D01*
X435377Y363700D01*
X435502Y363408D01*
Y362367D01*
G01Y363408D02*
X436710Y364033D01*
G01X436418Y365592D02*
X436627Y365883D01*
X436710Y366217D01*
X436627Y366550D01*
X436377Y366842D01*
X436002Y367050D01*
X435627Y367133D01*
X435168D01*
X434793Y367050D01*
X434460Y366842D01*
X434293Y366592D01*
X434210Y366300D01*
X434293Y365967D01*
X434460Y365717D01*
X434710Y365550D01*
X435043Y365467D01*
X435335Y365550D01*
X435627Y365758D01*
X435793Y366008D01*
X435835Y366300D01*
X435752Y366633D01*
X435543Y366883D01*
X435168Y367133D01*
G01X436710Y369400D02*
X434210D01*
X434710Y368900D01*
G01X436710D02*
Y369900D01*
G01X434627Y371708D02*
X434377Y371958D01*
X434252Y372250D01*
X434210Y372583D01*
X434293Y373000D01*
X434502Y373292D01*
X434752Y373375D01*
X435002Y373333D01*
X435210Y373167D01*
X435627Y372333D01*
X435918Y371958D01*
X436335Y371708D01*
X436710Y371625D01*
Y373375D01*
G01X436335Y374683D02*
X436543Y374933D01*
X436668Y375225D01*
X436710Y375600D01*
X436627Y375975D01*
X436460Y376267D01*
X436168Y376475D01*
X435835Y376517D01*
X435502Y376433D01*
X435293Y376225D01*
X435127Y375933D01*
X435085Y375642D01*
X435127Y375350D01*
X435293Y374975D01*
X434210Y375100D01*
Y376225D01*
G01X447210Y363367D02*
X444710D01*
Y364408D01*
X444835Y364742D01*
X445002Y364950D01*
X445335Y365033D01*
X445668Y364950D01*
X445877Y364700D01*
X446002Y364408D01*
Y363367D01*
G01Y364408D02*
X447210Y365033D01*
G01X446918Y366592D02*
X447127Y366883D01*
X447210Y367217D01*
X447127Y367550D01*
X446877Y367842D01*
X446502Y368050D01*
X446127Y368133D01*
X445668D01*
X445293Y368050D01*
X444960Y367842D01*
X444793Y367592D01*
X444710Y367300D01*
X444793Y366967D01*
X444960Y366717D01*
X445210Y366550D01*
X445543Y366467D01*
X445835Y366550D01*
X446127Y366758D01*
X446293Y367008D01*
X446335Y367300D01*
X446252Y367633D01*
X446043Y367883D01*
X445668Y368133D01*
G01X447210Y370400D02*
X444710D01*
X445210Y369900D01*
G01X447210D02*
Y370900D01*
G01X445127Y372708D02*
X444877Y372958D01*
X444752Y373250D01*
X444710Y373583D01*
X444793Y374000D01*
X445002Y374292D01*
X445252Y374375D01*
X445502Y374333D01*
X445710Y374167D01*
X446127Y373333D01*
X446418Y372958D01*
X446835Y372708D01*
X447210Y372625D01*
Y374375D01*
G01X446168Y375808D02*
X445877Y376100D01*
X445710Y376350D01*
X445627Y376683D01*
X445710Y376975D01*
X445877Y377183D01*
X446127Y377350D01*
X446418Y377392D01*
X446668Y377350D01*
X446918Y377183D01*
X447127Y376933D01*
X447210Y376642D01*
X447127Y376308D01*
X446877Y376017D01*
X446502Y375850D01*
X446085Y375808D01*
X445543Y375892D01*
X445252Y376017D01*
X444960Y376225D01*
X444752Y376517D01*
X444710Y376808D01*
X444793Y377100D01*
X445002Y377308D01*
G01X413210Y354867D02*
X410710D01*
Y355908D01*
X410835Y356242D01*
X411002Y356450D01*
X411335Y356533D01*
X411668Y356450D01*
X411877Y356200D01*
X412002Y355908D01*
Y354867D01*
G01Y355908D02*
X413210Y356533D01*
G01X412918Y358092D02*
X413127Y358383D01*
X413210Y358717D01*
X413127Y359050D01*
X412877Y359342D01*
X412502Y359550D01*
X412127Y359633D01*
X411668D01*
X411293Y359550D01*
X410960Y359342D01*
X410793Y359092D01*
X410710Y358800D01*
X410793Y358467D01*
X410960Y358217D01*
X411210Y358050D01*
X411543Y357967D01*
X411835Y358050D01*
X412127Y358258D01*
X412293Y358508D01*
X412335Y358800D01*
X412252Y359133D01*
X412043Y359383D01*
X411668Y359633D01*
G01X413210Y361900D02*
X410710D01*
X411210Y361400D01*
G01X413210D02*
Y362400D01*
G01X411127Y364208D02*
X410877Y364458D01*
X410752Y364750D01*
X410710Y365083D01*
X410793Y365500D01*
X411002Y365792D01*
X411252Y365875D01*
X411502Y365833D01*
X411710Y365667D01*
X412127Y364833D01*
X412418Y364458D01*
X412835Y364208D01*
X413210Y364125D01*
Y365875D01*
G01Y368017D02*
X412668Y368100D01*
X412210Y368225D01*
X411793Y368392D01*
X411335Y368600D01*
X410710Y368933D01*
Y367267D01*
G01X432710Y362367D02*
X430210D01*
Y363408D01*
X430335Y363742D01*
X430502Y363950D01*
X430835Y364033D01*
X431168Y363950D01*
X431377Y363700D01*
X431502Y363408D01*
Y362367D01*
G01Y363408D02*
X432710Y364033D01*
G01X432418Y365592D02*
X432627Y365883D01*
X432710Y366217D01*
X432627Y366550D01*
X432377Y366842D01*
X432002Y367050D01*
X431627Y367133D01*
X431168D01*
X430793Y367050D01*
X430460Y366842D01*
X430293Y366592D01*
X430210Y366300D01*
X430293Y365967D01*
X430460Y365717D01*
X430710Y365550D01*
X431043Y365467D01*
X431335Y365550D01*
X431627Y365758D01*
X431793Y366008D01*
X431835Y366300D01*
X431752Y366633D01*
X431543Y366883D01*
X431168Y367133D01*
G01X432710Y369400D02*
X430210D01*
X430710Y368900D01*
G01X432710D02*
Y369900D01*
G01X430627Y371708D02*
X430377Y371958D01*
X430252Y372250D01*
X430210Y372583D01*
X430293Y373000D01*
X430502Y373292D01*
X430752Y373375D01*
X431002Y373333D01*
X431210Y373167D01*
X431627Y372333D01*
X431918Y371958D01*
X432335Y371708D01*
X432710Y371625D01*
Y373375D01*
G01Y375600D02*
X432668Y375892D01*
X432543Y376225D01*
X432335Y376433D01*
X432043Y376517D01*
X431752Y376433D01*
X431502Y376183D01*
X431377Y375808D01*
Y375392D01*
X431293Y375142D01*
X431085Y374933D01*
X430793Y374850D01*
X430502Y374975D01*
X430293Y375267D01*
X430210Y375600D01*
X430293Y375933D01*
X430502Y376225D01*
X430793Y376350D01*
X431085Y376267D01*
X431293Y376058D01*
X431377Y375808D01*
Y375392D01*
X431502Y375017D01*
X431752Y374767D01*
X432043Y374683D01*
X432335Y374767D01*
X432543Y374975D01*
X432668Y375308D01*
X432710Y375600D01*
G01X443210Y363367D02*
X440710D01*
Y364408D01*
X440835Y364742D01*
X441002Y364950D01*
X441335Y365033D01*
X441668Y364950D01*
X441877Y364700D01*
X442002Y364408D01*
Y363367D01*
G01Y364408D02*
X443210Y365033D01*
G01X442918Y366592D02*
X443127Y366883D01*
X443210Y367217D01*
X443127Y367550D01*
X442877Y367842D01*
X442502Y368050D01*
X442127Y368133D01*
X441668D01*
X441293Y368050D01*
X440960Y367842D01*
X440793Y367592D01*
X440710Y367300D01*
X440793Y366967D01*
X440960Y366717D01*
X441210Y366550D01*
X441543Y366467D01*
X441835Y366550D01*
X442127Y366758D01*
X442293Y367008D01*
X442335Y367300D01*
X442252Y367633D01*
X442043Y367883D01*
X441668Y368133D01*
G01X443210Y370400D02*
X440710D01*
X441210Y369900D01*
G01X443210D02*
Y370900D01*
G01X441127Y372708D02*
X440877Y372958D01*
X440752Y373250D01*
X440710Y373583D01*
X440793Y374000D01*
X441002Y374292D01*
X441252Y374375D01*
X441502Y374333D01*
X441710Y374167D01*
X442127Y373333D01*
X442418Y372958D01*
X442835Y372708D01*
X443210Y372625D01*
Y374375D01*
G01X442918Y375892D02*
X443127Y376183D01*
X443210Y376517D01*
X443127Y376850D01*
X442877Y377142D01*
X442502Y377350D01*
X442127Y377433D01*
X441668D01*
X441293Y377350D01*
X440960Y377142D01*
X440793Y376892D01*
X440710Y376600D01*
X440793Y376267D01*
X440960Y376017D01*
X441210Y375850D01*
X441543Y375767D01*
X441835Y375850D01*
X442127Y376058D01*
X442293Y376308D01*
X442335Y376600D01*
X442252Y376933D01*
X442043Y377183D01*
X441668Y377433D01*
G01X413500Y397467D02*
X411000D01*
Y398508D01*
X411125Y398842D01*
X411292Y399050D01*
X411625Y399133D01*
X411958Y399050D01*
X412167Y398800D01*
X412292Y398508D01*
Y397467D01*
G01Y398508D02*
X413500Y399133D01*
G01X413208Y400692D02*
X413417Y400983D01*
X413500Y401317D01*
X413417Y401650D01*
X413167Y401942D01*
X412792Y402150D01*
X412417Y402233D01*
X411958D01*
X411583Y402150D01*
X411250Y401942D01*
X411083Y401692D01*
X411000Y401400D01*
X411083Y401067D01*
X411250Y400817D01*
X411500Y400650D01*
X411833Y400567D01*
X412125Y400650D01*
X412417Y400858D01*
X412583Y401108D01*
X412625Y401400D01*
X412542Y401733D01*
X412333Y401983D01*
X411958Y402233D01*
G01X413125Y403583D02*
X413333Y403833D01*
X413458Y404125D01*
X413500Y404500D01*
X413417Y404875D01*
X413250Y405167D01*
X412958Y405375D01*
X412625Y405417D01*
X412292Y405333D01*
X412083Y405125D01*
X411917Y404833D01*
X411875Y404542D01*
X411917Y404250D01*
X412083Y403875D01*
X411000Y404000D01*
Y405125D01*
G01X413500Y407600D02*
X411000D01*
X411500Y407100D01*
G01X413500D02*
Y408100D01*
G01X411000Y410700D02*
X411083Y410367D01*
X411292Y410117D01*
X411542Y409950D01*
X411875Y409825D01*
X412250Y409783D01*
X412625Y409825D01*
X412958Y409950D01*
X413208Y410117D01*
X413417Y410367D01*
X413500Y410700D01*
X413417Y411033D01*
X413208Y411283D01*
X412958Y411450D01*
X412625Y411575D01*
X412250Y411617D01*
X411875Y411575D01*
X411542Y411450D01*
X411292Y411283D01*
X411083Y411033D01*
X411000Y410700D01*
G01X417417Y449392D02*
X417167Y449517D01*
X416875Y449600D01*
X416542D01*
X416167Y449475D01*
X415875Y449267D01*
X415667Y449017D01*
X415500Y448600D01*
X415458Y448225D01*
X415542Y447850D01*
X415667Y447600D01*
X415917Y447350D01*
X416208Y447183D01*
X416500Y447100D01*
X416792D01*
X417083Y447183D01*
X417333Y447308D01*
X417542Y447475D01*
G01X418892Y447392D02*
X419183Y447183D01*
X419517Y447100D01*
X419850Y447183D01*
X420142Y447433D01*
X420350Y447808D01*
X420433Y448183D01*
Y448642D01*
X420350Y449017D01*
X420142Y449350D01*
X419892Y449517D01*
X419600Y449600D01*
X419267Y449517D01*
X419017Y449350D01*
X418850Y449100D01*
X418767Y448767D01*
X418850Y448475D01*
X419058Y448183D01*
X419308Y448017D01*
X419600Y447975D01*
X419933Y448058D01*
X420183Y448267D01*
X420433Y448642D01*
G01X421783Y447600D02*
X422033Y447308D01*
X422367Y447142D01*
X422742Y447100D01*
X423075Y447142D01*
X423408Y447350D01*
X423617Y447600D01*
X423658Y447850D01*
X423575Y448142D01*
X423283Y448350D01*
X422992Y448433D01*
X422617D01*
G01X422992D02*
X423242Y448558D01*
X423450Y448767D01*
X423533Y449017D01*
X423450Y449267D01*
X423242Y449475D01*
X422867Y449600D01*
X422492Y449558D01*
X422117Y449392D01*
G01X426300Y447100D02*
Y449600D01*
X424758Y447808D01*
X426842D01*
G01X428817Y447100D02*
X428900Y447642D01*
X429025Y448100D01*
X429192Y448517D01*
X429400Y448975D01*
X429733Y449600D01*
X428067D01*
G01X415667Y455100D02*
Y457600D01*
X416708D01*
X417042Y457475D01*
X417250Y457308D01*
X417333Y456975D01*
X417250Y456642D01*
X417000Y456433D01*
X416708Y456308D01*
X415667D01*
G01X416708D02*
X417333Y455100D01*
G01X418892Y455392D02*
X419183Y455183D01*
X419517Y455100D01*
X419850Y455183D01*
X420142Y455433D01*
X420350Y455808D01*
X420433Y456183D01*
Y456642D01*
X420350Y457017D01*
X420142Y457350D01*
X419892Y457517D01*
X419600Y457600D01*
X419267Y457517D01*
X419017Y457350D01*
X418850Y457100D01*
X418767Y456767D01*
X418850Y456475D01*
X419058Y456183D01*
X419308Y456017D01*
X419600Y455975D01*
X419933Y456058D01*
X420183Y456267D01*
X420433Y456642D01*
G01X423200Y455100D02*
Y457600D01*
X421658Y455808D01*
X423742D01*
G01X424883Y455600D02*
X425133Y455308D01*
X425467Y455142D01*
X425842Y455100D01*
X426175Y455142D01*
X426508Y455350D01*
X426717Y455600D01*
X426758Y455850D01*
X426675Y456142D01*
X426383Y456350D01*
X426092Y456433D01*
X425717D01*
G01X426092D02*
X426342Y456558D01*
X426550Y456767D01*
X426633Y457017D01*
X426550Y457267D01*
X426342Y457475D01*
X425967Y457600D01*
X425592Y457558D01*
X425217Y457392D01*
G01X428900Y457600D02*
X428567Y457517D01*
X428317Y457308D01*
X428150Y457058D01*
X428025Y456725D01*
X427983Y456350D01*
X428025Y455975D01*
X428150Y455642D01*
X428317Y455392D01*
X428567Y455183D01*
X428900Y455100D01*
X429233Y455183D01*
X429483Y455392D01*
X429650Y455642D01*
X429775Y455975D01*
X429817Y456350D01*
X429775Y456725D01*
X429650Y457058D01*
X429483Y457308D01*
X429233Y457517D01*
X428900Y457600D01*
G01X427970Y427377D02*
X425470D01*
Y428418D01*
X425595Y428752D01*
X425762Y428960D01*
X426095Y429043D01*
X426428Y428960D01*
X426637Y428710D01*
X426762Y428418D01*
Y427377D01*
G01Y428418D02*
X427970Y429043D01*
G01X427678Y430602D02*
X427887Y430893D01*
X427970Y431227D01*
X427887Y431560D01*
X427637Y431852D01*
X427262Y432060D01*
X426887Y432143D01*
X426428D01*
X426053Y432060D01*
X425720Y431852D01*
X425553Y431602D01*
X425470Y431310D01*
X425553Y430977D01*
X425720Y430727D01*
X425970Y430560D01*
X426303Y430477D01*
X426595Y430560D01*
X426887Y430768D01*
X427053Y431018D01*
X427095Y431310D01*
X427012Y431643D01*
X426803Y431893D01*
X426428Y432143D01*
G01X427970Y434410D02*
X425470D01*
X425970Y433910D01*
G01X427970D02*
Y434910D01*
G01X427470Y436593D02*
X427762Y436843D01*
X427928Y437177D01*
X427970Y437552D01*
X427928Y437885D01*
X427720Y438218D01*
X427470Y438427D01*
X427220Y438468D01*
X426928Y438385D01*
X426720Y438093D01*
X426637Y437802D01*
Y437427D01*
G01Y437802D02*
X426512Y438052D01*
X426303Y438260D01*
X426053Y438343D01*
X425803Y438260D01*
X425595Y438052D01*
X425470Y437677D01*
X425512Y437302D01*
X425678Y436927D01*
G01X425470Y440610D02*
X425553Y440277D01*
X425762Y440027D01*
X426012Y439860D01*
X426345Y439735D01*
X426720Y439693D01*
X427095Y439735D01*
X427428Y439860D01*
X427678Y440027D01*
X427887Y440277D01*
X427970Y440610D01*
X427887Y440943D01*
X427678Y441193D01*
X427428Y441360D01*
X427095Y441485D01*
X426720Y441527D01*
X426345Y441485D01*
X426012Y441360D01*
X425762Y441193D01*
X425553Y440943D01*
X425470Y440610D01*
G01X423970Y427377D02*
X421470D01*
Y428418D01*
X421595Y428752D01*
X421762Y428960D01*
X422095Y429043D01*
X422428Y428960D01*
X422637Y428710D01*
X422762Y428418D01*
Y427377D01*
G01Y428418D02*
X423970Y429043D01*
G01X423678Y430602D02*
X423887Y430893D01*
X423970Y431227D01*
X423887Y431560D01*
X423637Y431852D01*
X423262Y432060D01*
X422887Y432143D01*
X422428D01*
X422053Y432060D01*
X421720Y431852D01*
X421553Y431602D01*
X421470Y431310D01*
X421553Y430977D01*
X421720Y430727D01*
X421970Y430560D01*
X422303Y430477D01*
X422595Y430560D01*
X422887Y430768D01*
X423053Y431018D01*
X423095Y431310D01*
X423012Y431643D01*
X422803Y431893D01*
X422428Y432143D01*
G01X423970Y434410D02*
X421470D01*
X421970Y433910D01*
G01X423970D02*
Y434910D01*
G01X423470Y436593D02*
X423762Y436843D01*
X423928Y437177D01*
X423970Y437552D01*
X423928Y437885D01*
X423720Y438218D01*
X423470Y438427D01*
X423220Y438468D01*
X422928Y438385D01*
X422720Y438093D01*
X422637Y437802D01*
Y437427D01*
G01Y437802D02*
X422512Y438052D01*
X422303Y438260D01*
X422053Y438343D01*
X421803Y438260D01*
X421595Y438052D01*
X421470Y437677D01*
X421512Y437302D01*
X421678Y436927D01*
G01X423970Y440610D02*
X421470D01*
X421970Y440110D01*
G01X423970D02*
Y441110D01*
G01X414970Y427177D02*
X412470D01*
Y428218D01*
X412595Y428552D01*
X412762Y428760D01*
X413095Y428843D01*
X413428Y428760D01*
X413637Y428510D01*
X413762Y428218D01*
Y427177D01*
G01Y428218D02*
X414970Y428843D01*
G01X414678Y430402D02*
X414887Y430693D01*
X414970Y431027D01*
X414887Y431360D01*
X414637Y431652D01*
X414262Y431860D01*
X413887Y431943D01*
X413428D01*
X413053Y431860D01*
X412720Y431652D01*
X412553Y431402D01*
X412470Y431110D01*
X412553Y430777D01*
X412720Y430527D01*
X412970Y430360D01*
X413303Y430277D01*
X413595Y430360D01*
X413887Y430568D01*
X414053Y430818D01*
X414095Y431110D01*
X414012Y431443D01*
X413803Y431693D01*
X413428Y431943D01*
G01X414970Y434210D02*
X412470D01*
X412970Y433710D01*
G01X414970D02*
Y434710D01*
G01X414470Y436393D02*
X414762Y436643D01*
X414928Y436977D01*
X414970Y437352D01*
X414928Y437685D01*
X414720Y438018D01*
X414470Y438227D01*
X414220Y438268D01*
X413928Y438185D01*
X413720Y437893D01*
X413637Y437602D01*
Y437227D01*
G01Y437602D02*
X413512Y437852D01*
X413303Y438060D01*
X413053Y438143D01*
X412803Y438060D01*
X412595Y437852D01*
X412470Y437477D01*
X412512Y437102D01*
X412678Y436727D01*
G01X412887Y439618D02*
X412637Y439868D01*
X412512Y440160D01*
X412470Y440493D01*
X412553Y440910D01*
X412762Y441202D01*
X413012Y441285D01*
X413262Y441243D01*
X413470Y441077D01*
X413887Y440243D01*
X414178Y439868D01*
X414595Y439618D01*
X414970Y439535D01*
Y441285D01*
G01X418970Y427177D02*
X416470D01*
Y428218D01*
X416595Y428552D01*
X416762Y428760D01*
X417095Y428843D01*
X417428Y428760D01*
X417637Y428510D01*
X417762Y428218D01*
Y427177D01*
G01Y428218D02*
X418970Y428843D01*
G01X418678Y430402D02*
X418887Y430693D01*
X418970Y431027D01*
X418887Y431360D01*
X418637Y431652D01*
X418262Y431860D01*
X417887Y431943D01*
X417428D01*
X417053Y431860D01*
X416720Y431652D01*
X416553Y431402D01*
X416470Y431110D01*
X416553Y430777D01*
X416720Y430527D01*
X416970Y430360D01*
X417303Y430277D01*
X417595Y430360D01*
X417887Y430568D01*
X418053Y430818D01*
X418095Y431110D01*
X418012Y431443D01*
X417803Y431693D01*
X417428Y431943D01*
G01X418970Y434210D02*
X416470D01*
X416970Y433710D01*
G01X418970D02*
Y434710D01*
G01X418470Y436393D02*
X418762Y436643D01*
X418928Y436977D01*
X418970Y437352D01*
X418928Y437685D01*
X418720Y438018D01*
X418470Y438227D01*
X418220Y438268D01*
X417928Y438185D01*
X417720Y437893D01*
X417637Y437602D01*
Y437227D01*
G01Y437602D02*
X417512Y437852D01*
X417303Y438060D01*
X417053Y438143D01*
X416803Y438060D01*
X416595Y437852D01*
X416470Y437477D01*
X416512Y437102D01*
X416678Y436727D01*
G01X418470Y439493D02*
X418762Y439743D01*
X418928Y440077D01*
X418970Y440452D01*
X418928Y440785D01*
X418720Y441118D01*
X418470Y441327D01*
X418220Y441368D01*
X417928Y441285D01*
X417720Y440993D01*
X417637Y440702D01*
Y440327D01*
G01Y440702D02*
X417512Y440952D01*
X417303Y441160D01*
X417053Y441243D01*
X416803Y441160D01*
X416595Y440952D01*
X416470Y440577D01*
X416512Y440202D01*
X416678Y439827D01*
G01X412917Y419000D02*
Y421500D01*
X413958D01*
X414292Y421375D01*
X414500Y421208D01*
X414583Y420875D01*
X414500Y420542D01*
X414250Y420333D01*
X413958Y420208D01*
X412917D01*
G01X413958D02*
X414583Y419000D01*
G01X416142Y419292D02*
X416433Y419083D01*
X416767Y419000D01*
X417100Y419083D01*
X417392Y419333D01*
X417600Y419708D01*
X417683Y420083D01*
Y420542D01*
X417600Y420917D01*
X417392Y421250D01*
X417142Y421417D01*
X416850Y421500D01*
X416517Y421417D01*
X416267Y421250D01*
X416100Y421000D01*
X416017Y420667D01*
X416100Y420375D01*
X416308Y420083D01*
X416558Y419917D01*
X416850Y419875D01*
X417183Y419958D01*
X417433Y420167D01*
X417683Y420542D01*
G01X419033Y419375D02*
X419283Y419167D01*
X419575Y419042D01*
X419950Y419000D01*
X420325Y419083D01*
X420617Y419250D01*
X420825Y419542D01*
X420867Y419875D01*
X420783Y420208D01*
X420575Y420417D01*
X420283Y420583D01*
X419992Y420625D01*
X419700Y420583D01*
X419325Y420417D01*
X419450Y421500D01*
X420575D01*
G01X423050Y419000D02*
X423342Y419042D01*
X423675Y419167D01*
X423883Y419375D01*
X423967Y419667D01*
X423883Y419958D01*
X423633Y420208D01*
X423258Y420333D01*
X422842D01*
X422592Y420417D01*
X422383Y420625D01*
X422300Y420917D01*
X422425Y421208D01*
X422717Y421417D01*
X423050Y421500D01*
X423383Y421417D01*
X423675Y421208D01*
X423800Y420917D01*
X423717Y420625D01*
X423508Y420417D01*
X423258Y420333D01*
X422842D01*
X422467Y420208D01*
X422217Y419958D01*
X422133Y419667D01*
X422217Y419375D01*
X422425Y419167D01*
X422758Y419042D01*
X423050Y419000D01*
G01X425233Y419375D02*
X425483Y419167D01*
X425775Y419042D01*
X426150Y419000D01*
X426525Y419083D01*
X426817Y419250D01*
X427025Y419542D01*
X427067Y419875D01*
X426983Y420208D01*
X426775Y420417D01*
X426483Y420583D01*
X426192Y420625D01*
X425900Y420583D01*
X425525Y420417D01*
X425650Y421500D01*
X426775D01*
G01X409200Y417000D02*
X404000D01*
G01X409200D02*
Y424000D01*
G01X415719Y451124D02*
Y453624D01*
X416760D01*
X417094Y453499D01*
X417302Y453332D01*
X417385Y452999D01*
X417302Y452666D01*
X417052Y452457D01*
X416760Y452332D01*
X415719D01*
G01X416760D02*
X417385Y451124D01*
G01X418944Y451416D02*
X419235Y451207D01*
X419569Y451124D01*
X419902Y451207D01*
X420194Y451457D01*
X420402Y451832D01*
X420485Y452207D01*
Y452666D01*
X420402Y453041D01*
X420194Y453374D01*
X419944Y453541D01*
X419652Y453624D01*
X419319Y453541D01*
X419069Y453374D01*
X418902Y453124D01*
X418819Y452791D01*
X418902Y452499D01*
X419110Y452207D01*
X419360Y452041D01*
X419652Y451999D01*
X419985Y452082D01*
X420235Y452291D01*
X420485Y452666D01*
G01X421960Y452166D02*
X422252Y452457D01*
X422502Y452624D01*
X422835Y452707D01*
X423127Y452624D01*
X423335Y452457D01*
X423502Y452207D01*
X423544Y451916D01*
X423502Y451666D01*
X423335Y451416D01*
X423085Y451207D01*
X422794Y451124D01*
X422460Y451207D01*
X422169Y451457D01*
X422002Y451832D01*
X421960Y452249D01*
X422044Y452791D01*
X422169Y453082D01*
X422377Y453374D01*
X422669Y453582D01*
X422960Y453624D01*
X423252Y453541D01*
X423460Y453332D01*
G01X425852Y453624D02*
X425519Y453541D01*
X425269Y453332D01*
X425102Y453082D01*
X424977Y452749D01*
X424935Y452374D01*
X424977Y451999D01*
X425102Y451666D01*
X425269Y451416D01*
X425519Y451207D01*
X425852Y451124D01*
X426185Y451207D01*
X426435Y451416D01*
X426602Y451666D01*
X426727Y451999D01*
X426769Y452374D01*
X426727Y452749D01*
X426602Y453082D01*
X426435Y453332D01*
X426185Y453541D01*
X425852Y453624D01*
G01X429452Y451124D02*
Y453624D01*
X427910Y451832D01*
X429994D01*
G01X439808Y789617D02*
X439683Y789367D01*
X439600Y789075D01*
Y788742D01*
X439725Y788367D01*
X439933Y788075D01*
X440183Y787867D01*
X440600Y787700D01*
X440975Y787658D01*
X441350Y787742D01*
X441600Y787867D01*
X441850Y788117D01*
X442017Y788408D01*
X442100Y788700D01*
Y788992D01*
X442017Y789283D01*
X441892Y789533D01*
X441725Y789742D01*
G01X441808Y791092D02*
X442017Y791383D01*
X442100Y791717D01*
X442017Y792050D01*
X441767Y792342D01*
X441392Y792550D01*
X441017Y792633D01*
X440558D01*
X440183Y792550D01*
X439850Y792342D01*
X439683Y792092D01*
X439600Y791800D01*
X439683Y791467D01*
X439850Y791217D01*
X440100Y791050D01*
X440433Y790967D01*
X440725Y791050D01*
X441017Y791258D01*
X441183Y791508D01*
X441225Y791800D01*
X441142Y792133D01*
X440933Y792383D01*
X440558Y792633D01*
G01X441600Y793983D02*
X441892Y794233D01*
X442058Y794567D01*
X442100Y794942D01*
X442058Y795275D01*
X441850Y795608D01*
X441600Y795817D01*
X441350Y795858D01*
X441058Y795775D01*
X440850Y795483D01*
X440767Y795192D01*
Y794817D01*
G01Y795192D02*
X440642Y795442D01*
X440433Y795650D01*
X440183Y795733D01*
X439933Y795650D01*
X439725Y795442D01*
X439600Y795067D01*
X439642Y794692D01*
X439808Y794317D01*
G01X441725Y797083D02*
X441933Y797333D01*
X442058Y797625D01*
X442100Y798000D01*
X442017Y798375D01*
X441850Y798667D01*
X441558Y798875D01*
X441225Y798917D01*
X440892Y798833D01*
X440683Y798625D01*
X440517Y798333D01*
X440475Y798042D01*
X440517Y797750D01*
X440683Y797375D01*
X439600Y797500D01*
Y798625D01*
G01X442100Y801100D02*
X439600D01*
X440100Y800600D01*
G01X442100D02*
Y801600D01*
G01X439508Y806017D02*
X439383Y805767D01*
X439300Y805475D01*
Y805142D01*
X439425Y804767D01*
X439633Y804475D01*
X439883Y804267D01*
X440300Y804100D01*
X440675Y804058D01*
X441050Y804142D01*
X441300Y804267D01*
X441550Y804517D01*
X441717Y804808D01*
X441800Y805100D01*
Y805392D01*
X441717Y805683D01*
X441592Y805933D01*
X441425Y806142D01*
G01X441508Y807492D02*
X441717Y807783D01*
X441800Y808117D01*
X441717Y808450D01*
X441467Y808742D01*
X441092Y808950D01*
X440717Y809033D01*
X440258D01*
X439883Y808950D01*
X439550Y808742D01*
X439383Y808492D01*
X439300Y808200D01*
X439383Y807867D01*
X439550Y807617D01*
X439800Y807450D01*
X440133Y807367D01*
X440425Y807450D01*
X440717Y807658D01*
X440883Y807908D01*
X440925Y808200D01*
X440842Y808533D01*
X440633Y808783D01*
X440258Y809033D01*
G01X441300Y810383D02*
X441592Y810633D01*
X441758Y810967D01*
X441800Y811342D01*
X441758Y811675D01*
X441550Y812008D01*
X441300Y812217D01*
X441050Y812258D01*
X440758Y812175D01*
X440550Y811883D01*
X440467Y811592D01*
Y811217D01*
G01Y811592D02*
X440342Y811842D01*
X440133Y812050D01*
X439883Y812133D01*
X439633Y812050D01*
X439425Y811842D01*
X439300Y811467D01*
X439342Y811092D01*
X439508Y810717D01*
G01X440758Y813608D02*
X440467Y813900D01*
X440300Y814150D01*
X440217Y814483D01*
X440300Y814775D01*
X440467Y814983D01*
X440717Y815150D01*
X441008Y815192D01*
X441258Y815150D01*
X441508Y814983D01*
X441717Y814733D01*
X441800Y814442D01*
X441717Y814108D01*
X441467Y813817D01*
X441092Y813650D01*
X440675Y813608D01*
X440133Y813692D01*
X439842Y813817D01*
X439550Y814025D01*
X439342Y814317D01*
X439300Y814608D01*
X439383Y814900D01*
X439592Y815108D01*
G01X441300Y816583D02*
X441592Y816833D01*
X441758Y817167D01*
X441800Y817542D01*
X441758Y817875D01*
X441550Y818208D01*
X441300Y818417D01*
X441050Y818458D01*
X440758Y818375D01*
X440550Y818083D01*
X440467Y817792D01*
Y817417D01*
G01Y817792D02*
X440342Y818042D01*
X440133Y818250D01*
X439883Y818333D01*
X439633Y818250D01*
X439425Y818042D01*
X439300Y817667D01*
X439342Y817292D01*
X439508Y816917D01*
G01X413748Y844467D02*
X413623Y844217D01*
X413540Y843925D01*
Y843592D01*
X413665Y843217D01*
X413873Y842925D01*
X414123Y842717D01*
X414540Y842550D01*
X414915Y842508D01*
X415290Y842592D01*
X415540Y842717D01*
X415790Y842967D01*
X415957Y843258D01*
X416040Y843550D01*
Y843842D01*
X415957Y844133D01*
X415832Y844383D01*
X415665Y844592D01*
G01X416040Y846650D02*
X415998Y846942D01*
X415873Y847275D01*
X415665Y847483D01*
X415373Y847567D01*
X415082Y847483D01*
X414832Y847233D01*
X414707Y846858D01*
Y846442D01*
X414623Y846192D01*
X414415Y845983D01*
X414123Y845900D01*
X413832Y846025D01*
X413623Y846317D01*
X413540Y846650D01*
X413623Y846983D01*
X413832Y847275D01*
X414123Y847400D01*
X414415Y847317D01*
X414623Y847108D01*
X414707Y846858D01*
Y846442D01*
X414832Y846067D01*
X415082Y845817D01*
X415373Y845733D01*
X415665Y845817D01*
X415873Y846025D01*
X415998Y846358D01*
X416040Y846650D01*
G01Y849750D02*
X415998Y850042D01*
X415873Y850375D01*
X415665Y850583D01*
X415373Y850667D01*
X415082Y850583D01*
X414832Y850333D01*
X414707Y849958D01*
Y849542D01*
X414623Y849292D01*
X414415Y849083D01*
X414123Y849000D01*
X413832Y849125D01*
X413623Y849417D01*
X413540Y849750D01*
X413623Y850083D01*
X413832Y850375D01*
X414123Y850500D01*
X414415Y850417D01*
X414623Y850208D01*
X414707Y849958D01*
Y849542D01*
X414832Y849167D01*
X415082Y848917D01*
X415373Y848833D01*
X415665Y848917D01*
X415873Y849125D01*
X415998Y849458D01*
X416040Y849750D01*
G01X414998Y852058D02*
X414707Y852350D01*
X414540Y852600D01*
X414457Y852933D01*
X414540Y853225D01*
X414707Y853433D01*
X414957Y853600D01*
X415248Y853642D01*
X415498Y853600D01*
X415748Y853433D01*
X415957Y853183D01*
X416040Y852892D01*
X415957Y852558D01*
X415707Y852267D01*
X415332Y852100D01*
X414915Y852058D01*
X414373Y852142D01*
X414082Y852267D01*
X413790Y852475D01*
X413582Y852767D01*
X413540Y853058D01*
X413623Y853350D01*
X413832Y853558D01*
G01X413957Y855158D02*
X413707Y855408D01*
X413582Y855700D01*
X413540Y856033D01*
X413623Y856450D01*
X413832Y856742D01*
X414082Y856825D01*
X414332Y856783D01*
X414540Y856617D01*
X414957Y855783D01*
X415248Y855408D01*
X415665Y855158D01*
X416040Y855075D01*
Y856825D01*
G01X405497Y830947D02*
X405372Y830697D01*
X405289Y830405D01*
Y830072D01*
X405414Y829697D01*
X405622Y829405D01*
X405872Y829197D01*
X406289Y829030D01*
X406664Y828988D01*
X407039Y829072D01*
X407289Y829197D01*
X407539Y829447D01*
X407706Y829738D01*
X407789Y830030D01*
Y830322D01*
X407706Y830613D01*
X407581Y830863D01*
X407414Y831072D01*
G01X407497Y832422D02*
X407706Y832713D01*
X407789Y833047D01*
X407706Y833380D01*
X407456Y833672D01*
X407081Y833880D01*
X406706Y833963D01*
X406247D01*
X405872Y833880D01*
X405539Y833672D01*
X405372Y833422D01*
X405289Y833130D01*
X405372Y832797D01*
X405539Y832547D01*
X405789Y832380D01*
X406122Y832297D01*
X406414Y832380D01*
X406706Y832588D01*
X406872Y832838D01*
X406914Y833130D01*
X406831Y833463D01*
X406622Y833713D01*
X406247Y833963D01*
G01X407414Y835313D02*
X407622Y835563D01*
X407747Y835855D01*
X407789Y836230D01*
X407706Y836605D01*
X407539Y836897D01*
X407247Y837105D01*
X406914Y837147D01*
X406581Y837063D01*
X406372Y836855D01*
X406206Y836563D01*
X406164Y836272D01*
X406206Y835980D01*
X406372Y835605D01*
X405289Y835730D01*
Y836855D01*
G01X407789Y839330D02*
X405289D01*
X405789Y838830D01*
G01X407789D02*
Y839830D01*
G01X406747Y841638D02*
X406456Y841930D01*
X406289Y842180D01*
X406206Y842513D01*
X406289Y842805D01*
X406456Y843013D01*
X406706Y843180D01*
X406997Y843222D01*
X407247Y843180D01*
X407497Y843013D01*
X407706Y842763D01*
X407789Y842472D01*
X407706Y842138D01*
X407456Y841847D01*
X407081Y841680D01*
X406664Y841638D01*
X406122Y841722D01*
X405831Y841847D01*
X405539Y842055D01*
X405331Y842347D01*
X405289Y842638D01*
X405372Y842930D01*
X405581Y843138D01*
G01X450100Y787867D02*
X447600D01*
Y788908D01*
X447725Y789242D01*
X447892Y789450D01*
X448225Y789533D01*
X448558Y789450D01*
X448767Y789200D01*
X448892Y788908D01*
Y787867D01*
G01Y788908D02*
X450100Y789533D01*
G01X449808Y791092D02*
X450017Y791383D01*
X450100Y791717D01*
X450017Y792050D01*
X449767Y792342D01*
X449392Y792550D01*
X449017Y792633D01*
X448558D01*
X448183Y792550D01*
X447850Y792342D01*
X447683Y792092D01*
X447600Y791800D01*
X447683Y791467D01*
X447850Y791217D01*
X448100Y791050D01*
X448433Y790967D01*
X448725Y791050D01*
X449017Y791258D01*
X449183Y791508D01*
X449225Y791800D01*
X449142Y792133D01*
X448933Y792383D01*
X448558Y792633D01*
G01X450100Y795400D02*
X447600D01*
X449392Y793858D01*
Y795942D01*
G01X450100Y798500D02*
X447600D01*
X449392Y796958D01*
Y799042D01*
G01X450100Y801600D02*
X447600D01*
X449392Y800058D01*
Y802142D01*
G01X431000Y814700D02*
X427000D01*
Y807300D01*
G01X411367Y828961D02*
Y831461D01*
X412408D01*
X412742Y831336D01*
X412950Y831169D01*
X413033Y830836D01*
X412950Y830503D01*
X412700Y830294D01*
X412408Y830169D01*
X411367D01*
G01X412408D02*
X413033Y828961D01*
G01X414592Y829253D02*
X414883Y829044D01*
X415217Y828961D01*
X415550Y829044D01*
X415842Y829294D01*
X416050Y829669D01*
X416133Y830044D01*
Y830503D01*
X416050Y830878D01*
X415842Y831211D01*
X415592Y831378D01*
X415300Y831461D01*
X414967Y831378D01*
X414717Y831211D01*
X414550Y830961D01*
X414467Y830628D01*
X414550Y830336D01*
X414758Y830044D01*
X415008Y829878D01*
X415300Y829836D01*
X415633Y829919D01*
X415883Y830128D01*
X416133Y830503D01*
G01X418400Y831461D02*
X418067Y831378D01*
X417817Y831169D01*
X417650Y830919D01*
X417525Y830586D01*
X417483Y830211D01*
X417525Y829836D01*
X417650Y829503D01*
X417817Y829253D01*
X418067Y829044D01*
X418400Y828961D01*
X418733Y829044D01*
X418983Y829253D01*
X419150Y829503D01*
X419275Y829836D01*
X419317Y830211D01*
X419275Y830586D01*
X419150Y830919D01*
X418983Y831169D01*
X418733Y831378D01*
X418400Y831461D01*
G01X421500Y828961D02*
X421792Y829003D01*
X422125Y829128D01*
X422333Y829336D01*
X422417Y829628D01*
X422333Y829919D01*
X422083Y830169D01*
X421708Y830294D01*
X421292D01*
X421042Y830378D01*
X420833Y830586D01*
X420750Y830878D01*
X420875Y831169D01*
X421167Y831378D01*
X421500Y831461D01*
X421833Y831378D01*
X422125Y831169D01*
X422250Y830878D01*
X422167Y830586D01*
X421958Y830378D01*
X421708Y830294D01*
X421292D01*
X420917Y830169D01*
X420667Y829919D01*
X420583Y829628D01*
X420667Y829336D01*
X420875Y829128D01*
X421208Y829003D01*
X421500Y828961D01*
G01X424600D02*
Y831461D01*
X424100Y830961D01*
G01Y828961D02*
X425100D01*
G01X409567Y795281D02*
Y797781D01*
X410608D01*
X410942Y797656D01*
X411150Y797489D01*
X411233Y797156D01*
X411150Y796823D01*
X410900Y796614D01*
X410608Y796489D01*
X409567D01*
G01X410608D02*
X411233Y795281D01*
G01X412792Y795573D02*
X413083Y795364D01*
X413417Y795281D01*
X413750Y795364D01*
X414042Y795614D01*
X414250Y795989D01*
X414333Y796364D01*
Y796823D01*
X414250Y797198D01*
X414042Y797531D01*
X413792Y797698D01*
X413500Y797781D01*
X413167Y797698D01*
X412917Y797531D01*
X412750Y797281D01*
X412667Y796948D01*
X412750Y796656D01*
X412958Y796364D01*
X413208Y796198D01*
X413500Y796156D01*
X413833Y796239D01*
X414083Y796448D01*
X414333Y796823D01*
G01X416600Y797781D02*
X416267Y797698D01*
X416017Y797489D01*
X415850Y797239D01*
X415725Y796906D01*
X415683Y796531D01*
X415725Y796156D01*
X415850Y795823D01*
X416017Y795573D01*
X416267Y795364D01*
X416600Y795281D01*
X416933Y795364D01*
X417183Y795573D01*
X417350Y795823D01*
X417475Y796156D01*
X417517Y796531D01*
X417475Y796906D01*
X417350Y797239D01*
X417183Y797489D01*
X416933Y797698D01*
X416600Y797781D01*
G01X419700Y795281D02*
X419992Y795323D01*
X420325Y795448D01*
X420533Y795656D01*
X420617Y795948D01*
X420533Y796239D01*
X420283Y796489D01*
X419908Y796614D01*
X419492D01*
X419242Y796698D01*
X419033Y796906D01*
X418950Y797198D01*
X419075Y797489D01*
X419367Y797698D01*
X419700Y797781D01*
X420033Y797698D01*
X420325Y797489D01*
X420450Y797198D01*
X420367Y796906D01*
X420158Y796698D01*
X419908Y796614D01*
X419492D01*
X419117Y796489D01*
X418867Y796239D01*
X418783Y795948D01*
X418867Y795656D01*
X419075Y795448D01*
X419408Y795323D01*
X419700Y795281D01*
G01X422008Y797364D02*
X422258Y797614D01*
X422550Y797739D01*
X422883Y797781D01*
X423300Y797698D01*
X423592Y797489D01*
X423675Y797239D01*
X423633Y796989D01*
X423467Y796781D01*
X422633Y796364D01*
X422258Y796073D01*
X422008Y795656D01*
X421925Y795281D01*
X423675D01*
G01X411367Y832961D02*
Y835461D01*
X412408D01*
X412742Y835336D01*
X412950Y835169D01*
X413033Y834836D01*
X412950Y834503D01*
X412700Y834294D01*
X412408Y834169D01*
X411367D01*
G01X412408D02*
X413033Y832961D01*
G01X414592Y833253D02*
X414883Y833044D01*
X415217Y832961D01*
X415550Y833044D01*
X415842Y833294D01*
X416050Y833669D01*
X416133Y834044D01*
Y834503D01*
X416050Y834878D01*
X415842Y835211D01*
X415592Y835378D01*
X415300Y835461D01*
X414967Y835378D01*
X414717Y835211D01*
X414550Y834961D01*
X414467Y834628D01*
X414550Y834336D01*
X414758Y834044D01*
X415008Y833878D01*
X415300Y833836D01*
X415633Y833919D01*
X415883Y834128D01*
X416133Y834503D01*
G01X418400Y835461D02*
X418067Y835378D01*
X417817Y835169D01*
X417650Y834919D01*
X417525Y834586D01*
X417483Y834211D01*
X417525Y833836D01*
X417650Y833503D01*
X417817Y833253D01*
X418067Y833044D01*
X418400Y832961D01*
X418733Y833044D01*
X418983Y833253D01*
X419150Y833503D01*
X419275Y833836D01*
X419317Y834211D01*
X419275Y834586D01*
X419150Y834919D01*
X418983Y835169D01*
X418733Y835378D01*
X418400Y835461D01*
G01X421500Y832961D02*
X421792Y833003D01*
X422125Y833128D01*
X422333Y833336D01*
X422417Y833628D01*
X422333Y833919D01*
X422083Y834169D01*
X421708Y834294D01*
X421292D01*
X421042Y834378D01*
X420833Y834586D01*
X420750Y834878D01*
X420875Y835169D01*
X421167Y835378D01*
X421500Y835461D01*
X421833Y835378D01*
X422125Y835169D01*
X422250Y834878D01*
X422167Y834586D01*
X421958Y834378D01*
X421708Y834294D01*
X421292D01*
X420917Y834169D01*
X420667Y833919D01*
X420583Y833628D01*
X420667Y833336D01*
X420875Y833128D01*
X421208Y833003D01*
X421500Y832961D01*
G01X423683Y833461D02*
X423933Y833169D01*
X424267Y833003D01*
X424642Y832961D01*
X424975Y833003D01*
X425308Y833211D01*
X425517Y833461D01*
X425558Y833711D01*
X425475Y834003D01*
X425183Y834211D01*
X424892Y834294D01*
X424517D01*
G01X424892D02*
X425142Y834419D01*
X425350Y834628D01*
X425433Y834878D01*
X425350Y835128D01*
X425142Y835336D01*
X424767Y835461D01*
X424392Y835419D01*
X424017Y835253D01*
G01X409567Y799281D02*
Y801781D01*
X410608D01*
X410942Y801656D01*
X411150Y801489D01*
X411233Y801156D01*
X411150Y800823D01*
X410900Y800614D01*
X410608Y800489D01*
X409567D01*
G01X410608D02*
X411233Y799281D01*
G01X412792Y799573D02*
X413083Y799364D01*
X413417Y799281D01*
X413750Y799364D01*
X414042Y799614D01*
X414250Y799989D01*
X414333Y800364D01*
Y800823D01*
X414250Y801198D01*
X414042Y801531D01*
X413792Y801698D01*
X413500Y801781D01*
X413167Y801698D01*
X412917Y801531D01*
X412750Y801281D01*
X412667Y800948D01*
X412750Y800656D01*
X412958Y800364D01*
X413208Y800198D01*
X413500Y800156D01*
X413833Y800239D01*
X414083Y800448D01*
X414333Y800823D01*
G01X416600Y801781D02*
X416267Y801698D01*
X416017Y801489D01*
X415850Y801239D01*
X415725Y800906D01*
X415683Y800531D01*
X415725Y800156D01*
X415850Y799823D01*
X416017Y799573D01*
X416267Y799364D01*
X416600Y799281D01*
X416933Y799364D01*
X417183Y799573D01*
X417350Y799823D01*
X417475Y800156D01*
X417517Y800531D01*
X417475Y800906D01*
X417350Y801239D01*
X417183Y801489D01*
X416933Y801698D01*
X416600Y801781D01*
G01X419700Y799281D02*
X419992Y799323D01*
X420325Y799448D01*
X420533Y799656D01*
X420617Y799948D01*
X420533Y800239D01*
X420283Y800489D01*
X419908Y800614D01*
X419492D01*
X419242Y800698D01*
X419033Y800906D01*
X418950Y801198D01*
X419075Y801489D01*
X419367Y801698D01*
X419700Y801781D01*
X420033Y801698D01*
X420325Y801489D01*
X420450Y801198D01*
X420367Y800906D01*
X420158Y800698D01*
X419908Y800614D01*
X419492D01*
X419117Y800489D01*
X418867Y800239D01*
X418783Y799948D01*
X418867Y799656D01*
X419075Y799448D01*
X419408Y799323D01*
X419700Y799281D01*
G01X421883Y799656D02*
X422133Y799448D01*
X422425Y799323D01*
X422800Y799281D01*
X423175Y799364D01*
X423467Y799531D01*
X423675Y799823D01*
X423717Y800156D01*
X423633Y800489D01*
X423425Y800698D01*
X423133Y800864D01*
X422842Y800906D01*
X422550Y800864D01*
X422175Y800698D01*
X422300Y801781D01*
X423425D01*
G01X421967Y841000D02*
Y843500D01*
X423008D01*
X423342Y843375D01*
X423550Y843208D01*
X423633Y842875D01*
X423550Y842542D01*
X423300Y842333D01*
X423008Y842208D01*
X421967D01*
G01X423008D02*
X423633Y841000D01*
G01X425192Y841292D02*
X425483Y841083D01*
X425817Y841000D01*
X426150Y841083D01*
X426442Y841333D01*
X426650Y841708D01*
X426733Y842083D01*
Y842542D01*
X426650Y842917D01*
X426442Y843250D01*
X426192Y843417D01*
X425900Y843500D01*
X425567Y843417D01*
X425317Y843250D01*
X425150Y843000D01*
X425067Y842667D01*
X425150Y842375D01*
X425358Y842083D01*
X425608Y841917D01*
X425900Y841875D01*
X426233Y841958D01*
X426483Y842167D01*
X426733Y842542D01*
G01X428083Y841375D02*
X428333Y841167D01*
X428625Y841042D01*
X429000Y841000D01*
X429375Y841083D01*
X429667Y841250D01*
X429875Y841542D01*
X429917Y841875D01*
X429833Y842208D01*
X429625Y842417D01*
X429333Y842583D01*
X429042Y842625D01*
X428750Y842583D01*
X428375Y842417D01*
X428500Y843500D01*
X429625D01*
G01X432100D02*
X431767Y843417D01*
X431517Y843208D01*
X431350Y842958D01*
X431225Y842625D01*
X431183Y842250D01*
X431225Y841875D01*
X431350Y841542D01*
X431517Y841292D01*
X431767Y841083D01*
X432100Y841000D01*
X432433Y841083D01*
X432683Y841292D01*
X432850Y841542D01*
X432975Y841875D01*
X433017Y842250D01*
X432975Y842625D01*
X432850Y842958D01*
X432683Y843208D01*
X432433Y843417D01*
X432100Y843500D01*
G01X434492Y841292D02*
X434783Y841083D01*
X435117Y841000D01*
X435450Y841083D01*
X435742Y841333D01*
X435950Y841708D01*
X436033Y842083D01*
Y842542D01*
X435950Y842917D01*
X435742Y843250D01*
X435492Y843417D01*
X435200Y843500D01*
X434867Y843417D01*
X434617Y843250D01*
X434450Y843000D01*
X434367Y842667D01*
X434450Y842375D01*
X434658Y842083D01*
X434908Y841917D01*
X435200Y841875D01*
X435533Y841958D01*
X435783Y842167D01*
X436033Y842542D01*
G01X449800Y804267D02*
X447300D01*
Y805308D01*
X447425Y805642D01*
X447592Y805850D01*
X447925Y805933D01*
X448258Y805850D01*
X448467Y805600D01*
X448592Y805308D01*
Y804267D01*
G01Y805308D02*
X449800Y805933D01*
G01X449508Y807492D02*
X449717Y807783D01*
X449800Y808117D01*
X449717Y808450D01*
X449467Y808742D01*
X449092Y808950D01*
X448717Y809033D01*
X448258D01*
X447883Y808950D01*
X447550Y808742D01*
X447383Y808492D01*
X447300Y808200D01*
X447383Y807867D01*
X447550Y807617D01*
X447800Y807450D01*
X448133Y807367D01*
X448425Y807450D01*
X448717Y807658D01*
X448883Y807908D01*
X448925Y808200D01*
X448842Y808533D01*
X448633Y808783D01*
X448258Y809033D01*
G01X449800Y811800D02*
X447300D01*
X449092Y810258D01*
Y812342D01*
G01X449508Y813692D02*
X449717Y813983D01*
X449800Y814317D01*
X449717Y814650D01*
X449467Y814942D01*
X449092Y815150D01*
X448717Y815233D01*
X448258D01*
X447883Y815150D01*
X447550Y814942D01*
X447383Y814692D01*
X447300Y814400D01*
X447383Y814067D01*
X447550Y813817D01*
X447800Y813650D01*
X448133Y813567D01*
X448425Y813650D01*
X448717Y813858D01*
X448883Y814108D01*
X448925Y814400D01*
X448842Y814733D01*
X448633Y814983D01*
X448258Y815233D01*
G01X447300Y817500D02*
X447383Y817167D01*
X447592Y816917D01*
X447842Y816750D01*
X448175Y816625D01*
X448550Y816583D01*
X448925Y816625D01*
X449258Y816750D01*
X449508Y816917D01*
X449717Y817167D01*
X449800Y817500D01*
X449717Y817833D01*
X449508Y818083D01*
X449258Y818250D01*
X448925Y818375D01*
X448550Y818417D01*
X448175Y818375D01*
X447842Y818250D01*
X447592Y818083D01*
X447383Y817833D01*
X447300Y817500D01*
G01X431000Y822700D02*
X427000D01*
Y815300D01*
G01X409200Y847000D02*
X404000D01*
G01X409200D02*
Y854000D01*
G01X445833Y803967D02*
X443333D01*
Y805008D01*
X443458Y805342D01*
X443625Y805550D01*
X443958Y805633D01*
X444291Y805550D01*
X444500Y805300D01*
X444625Y805008D01*
Y803967D01*
G01Y805008D02*
X445833Y805633D01*
G01X445541Y807192D02*
X445750Y807483D01*
X445833Y807817D01*
X445750Y808150D01*
X445500Y808442D01*
X445125Y808650D01*
X444750Y808733D01*
X444291D01*
X443916Y808650D01*
X443583Y808442D01*
X443416Y808192D01*
X443333Y807900D01*
X443416Y807567D01*
X443583Y807317D01*
X443833Y807150D01*
X444166Y807067D01*
X444458Y807150D01*
X444750Y807358D01*
X444916Y807608D01*
X444958Y807900D01*
X444875Y808233D01*
X444666Y808483D01*
X444291Y808733D01*
G01X445458Y810083D02*
X445666Y810333D01*
X445791Y810625D01*
X445833Y811000D01*
X445750Y811375D01*
X445583Y811667D01*
X445291Y811875D01*
X444958Y811917D01*
X444625Y811833D01*
X444416Y811625D01*
X444250Y811333D01*
X444208Y811042D01*
X444250Y810750D01*
X444416Y810375D01*
X443333Y810500D01*
Y811625D01*
G01X445541Y813392D02*
X445750Y813683D01*
X445833Y814017D01*
X445750Y814350D01*
X445500Y814642D01*
X445125Y814850D01*
X444750Y814933D01*
X444291D01*
X443916Y814850D01*
X443583Y814642D01*
X443416Y814392D01*
X443333Y814100D01*
X443416Y813767D01*
X443583Y813517D01*
X443833Y813350D01*
X444166Y813267D01*
X444458Y813350D01*
X444750Y813558D01*
X444916Y813808D01*
X444958Y814100D01*
X444875Y814433D01*
X444666Y814683D01*
X444291Y814933D01*
G01X445458Y816283D02*
X445666Y816533D01*
X445791Y816825D01*
X445833Y817200D01*
X445750Y817575D01*
X445583Y817867D01*
X445291Y818075D01*
X444958Y818117D01*
X444625Y818033D01*
X444416Y817825D01*
X444250Y817533D01*
X444208Y817242D01*
X444250Y816950D01*
X444416Y816575D01*
X443333Y816700D01*
Y817825D01*
G01X426700Y815500D02*
Y819500D01*
X419300D01*
G01X446176Y787619D02*
X443676D01*
Y788660D01*
X443801Y788994D01*
X443968Y789202D01*
X444301Y789285D01*
X444634Y789202D01*
X444843Y788952D01*
X444968Y788660D01*
Y787619D01*
G01Y788660D02*
X446176Y789285D01*
G01X445884Y790844D02*
X446093Y791135D01*
X446176Y791469D01*
X446093Y791802D01*
X445843Y792094D01*
X445468Y792302D01*
X445093Y792385D01*
X444634D01*
X444259Y792302D01*
X443926Y792094D01*
X443759Y791844D01*
X443676Y791552D01*
X443759Y791219D01*
X443926Y790969D01*
X444176Y790802D01*
X444509Y790719D01*
X444801Y790802D01*
X445093Y791010D01*
X445259Y791260D01*
X445301Y791552D01*
X445218Y791885D01*
X445009Y792135D01*
X444634Y792385D01*
G01X445801Y793735D02*
X446009Y793985D01*
X446134Y794277D01*
X446176Y794652D01*
X446093Y795027D01*
X445926Y795319D01*
X445634Y795527D01*
X445301Y795569D01*
X444968Y795485D01*
X444759Y795277D01*
X444593Y794985D01*
X444551Y794694D01*
X444593Y794402D01*
X444759Y794027D01*
X443676Y794152D01*
Y795277D01*
G01X445884Y797044D02*
X446093Y797335D01*
X446176Y797669D01*
X446093Y798002D01*
X445843Y798294D01*
X445468Y798502D01*
X445093Y798585D01*
X444634D01*
X444259Y798502D01*
X443926Y798294D01*
X443759Y798044D01*
X443676Y797752D01*
X443759Y797419D01*
X443926Y797169D01*
X444176Y797002D01*
X444509Y796919D01*
X444801Y797002D01*
X445093Y797210D01*
X445259Y797460D01*
X445301Y797752D01*
X445218Y798085D01*
X445009Y798335D01*
X444634Y798585D01*
G01X446176Y801352D02*
X443676D01*
X445468Y799810D01*
Y801894D01*
G01X426700Y807500D02*
Y811500D01*
X419300D01*
G01X419117Y884492D02*
X418867Y884617D01*
X418575Y884700D01*
X418242D01*
X417867Y884575D01*
X417575Y884367D01*
X417367Y884117D01*
X417200Y883700D01*
X417158Y883325D01*
X417242Y882950D01*
X417367Y882700D01*
X417617Y882450D01*
X417908Y882283D01*
X418200Y882200D01*
X418492D01*
X418783Y882283D01*
X419033Y882408D01*
X419242Y882575D01*
G01X420592Y882492D02*
X420883Y882283D01*
X421217Y882200D01*
X421550Y882283D01*
X421842Y882533D01*
X422050Y882908D01*
X422133Y883283D01*
Y883742D01*
X422050Y884117D01*
X421842Y884450D01*
X421592Y884617D01*
X421300Y884700D01*
X420967Y884617D01*
X420717Y884450D01*
X420550Y884200D01*
X420467Y883867D01*
X420550Y883575D01*
X420758Y883283D01*
X421008Y883117D01*
X421300Y883075D01*
X421633Y883158D01*
X421883Y883367D01*
X422133Y883742D01*
G01X423483Y882700D02*
X423733Y882408D01*
X424067Y882242D01*
X424442Y882200D01*
X424775Y882242D01*
X425108Y882450D01*
X425317Y882700D01*
X425358Y882950D01*
X425275Y883242D01*
X424983Y883450D01*
X424692Y883533D01*
X424317D01*
G01X424692D02*
X424942Y883658D01*
X425150Y883867D01*
X425233Y884117D01*
X425150Y884367D01*
X424942Y884575D01*
X424567Y884700D01*
X424192Y884658D01*
X423817Y884492D01*
G01X426583Y882575D02*
X426833Y882367D01*
X427125Y882242D01*
X427500Y882200D01*
X427875Y882283D01*
X428167Y882450D01*
X428375Y882742D01*
X428417Y883075D01*
X428333Y883408D01*
X428125Y883617D01*
X427833Y883783D01*
X427542Y883825D01*
X427250Y883783D01*
X426875Y883617D01*
X427000Y884700D01*
X428125D01*
G01X430517Y882200D02*
X430600Y882742D01*
X430725Y883200D01*
X430892Y883617D01*
X431100Y884075D01*
X431433Y884700D01*
X429767D01*
G01X417367Y890200D02*
Y892700D01*
X418408D01*
X418742Y892575D01*
X418950Y892408D01*
X419033Y892075D01*
X418950Y891742D01*
X418700Y891533D01*
X418408Y891408D01*
X417367D01*
G01X418408D02*
X419033Y890200D01*
G01X420592Y890492D02*
X420883Y890283D01*
X421217Y890200D01*
X421550Y890283D01*
X421842Y890533D01*
X422050Y890908D01*
X422133Y891283D01*
Y891742D01*
X422050Y892117D01*
X421842Y892450D01*
X421592Y892617D01*
X421300Y892700D01*
X420967Y892617D01*
X420717Y892450D01*
X420550Y892200D01*
X420467Y891867D01*
X420550Y891575D01*
X420758Y891283D01*
X421008Y891117D01*
X421300Y891075D01*
X421633Y891158D01*
X421883Y891367D01*
X422133Y891742D01*
G01X424900Y890200D02*
Y892700D01*
X423358Y890908D01*
X425442D01*
G01X426708Y891242D02*
X427000Y891533D01*
X427250Y891700D01*
X427583Y891783D01*
X427875Y891700D01*
X428083Y891533D01*
X428250Y891283D01*
X428292Y890992D01*
X428250Y890742D01*
X428083Y890492D01*
X427833Y890283D01*
X427542Y890200D01*
X427208Y890283D01*
X426917Y890533D01*
X426750Y890908D01*
X426708Y891325D01*
X426792Y891867D01*
X426917Y892158D01*
X427125Y892450D01*
X427417Y892658D01*
X427708Y892700D01*
X428000Y892617D01*
X428208Y892408D01*
G01X429683Y890575D02*
X429933Y890367D01*
X430225Y890242D01*
X430600Y890200D01*
X430975Y890283D01*
X431267Y890450D01*
X431475Y890742D01*
X431517Y891075D01*
X431433Y891408D01*
X431225Y891617D01*
X430933Y891783D01*
X430642Y891825D01*
X430350Y891783D01*
X429975Y891617D01*
X430100Y892700D01*
X431225D01*
G01X418760Y860317D02*
X416260D01*
Y861358D01*
X416385Y861692D01*
X416552Y861900D01*
X416885Y861983D01*
X417218Y861900D01*
X417427Y861650D01*
X417552Y861358D01*
Y860317D01*
G01Y861358D02*
X418760Y861983D01*
G01X418468Y863542D02*
X418677Y863833D01*
X418760Y864167D01*
X418677Y864500D01*
X418427Y864792D01*
X418052Y865000D01*
X417677Y865083D01*
X417218D01*
X416843Y865000D01*
X416510Y864792D01*
X416343Y864542D01*
X416260Y864250D01*
X416343Y863917D01*
X416510Y863667D01*
X416760Y863500D01*
X417093Y863417D01*
X417385Y863500D01*
X417677Y863708D01*
X417843Y863958D01*
X417885Y864250D01*
X417802Y864583D01*
X417593Y864833D01*
X417218Y865083D01*
G01X416260Y867350D02*
X416343Y867017D01*
X416552Y866767D01*
X416802Y866600D01*
X417135Y866475D01*
X417510Y866433D01*
X417885Y866475D01*
X418218Y866600D01*
X418468Y866767D01*
X418677Y867017D01*
X418760Y867350D01*
X418677Y867683D01*
X418468Y867933D01*
X418218Y868100D01*
X417885Y868225D01*
X417510Y868267D01*
X417135Y868225D01*
X416802Y868100D01*
X416552Y867933D01*
X416343Y867683D01*
X416260Y867350D01*
G01X418468Y869742D02*
X418677Y870033D01*
X418760Y870367D01*
X418677Y870700D01*
X418427Y870992D01*
X418052Y871200D01*
X417677Y871283D01*
X417218D01*
X416843Y871200D01*
X416510Y870992D01*
X416343Y870742D01*
X416260Y870450D01*
X416343Y870117D01*
X416510Y869867D01*
X416760Y869700D01*
X417093Y869617D01*
X417385Y869700D01*
X417677Y869908D01*
X417843Y870158D01*
X417885Y870450D01*
X417802Y870783D01*
X417593Y871033D01*
X417218Y871283D01*
G01X418760Y874050D02*
X416260D01*
X418052Y872508D01*
Y874592D01*
G01X428760Y860317D02*
X426260D01*
Y861358D01*
X426385Y861692D01*
X426552Y861900D01*
X426885Y861983D01*
X427218Y861900D01*
X427427Y861650D01*
X427552Y861358D01*
Y860317D01*
G01Y861358D02*
X428760Y861983D01*
G01X428468Y863542D02*
X428677Y863833D01*
X428760Y864167D01*
X428677Y864500D01*
X428427Y864792D01*
X428052Y865000D01*
X427677Y865083D01*
X427218D01*
X426843Y865000D01*
X426510Y864792D01*
X426343Y864542D01*
X426260Y864250D01*
X426343Y863917D01*
X426510Y863667D01*
X426760Y863500D01*
X427093Y863417D01*
X427385Y863500D01*
X427677Y863708D01*
X427843Y863958D01*
X427885Y864250D01*
X427802Y864583D01*
X427593Y864833D01*
X427218Y865083D01*
G01X426260Y867350D02*
X426343Y867017D01*
X426552Y866767D01*
X426802Y866600D01*
X427135Y866475D01*
X427510Y866433D01*
X427885Y866475D01*
X428218Y866600D01*
X428468Y866767D01*
X428677Y867017D01*
X428760Y867350D01*
X428677Y867683D01*
X428468Y867933D01*
X428218Y868100D01*
X427885Y868225D01*
X427510Y868267D01*
X427135Y868225D01*
X426802Y868100D01*
X426552Y867933D01*
X426343Y867683D01*
X426260Y867350D01*
G01X428468Y869742D02*
X428677Y870033D01*
X428760Y870367D01*
X428677Y870700D01*
X428427Y870992D01*
X428052Y871200D01*
X427677Y871283D01*
X427218D01*
X426843Y871200D01*
X426510Y870992D01*
X426343Y870742D01*
X426260Y870450D01*
X426343Y870117D01*
X426510Y869867D01*
X426760Y869700D01*
X427093Y869617D01*
X427385Y869700D01*
X427677Y869908D01*
X427843Y870158D01*
X427885Y870450D01*
X427802Y870783D01*
X427593Y871033D01*
X427218Y871283D01*
G01X428385Y872633D02*
X428593Y872883D01*
X428718Y873175D01*
X428760Y873550D01*
X428677Y873925D01*
X428510Y874217D01*
X428218Y874425D01*
X427885Y874467D01*
X427552Y874383D01*
X427343Y874175D01*
X427177Y873883D01*
X427135Y873592D01*
X427177Y873300D01*
X427343Y872925D01*
X426260Y873050D01*
Y874175D01*
G01X414760Y860317D02*
X412260D01*
Y861358D01*
X412385Y861692D01*
X412552Y861900D01*
X412885Y861983D01*
X413218Y861900D01*
X413427Y861650D01*
X413552Y861358D01*
Y860317D01*
G01Y861358D02*
X414760Y861983D01*
G01X414468Y863542D02*
X414677Y863833D01*
X414760Y864167D01*
X414677Y864500D01*
X414427Y864792D01*
X414052Y865000D01*
X413677Y865083D01*
X413218D01*
X412843Y865000D01*
X412510Y864792D01*
X412343Y864542D01*
X412260Y864250D01*
X412343Y863917D01*
X412510Y863667D01*
X412760Y863500D01*
X413093Y863417D01*
X413385Y863500D01*
X413677Y863708D01*
X413843Y863958D01*
X413885Y864250D01*
X413802Y864583D01*
X413593Y864833D01*
X413218Y865083D01*
G01X412260Y867350D02*
X412343Y867017D01*
X412552Y866767D01*
X412802Y866600D01*
X413135Y866475D01*
X413510Y866433D01*
X413885Y866475D01*
X414218Y866600D01*
X414468Y866767D01*
X414677Y867017D01*
X414760Y867350D01*
X414677Y867683D01*
X414468Y867933D01*
X414218Y868100D01*
X413885Y868225D01*
X413510Y868267D01*
X413135Y868225D01*
X412802Y868100D01*
X412552Y867933D01*
X412343Y867683D01*
X412260Y867350D01*
G01X414468Y869742D02*
X414677Y870033D01*
X414760Y870367D01*
X414677Y870700D01*
X414427Y870992D01*
X414052Y871200D01*
X413677Y871283D01*
X413218D01*
X412843Y871200D01*
X412510Y870992D01*
X412343Y870742D01*
X412260Y870450D01*
X412343Y870117D01*
X412510Y869867D01*
X412760Y869700D01*
X413093Y869617D01*
X413385Y869700D01*
X413677Y869908D01*
X413843Y870158D01*
X413885Y870450D01*
X413802Y870783D01*
X413593Y871033D01*
X413218Y871283D01*
G01X413718Y872758D02*
X413427Y873050D01*
X413260Y873300D01*
X413177Y873633D01*
X413260Y873925D01*
X413427Y874133D01*
X413677Y874300D01*
X413968Y874342D01*
X414218Y874300D01*
X414468Y874133D01*
X414677Y873883D01*
X414760Y873592D01*
X414677Y873258D01*
X414427Y872967D01*
X414052Y872800D01*
X413635Y872758D01*
X413093Y872842D01*
X412802Y872967D01*
X412510Y873175D01*
X412302Y873467D01*
X412260Y873758D01*
X412343Y874050D01*
X412552Y874258D01*
G01X424760Y860317D02*
X422260D01*
Y861358D01*
X422385Y861692D01*
X422552Y861900D01*
X422885Y861983D01*
X423218Y861900D01*
X423427Y861650D01*
X423552Y861358D01*
Y860317D01*
G01Y861358D02*
X424760Y861983D01*
G01X424468Y863542D02*
X424677Y863833D01*
X424760Y864167D01*
X424677Y864500D01*
X424427Y864792D01*
X424052Y865000D01*
X423677Y865083D01*
X423218D01*
X422843Y865000D01*
X422510Y864792D01*
X422343Y864542D01*
X422260Y864250D01*
X422343Y863917D01*
X422510Y863667D01*
X422760Y863500D01*
X423093Y863417D01*
X423385Y863500D01*
X423677Y863708D01*
X423843Y863958D01*
X423885Y864250D01*
X423802Y864583D01*
X423593Y864833D01*
X423218Y865083D01*
G01X422260Y867350D02*
X422343Y867017D01*
X422552Y866767D01*
X422802Y866600D01*
X423135Y866475D01*
X423510Y866433D01*
X423885Y866475D01*
X424218Y866600D01*
X424468Y866767D01*
X424677Y867017D01*
X424760Y867350D01*
X424677Y867683D01*
X424468Y867933D01*
X424218Y868100D01*
X423885Y868225D01*
X423510Y868267D01*
X423135Y868225D01*
X422802Y868100D01*
X422552Y867933D01*
X422343Y867683D01*
X422260Y867350D01*
G01X424468Y869742D02*
X424677Y870033D01*
X424760Y870367D01*
X424677Y870700D01*
X424427Y870992D01*
X424052Y871200D01*
X423677Y871283D01*
X423218D01*
X422843Y871200D01*
X422510Y870992D01*
X422343Y870742D01*
X422260Y870450D01*
X422343Y870117D01*
X422510Y869867D01*
X422760Y869700D01*
X423093Y869617D01*
X423385Y869700D01*
X423677Y869908D01*
X423843Y870158D01*
X423885Y870450D01*
X423802Y870783D01*
X423593Y871033D01*
X423218Y871283D01*
G01X424760Y873550D02*
X424718Y873842D01*
X424593Y874175D01*
X424385Y874383D01*
X424093Y874467D01*
X423802Y874383D01*
X423552Y874133D01*
X423427Y873758D01*
Y873342D01*
X423343Y873092D01*
X423135Y872883D01*
X422843Y872800D01*
X422552Y872925D01*
X422343Y873217D01*
X422260Y873550D01*
X422343Y873883D01*
X422552Y874175D01*
X422843Y874300D01*
X423135Y874217D01*
X423343Y874008D01*
X423427Y873758D01*
Y873342D01*
X423552Y872967D01*
X423802Y872717D01*
X424093Y872633D01*
X424385Y872717D01*
X424593Y872925D01*
X424718Y873258D01*
X424760Y873550D01*
G01X417747Y849471D02*
Y851971D01*
X418788D01*
X419122Y851846D01*
X419330Y851679D01*
X419413Y851346D01*
X419330Y851013D01*
X419080Y850804D01*
X418788Y850679D01*
X417747D01*
G01X418788D02*
X419413Y849471D01*
G01X420972Y849763D02*
X421263Y849554D01*
X421597Y849471D01*
X421930Y849554D01*
X422222Y849804D01*
X422430Y850179D01*
X422513Y850554D01*
Y851013D01*
X422430Y851388D01*
X422222Y851721D01*
X421972Y851888D01*
X421680Y851971D01*
X421347Y851888D01*
X421097Y851721D01*
X420930Y851471D01*
X420847Y851138D01*
X420930Y850846D01*
X421138Y850554D01*
X421388Y850388D01*
X421680Y850346D01*
X422013Y850429D01*
X422263Y850638D01*
X422513Y851013D01*
G01X423863Y849846D02*
X424113Y849638D01*
X424405Y849513D01*
X424780Y849471D01*
X425155Y849554D01*
X425447Y849721D01*
X425655Y850013D01*
X425697Y850346D01*
X425613Y850679D01*
X425405Y850888D01*
X425113Y851054D01*
X424822Y851096D01*
X424530Y851054D01*
X424155Y850888D01*
X424280Y851971D01*
X425405D01*
G01X427880Y849471D02*
X428172Y849513D01*
X428505Y849638D01*
X428713Y849846D01*
X428797Y850138D01*
X428713Y850429D01*
X428463Y850679D01*
X428088Y850804D01*
X427672D01*
X427422Y850888D01*
X427213Y851096D01*
X427130Y851388D01*
X427255Y851679D01*
X427547Y851888D01*
X427880Y851971D01*
X428213Y851888D01*
X428505Y851679D01*
X428630Y851388D01*
X428547Y851096D01*
X428338Y850888D01*
X428088Y850804D01*
X427672D01*
X427297Y850679D01*
X427047Y850429D01*
X426963Y850138D01*
X427047Y849846D01*
X427255Y849638D01*
X427588Y849513D01*
X427880Y849471D01*
G01X431480D02*
Y851971D01*
X429938Y850179D01*
X432022D01*
G01X417419Y886324D02*
Y888824D01*
X418460D01*
X418794Y888699D01*
X419002Y888532D01*
X419085Y888199D01*
X419002Y887866D01*
X418752Y887657D01*
X418460Y887532D01*
X417419D01*
G01X418460D02*
X419085Y886324D01*
G01X420644Y886616D02*
X420935Y886407D01*
X421269Y886324D01*
X421602Y886407D01*
X421894Y886657D01*
X422102Y887032D01*
X422185Y887407D01*
Y887866D01*
X422102Y888241D01*
X421894Y888574D01*
X421644Y888741D01*
X421352Y888824D01*
X421019Y888741D01*
X420769Y888574D01*
X420602Y888324D01*
X420519Y887991D01*
X420602Y887699D01*
X420810Y887407D01*
X421060Y887241D01*
X421352Y887199D01*
X421685Y887282D01*
X421935Y887491D01*
X422185Y887866D01*
G01X423660Y887366D02*
X423952Y887657D01*
X424202Y887824D01*
X424535Y887907D01*
X424827Y887824D01*
X425035Y887657D01*
X425202Y887407D01*
X425244Y887116D01*
X425202Y886866D01*
X425035Y886616D01*
X424785Y886407D01*
X424494Y886324D01*
X424160Y886407D01*
X423869Y886657D01*
X423702Y887032D01*
X423660Y887449D01*
X423744Y887991D01*
X423869Y888282D01*
X424077Y888574D01*
X424369Y888782D01*
X424660Y888824D01*
X424952Y888741D01*
X425160Y888532D01*
G01X427552Y888824D02*
X427219Y888741D01*
X426969Y888532D01*
X426802Y888282D01*
X426677Y887949D01*
X426635Y887574D01*
X426677Y887199D01*
X426802Y886866D01*
X426969Y886616D01*
X427219Y886407D01*
X427552Y886324D01*
X427885Y886407D01*
X428135Y886616D01*
X428302Y886866D01*
X428427Y887199D01*
X428469Y887574D01*
X428427Y887949D01*
X428302Y888282D01*
X428135Y888532D01*
X427885Y888741D01*
X427552Y888824D01*
G01X429860Y888407D02*
X430110Y888657D01*
X430402Y888782D01*
X430735Y888824D01*
X431152Y888741D01*
X431444Y888532D01*
X431527Y888282D01*
X431485Y888032D01*
X431319Y887824D01*
X430485Y887407D01*
X430110Y887116D01*
X429860Y886699D01*
X429777Y886324D01*
X431527D01*
G01X441757Y1190737D02*
X441632Y1190487D01*
X441549Y1190195D01*
Y1189862D01*
X441674Y1189487D01*
X441882Y1189195D01*
X442132Y1188987D01*
X442549Y1188820D01*
X442924Y1188778D01*
X443299Y1188862D01*
X443549Y1188987D01*
X443799Y1189237D01*
X443966Y1189528D01*
X444049Y1189820D01*
Y1190112D01*
X443966Y1190403D01*
X443841Y1190653D01*
X443674Y1190862D01*
G01X443757Y1192212D02*
X443966Y1192503D01*
X444049Y1192837D01*
X443966Y1193170D01*
X443716Y1193462D01*
X443341Y1193670D01*
X442966Y1193753D01*
X442507D01*
X442132Y1193670D01*
X441799Y1193462D01*
X441632Y1193212D01*
X441549Y1192920D01*
X441632Y1192587D01*
X441799Y1192337D01*
X442049Y1192170D01*
X442382Y1192087D01*
X442674Y1192170D01*
X442966Y1192378D01*
X443132Y1192628D01*
X443174Y1192920D01*
X443091Y1193253D01*
X442882Y1193503D01*
X442507Y1193753D01*
G01X443549Y1195103D02*
X443841Y1195353D01*
X444007Y1195687D01*
X444049Y1196062D01*
X444007Y1196395D01*
X443799Y1196728D01*
X443549Y1196937D01*
X443299Y1196978D01*
X443007Y1196895D01*
X442799Y1196603D01*
X442716Y1196312D01*
Y1195937D01*
G01Y1196312D02*
X442591Y1196562D01*
X442382Y1196770D01*
X442132Y1196853D01*
X441882Y1196770D01*
X441674Y1196562D01*
X441549Y1196187D01*
X441591Y1195812D01*
X441757Y1195437D01*
G01X443674Y1198203D02*
X443882Y1198453D01*
X444007Y1198745D01*
X444049Y1199120D01*
X443966Y1199495D01*
X443799Y1199787D01*
X443507Y1199995D01*
X443174Y1200037D01*
X442841Y1199953D01*
X442632Y1199745D01*
X442466Y1199453D01*
X442424Y1199162D01*
X442466Y1198870D01*
X442632Y1198495D01*
X441549Y1198620D01*
Y1199745D01*
G01X443549Y1201303D02*
X443841Y1201553D01*
X444007Y1201887D01*
X444049Y1202262D01*
X444007Y1202595D01*
X443799Y1202928D01*
X443549Y1203137D01*
X443299Y1203178D01*
X443007Y1203095D01*
X442799Y1202803D01*
X442716Y1202512D01*
Y1202137D01*
G01Y1202512D02*
X442591Y1202762D01*
X442382Y1202970D01*
X442132Y1203053D01*
X441882Y1202970D01*
X441674Y1202762D01*
X441549Y1202387D01*
X441591Y1202012D01*
X441757Y1201637D01*
G01X408817Y1181427D02*
X408692Y1181177D01*
X408609Y1180885D01*
Y1180552D01*
X408734Y1180177D01*
X408942Y1179885D01*
X409192Y1179677D01*
X409609Y1179510D01*
X409984Y1179468D01*
X410359Y1179552D01*
X410609Y1179677D01*
X410859Y1179927D01*
X411026Y1180218D01*
X411109Y1180510D01*
Y1180802D01*
X411026Y1181093D01*
X410901Y1181343D01*
X410734Y1181552D01*
G01X410817Y1182902D02*
X411026Y1183193D01*
X411109Y1183527D01*
X411026Y1183860D01*
X410776Y1184152D01*
X410401Y1184360D01*
X410026Y1184443D01*
X409567D01*
X409192Y1184360D01*
X408859Y1184152D01*
X408692Y1183902D01*
X408609Y1183610D01*
X408692Y1183277D01*
X408859Y1183027D01*
X409109Y1182860D01*
X409442Y1182777D01*
X409734Y1182860D01*
X410026Y1183068D01*
X410192Y1183318D01*
X410234Y1183610D01*
X410151Y1183943D01*
X409942Y1184193D01*
X409567Y1184443D01*
G01X410734Y1185793D02*
X410942Y1186043D01*
X411067Y1186335D01*
X411109Y1186710D01*
X411026Y1187085D01*
X410859Y1187377D01*
X410567Y1187585D01*
X410234Y1187627D01*
X409901Y1187543D01*
X409692Y1187335D01*
X409526Y1187043D01*
X409484Y1186752D01*
X409526Y1186460D01*
X409692Y1186085D01*
X408609Y1186210D01*
Y1187335D01*
G01X411109Y1189810D02*
X408609D01*
X409109Y1189310D01*
G01X411109D02*
Y1190310D01*
G01X410734Y1191993D02*
X410942Y1192243D01*
X411067Y1192535D01*
X411109Y1192910D01*
X411026Y1193285D01*
X410859Y1193577D01*
X410567Y1193785D01*
X410234Y1193827D01*
X409901Y1193743D01*
X409692Y1193535D01*
X409526Y1193243D01*
X409484Y1192952D01*
X409526Y1192660D01*
X409692Y1192285D01*
X408609Y1192410D01*
Y1193535D01*
G01X466099Y1188447D02*
X463599D01*
Y1189488D01*
X463724Y1189822D01*
X463891Y1190030D01*
X464224Y1190113D01*
X464557Y1190030D01*
X464766Y1189780D01*
X464891Y1189488D01*
Y1188447D01*
G01Y1189488D02*
X466099Y1190113D01*
G01X465807Y1191672D02*
X466016Y1191963D01*
X466099Y1192297D01*
X466016Y1192630D01*
X465766Y1192922D01*
X465391Y1193130D01*
X465016Y1193213D01*
X464557D01*
X464182Y1193130D01*
X463849Y1192922D01*
X463682Y1192672D01*
X463599Y1192380D01*
X463682Y1192047D01*
X463849Y1191797D01*
X464099Y1191630D01*
X464432Y1191547D01*
X464724Y1191630D01*
X465016Y1191838D01*
X465182Y1192088D01*
X465224Y1192380D01*
X465141Y1192713D01*
X464932Y1192963D01*
X464557Y1193213D01*
G01X466099Y1195980D02*
X463599D01*
X465391Y1194438D01*
Y1196522D01*
G01X465724Y1197663D02*
X465932Y1197913D01*
X466057Y1198205D01*
X466099Y1198580D01*
X466016Y1198955D01*
X465849Y1199247D01*
X465557Y1199455D01*
X465224Y1199497D01*
X464891Y1199413D01*
X464682Y1199205D01*
X464516Y1198913D01*
X464474Y1198622D01*
X464516Y1198330D01*
X464682Y1197955D01*
X463599Y1198080D01*
Y1199205D01*
G01X466099Y1201680D02*
X463599D01*
X464099Y1201180D01*
G01X466099D02*
Y1202180D01*
G01X431000Y1217200D02*
X427000D01*
Y1209800D01*
G01X408587Y1195931D02*
Y1198431D01*
X409628D01*
X409962Y1198306D01*
X410170Y1198139D01*
X410253Y1197806D01*
X410170Y1197473D01*
X409920Y1197264D01*
X409628Y1197139D01*
X408587D01*
G01X409628D02*
X410253Y1195931D01*
G01X411812Y1196223D02*
X412103Y1196014D01*
X412437Y1195931D01*
X412770Y1196014D01*
X413062Y1196264D01*
X413270Y1196639D01*
X413353Y1197014D01*
Y1197473D01*
X413270Y1197848D01*
X413062Y1198181D01*
X412812Y1198348D01*
X412520Y1198431D01*
X412187Y1198348D01*
X411937Y1198181D01*
X411770Y1197931D01*
X411687Y1197598D01*
X411770Y1197306D01*
X411978Y1197014D01*
X412228Y1196848D01*
X412520Y1196806D01*
X412853Y1196889D01*
X413103Y1197098D01*
X413353Y1197473D01*
G01X415620Y1198431D02*
X415287Y1198348D01*
X415037Y1198139D01*
X414870Y1197889D01*
X414745Y1197556D01*
X414703Y1197181D01*
X414745Y1196806D01*
X414870Y1196473D01*
X415037Y1196223D01*
X415287Y1196014D01*
X415620Y1195931D01*
X415953Y1196014D01*
X416203Y1196223D01*
X416370Y1196473D01*
X416495Y1196806D01*
X416537Y1197181D01*
X416495Y1197556D01*
X416370Y1197889D01*
X416203Y1198139D01*
X415953Y1198348D01*
X415620Y1198431D01*
G01X418637Y1195931D02*
X418720Y1196473D01*
X418845Y1196931D01*
X419012Y1197348D01*
X419220Y1197806D01*
X419553Y1198431D01*
X417887D01*
G01X422320Y1195931D02*
Y1198431D01*
X420778Y1196639D01*
X422862D01*
G01X408587Y1199931D02*
Y1202431D01*
X409628D01*
X409962Y1202306D01*
X410170Y1202139D01*
X410253Y1201806D01*
X410170Y1201473D01*
X409920Y1201264D01*
X409628Y1201139D01*
X408587D01*
G01X409628D02*
X410253Y1199931D01*
G01X411812Y1200223D02*
X412103Y1200014D01*
X412437Y1199931D01*
X412770Y1200014D01*
X413062Y1200264D01*
X413270Y1200639D01*
X413353Y1201014D01*
Y1201473D01*
X413270Y1201848D01*
X413062Y1202181D01*
X412812Y1202348D01*
X412520Y1202431D01*
X412187Y1202348D01*
X411937Y1202181D01*
X411770Y1201931D01*
X411687Y1201598D01*
X411770Y1201306D01*
X411978Y1201014D01*
X412228Y1200848D01*
X412520Y1200806D01*
X412853Y1200889D01*
X413103Y1201098D01*
X413353Y1201473D01*
G01X415620Y1202431D02*
X415287Y1202348D01*
X415037Y1202139D01*
X414870Y1201889D01*
X414745Y1201556D01*
X414703Y1201181D01*
X414745Y1200806D01*
X414870Y1200473D01*
X415037Y1200223D01*
X415287Y1200014D01*
X415620Y1199931D01*
X415953Y1200014D01*
X416203Y1200223D01*
X416370Y1200473D01*
X416495Y1200806D01*
X416537Y1201181D01*
X416495Y1201556D01*
X416370Y1201889D01*
X416203Y1202139D01*
X415953Y1202348D01*
X415620Y1202431D01*
G01X418637Y1199931D02*
X418720Y1200473D01*
X418845Y1200931D01*
X419012Y1201348D01*
X419220Y1201806D01*
X419553Y1202431D01*
X417887D01*
G01X420903Y1200306D02*
X421153Y1200098D01*
X421445Y1199973D01*
X421820Y1199931D01*
X422195Y1200014D01*
X422487Y1200181D01*
X422695Y1200473D01*
X422737Y1200806D01*
X422653Y1201139D01*
X422445Y1201348D01*
X422153Y1201514D01*
X421862Y1201556D01*
X421570Y1201514D01*
X421195Y1201348D01*
X421320Y1202431D01*
X422445D01*
G01X406410Y1155017D02*
X403910D01*
Y1156058D01*
X404035Y1156392D01*
X404202Y1156600D01*
X404535Y1156683D01*
X404868Y1156600D01*
X405077Y1156350D01*
X405202Y1156058D01*
Y1155017D01*
G01Y1156058D02*
X406410Y1156683D01*
G01X406118Y1158242D02*
X406327Y1158533D01*
X406410Y1158867D01*
X406327Y1159200D01*
X406077Y1159492D01*
X405702Y1159700D01*
X405327Y1159783D01*
X404868D01*
X404493Y1159700D01*
X404160Y1159492D01*
X403993Y1159242D01*
X403910Y1158950D01*
X403993Y1158617D01*
X404160Y1158367D01*
X404410Y1158200D01*
X404743Y1158117D01*
X405035Y1158200D01*
X405327Y1158408D01*
X405493Y1158658D01*
X405535Y1158950D01*
X405452Y1159283D01*
X405243Y1159533D01*
X404868Y1159783D01*
G01X403910Y1162050D02*
X403993Y1161717D01*
X404202Y1161467D01*
X404452Y1161300D01*
X404785Y1161175D01*
X405160Y1161133D01*
X405535Y1161175D01*
X405868Y1161300D01*
X406118Y1161467D01*
X406327Y1161717D01*
X406410Y1162050D01*
X406327Y1162383D01*
X406118Y1162633D01*
X405868Y1162800D01*
X405535Y1162925D01*
X405160Y1162967D01*
X404785Y1162925D01*
X404452Y1162800D01*
X404202Y1162633D01*
X403993Y1162383D01*
X403910Y1162050D01*
G01X406410Y1165067D02*
X405868Y1165150D01*
X405410Y1165275D01*
X404993Y1165442D01*
X404535Y1165650D01*
X403910Y1165983D01*
Y1164317D01*
G01X406410Y1168167D02*
X405868Y1168250D01*
X405410Y1168375D01*
X404993Y1168542D01*
X404535Y1168750D01*
X403910Y1169083D01*
Y1167417D01*
G01X412767Y1185500D02*
Y1188000D01*
X413808D01*
X414142Y1187875D01*
X414350Y1187708D01*
X414433Y1187375D01*
X414350Y1187042D01*
X414100Y1186833D01*
X413808Y1186708D01*
X412767D01*
G01X413808D02*
X414433Y1185500D01*
G01X415992Y1185792D02*
X416283Y1185583D01*
X416617Y1185500D01*
X416950Y1185583D01*
X417242Y1185833D01*
X417450Y1186208D01*
X417533Y1186583D01*
Y1187042D01*
X417450Y1187417D01*
X417242Y1187750D01*
X416992Y1187917D01*
X416700Y1188000D01*
X416367Y1187917D01*
X416117Y1187750D01*
X415950Y1187500D01*
X415867Y1187167D01*
X415950Y1186875D01*
X416158Y1186583D01*
X416408Y1186417D01*
X416700Y1186375D01*
X417033Y1186458D01*
X417283Y1186667D01*
X417533Y1187042D01*
G01X418883Y1185875D02*
X419133Y1185667D01*
X419425Y1185542D01*
X419800Y1185500D01*
X420175Y1185583D01*
X420467Y1185750D01*
X420675Y1186042D01*
X420717Y1186375D01*
X420633Y1186708D01*
X420425Y1186917D01*
X420133Y1187083D01*
X419842Y1187125D01*
X419550Y1187083D01*
X419175Y1186917D01*
X419300Y1188000D01*
X420425D01*
G01X422900Y1185500D02*
Y1188000D01*
X422400Y1187500D01*
G01Y1185500D02*
X423400D01*
G01X425208Y1187583D02*
X425458Y1187833D01*
X425750Y1187958D01*
X426083Y1188000D01*
X426500Y1187917D01*
X426792Y1187708D01*
X426875Y1187458D01*
X426833Y1187208D01*
X426667Y1187000D01*
X425833Y1186583D01*
X425458Y1186292D01*
X425208Y1185875D01*
X425125Y1185500D01*
X426875D01*
G01X466249Y1211677D02*
X463749D01*
Y1212718D01*
X463874Y1213052D01*
X464041Y1213260D01*
X464374Y1213343D01*
X464707Y1213260D01*
X464916Y1213010D01*
X465041Y1212718D01*
Y1211677D01*
G01Y1212718D02*
X466249Y1213343D01*
G01X465957Y1214902D02*
X466166Y1215193D01*
X466249Y1215527D01*
X466166Y1215860D01*
X465916Y1216152D01*
X465541Y1216360D01*
X465166Y1216443D01*
X464707D01*
X464332Y1216360D01*
X463999Y1216152D01*
X463832Y1215902D01*
X463749Y1215610D01*
X463832Y1215277D01*
X463999Y1215027D01*
X464249Y1214860D01*
X464582Y1214777D01*
X464874Y1214860D01*
X465166Y1215068D01*
X465332Y1215318D01*
X465374Y1215610D01*
X465291Y1215943D01*
X465082Y1216193D01*
X464707Y1216443D01*
G01X466249Y1219210D02*
X463749D01*
X465541Y1217668D01*
Y1219752D01*
G01X465957Y1221102D02*
X466166Y1221393D01*
X466249Y1221727D01*
X466166Y1222060D01*
X465916Y1222352D01*
X465541Y1222560D01*
X465166Y1222643D01*
X464707D01*
X464332Y1222560D01*
X463999Y1222352D01*
X463832Y1222102D01*
X463749Y1221810D01*
X463832Y1221477D01*
X463999Y1221227D01*
X464249Y1221060D01*
X464582Y1220977D01*
X464874Y1221060D01*
X465166Y1221268D01*
X465332Y1221518D01*
X465374Y1221810D01*
X465291Y1222143D01*
X465082Y1222393D01*
X464707Y1222643D01*
G01X464166Y1224118D02*
X463916Y1224368D01*
X463791Y1224660D01*
X463749Y1224993D01*
X463832Y1225410D01*
X464041Y1225702D01*
X464291Y1225785D01*
X464541Y1225743D01*
X464749Y1225577D01*
X465166Y1224743D01*
X465457Y1224368D01*
X465874Y1224118D01*
X466249Y1224035D01*
Y1225785D01*
G01X447147Y1193031D02*
Y1195531D01*
X448188D01*
X448522Y1195406D01*
X448730Y1195239D01*
X448813Y1194906D01*
X448730Y1194573D01*
X448480Y1194364D01*
X448188Y1194239D01*
X447147D01*
G01X448188D02*
X448813Y1193031D01*
G01X450372Y1193323D02*
X450663Y1193114D01*
X450997Y1193031D01*
X451330Y1193114D01*
X451622Y1193364D01*
X451830Y1193739D01*
X451913Y1194114D01*
Y1194573D01*
X451830Y1194948D01*
X451622Y1195281D01*
X451372Y1195448D01*
X451080Y1195531D01*
X450747Y1195448D01*
X450497Y1195281D01*
X450330Y1195031D01*
X450247Y1194698D01*
X450330Y1194406D01*
X450538Y1194114D01*
X450788Y1193948D01*
X451080Y1193906D01*
X451413Y1193989D01*
X451663Y1194198D01*
X451913Y1194573D01*
G01X454680Y1193031D02*
Y1195531D01*
X453138Y1193739D01*
X455222D01*
G01X456363Y1193406D02*
X456613Y1193198D01*
X456905Y1193073D01*
X457280Y1193031D01*
X457655Y1193114D01*
X457947Y1193281D01*
X458155Y1193573D01*
X458197Y1193906D01*
X458113Y1194239D01*
X457905Y1194448D01*
X457613Y1194614D01*
X457322Y1194656D01*
X457030Y1194614D01*
X456655Y1194448D01*
X456780Y1195531D01*
X457905D01*
G01X459588Y1195114D02*
X459838Y1195364D01*
X460130Y1195489D01*
X460463Y1195531D01*
X460880Y1195448D01*
X461172Y1195239D01*
X461255Y1194989D01*
X461213Y1194739D01*
X461047Y1194531D01*
X460213Y1194114D01*
X459838Y1193823D01*
X459588Y1193406D01*
X459505Y1193031D01*
X461255D01*
G01X426700Y1210000D02*
Y1214000D01*
X419300D01*
G01X418817Y1265892D02*
X418567Y1266017D01*
X418275Y1266100D01*
X417942D01*
X417567Y1265975D01*
X417275Y1265767D01*
X417067Y1265517D01*
X416900Y1265100D01*
X416858Y1264725D01*
X416942Y1264350D01*
X417067Y1264100D01*
X417317Y1263850D01*
X417608Y1263683D01*
X417900Y1263600D01*
X418192D01*
X418483Y1263683D01*
X418733Y1263808D01*
X418942Y1263975D01*
G01X420292Y1263892D02*
X420583Y1263683D01*
X420917Y1263600D01*
X421250Y1263683D01*
X421542Y1263933D01*
X421750Y1264308D01*
X421833Y1264683D01*
Y1265142D01*
X421750Y1265517D01*
X421542Y1265850D01*
X421292Y1266017D01*
X421000Y1266100D01*
X420667Y1266017D01*
X420417Y1265850D01*
X420250Y1265600D01*
X420167Y1265267D01*
X420250Y1264975D01*
X420458Y1264683D01*
X420708Y1264517D01*
X421000Y1264475D01*
X421333Y1264558D01*
X421583Y1264767D01*
X421833Y1265142D01*
G01X423183Y1264100D02*
X423433Y1263808D01*
X423767Y1263642D01*
X424142Y1263600D01*
X424475Y1263642D01*
X424808Y1263850D01*
X425017Y1264100D01*
X425058Y1264350D01*
X424975Y1264642D01*
X424683Y1264850D01*
X424392Y1264933D01*
X424017D01*
G01X424392D02*
X424642Y1265058D01*
X424850Y1265267D01*
X424933Y1265517D01*
X424850Y1265767D01*
X424642Y1265975D01*
X424267Y1266100D01*
X423892Y1266058D01*
X423517Y1265892D01*
G01X426283Y1263975D02*
X426533Y1263767D01*
X426825Y1263642D01*
X427200Y1263600D01*
X427575Y1263683D01*
X427867Y1263850D01*
X428075Y1264142D01*
X428117Y1264475D01*
X428033Y1264808D01*
X427825Y1265017D01*
X427533Y1265183D01*
X427242Y1265225D01*
X426950Y1265183D01*
X426575Y1265017D01*
X426700Y1266100D01*
X427825D01*
G01X429592Y1263892D02*
X429883Y1263683D01*
X430217Y1263600D01*
X430550Y1263683D01*
X430842Y1263933D01*
X431050Y1264308D01*
X431133Y1264683D01*
Y1265142D01*
X431050Y1265517D01*
X430842Y1265850D01*
X430592Y1266017D01*
X430300Y1266100D01*
X429967Y1266017D01*
X429717Y1265850D01*
X429550Y1265600D01*
X429467Y1265267D01*
X429550Y1264975D01*
X429758Y1264683D01*
X430008Y1264517D01*
X430300Y1264475D01*
X430633Y1264558D01*
X430883Y1264767D01*
X431133Y1265142D01*
G01X441907Y1213967D02*
X441782Y1213717D01*
X441699Y1213425D01*
Y1213092D01*
X441824Y1212717D01*
X442032Y1212425D01*
X442282Y1212217D01*
X442699Y1212050D01*
X443074Y1212008D01*
X443449Y1212092D01*
X443699Y1212217D01*
X443949Y1212467D01*
X444116Y1212758D01*
X444199Y1213050D01*
Y1213342D01*
X444116Y1213633D01*
X443991Y1213883D01*
X443824Y1214092D01*
G01X443907Y1215442D02*
X444116Y1215733D01*
X444199Y1216067D01*
X444116Y1216400D01*
X443866Y1216692D01*
X443491Y1216900D01*
X443116Y1216983D01*
X442657D01*
X442282Y1216900D01*
X441949Y1216692D01*
X441782Y1216442D01*
X441699Y1216150D01*
X441782Y1215817D01*
X441949Y1215567D01*
X442199Y1215400D01*
X442532Y1215317D01*
X442824Y1215400D01*
X443116Y1215608D01*
X443282Y1215858D01*
X443324Y1216150D01*
X443241Y1216483D01*
X443032Y1216733D01*
X442657Y1216983D01*
G01X443699Y1218333D02*
X443991Y1218583D01*
X444157Y1218917D01*
X444199Y1219292D01*
X444157Y1219625D01*
X443949Y1219958D01*
X443699Y1220167D01*
X443449Y1220208D01*
X443157Y1220125D01*
X442949Y1219833D01*
X442866Y1219542D01*
Y1219167D01*
G01Y1219542D02*
X442741Y1219792D01*
X442532Y1220000D01*
X442282Y1220083D01*
X442032Y1220000D01*
X441824Y1219792D01*
X441699Y1219417D01*
X441741Y1219042D01*
X441907Y1218667D01*
G01X443157Y1221558D02*
X442866Y1221850D01*
X442699Y1222100D01*
X442616Y1222433D01*
X442699Y1222725D01*
X442866Y1222933D01*
X443116Y1223100D01*
X443407Y1223142D01*
X443657Y1223100D01*
X443907Y1222933D01*
X444116Y1222683D01*
X444199Y1222392D01*
X444116Y1222058D01*
X443866Y1221767D01*
X443491Y1221600D01*
X443074Y1221558D01*
X442532Y1221642D01*
X442241Y1221767D01*
X441949Y1221975D01*
X441741Y1222267D01*
X441699Y1222558D01*
X441782Y1222850D01*
X441991Y1223058D01*
G01X443824Y1224533D02*
X444032Y1224783D01*
X444157Y1225075D01*
X444199Y1225450D01*
X444116Y1225825D01*
X443949Y1226117D01*
X443657Y1226325D01*
X443324Y1226367D01*
X442991Y1226283D01*
X442782Y1226075D01*
X442616Y1225783D01*
X442574Y1225492D01*
X442616Y1225200D01*
X442782Y1224825D01*
X441699Y1224950D01*
Y1226075D01*
G01X421808Y1233347D02*
X421683Y1233097D01*
X421600Y1232805D01*
Y1232472D01*
X421725Y1232097D01*
X421933Y1231805D01*
X422183Y1231597D01*
X422600Y1231430D01*
X422975Y1231388D01*
X423350Y1231472D01*
X423600Y1231597D01*
X423850Y1231847D01*
X424017Y1232138D01*
X424100Y1232430D01*
Y1232722D01*
X424017Y1233013D01*
X423892Y1233263D01*
X423725Y1233472D01*
G01X424100Y1235530D02*
X424058Y1235822D01*
X423933Y1236155D01*
X423725Y1236363D01*
X423433Y1236447D01*
X423142Y1236363D01*
X422892Y1236113D01*
X422767Y1235738D01*
Y1235322D01*
X422683Y1235072D01*
X422475Y1234863D01*
X422183Y1234780D01*
X421892Y1234905D01*
X421683Y1235197D01*
X421600Y1235530D01*
X421683Y1235863D01*
X421892Y1236155D01*
X422183Y1236280D01*
X422475Y1236197D01*
X422683Y1235988D01*
X422767Y1235738D01*
Y1235322D01*
X422892Y1234947D01*
X423142Y1234697D01*
X423433Y1234613D01*
X423725Y1234697D01*
X423933Y1234905D01*
X424058Y1235238D01*
X424100Y1235530D01*
G01Y1238630D02*
X424058Y1238922D01*
X423933Y1239255D01*
X423725Y1239463D01*
X423433Y1239547D01*
X423142Y1239463D01*
X422892Y1239213D01*
X422767Y1238838D01*
Y1238422D01*
X422683Y1238172D01*
X422475Y1237963D01*
X422183Y1237880D01*
X421892Y1238005D01*
X421683Y1238297D01*
X421600Y1238630D01*
X421683Y1238963D01*
X421892Y1239255D01*
X422183Y1239380D01*
X422475Y1239297D01*
X422683Y1239088D01*
X422767Y1238838D01*
Y1238422D01*
X422892Y1238047D01*
X423142Y1237797D01*
X423433Y1237713D01*
X423725Y1237797D01*
X423933Y1238005D01*
X424058Y1238338D01*
X424100Y1238630D01*
G01X423725Y1240813D02*
X423933Y1241063D01*
X424058Y1241355D01*
X424100Y1241730D01*
X424017Y1242105D01*
X423850Y1242397D01*
X423558Y1242605D01*
X423225Y1242647D01*
X422892Y1242563D01*
X422683Y1242355D01*
X422517Y1242063D01*
X422475Y1241772D01*
X422517Y1241480D01*
X422683Y1241105D01*
X421600Y1241230D01*
Y1242355D01*
G01X422017Y1244038D02*
X421767Y1244288D01*
X421642Y1244580D01*
X421600Y1244913D01*
X421683Y1245330D01*
X421892Y1245622D01*
X422142Y1245705D01*
X422392Y1245663D01*
X422600Y1245497D01*
X423017Y1244663D01*
X423308Y1244288D01*
X423725Y1244038D01*
X424100Y1243955D01*
Y1245705D01*
G01X417067Y1271600D02*
Y1274100D01*
X418108D01*
X418442Y1273975D01*
X418650Y1273808D01*
X418733Y1273475D01*
X418650Y1273142D01*
X418400Y1272933D01*
X418108Y1272808D01*
X417067D01*
G01X418108D02*
X418733Y1271600D01*
G01X420292Y1271892D02*
X420583Y1271683D01*
X420917Y1271600D01*
X421250Y1271683D01*
X421542Y1271933D01*
X421750Y1272308D01*
X421833Y1272683D01*
Y1273142D01*
X421750Y1273517D01*
X421542Y1273850D01*
X421292Y1274017D01*
X421000Y1274100D01*
X420667Y1274017D01*
X420417Y1273850D01*
X420250Y1273600D01*
X420167Y1273267D01*
X420250Y1272975D01*
X420458Y1272683D01*
X420708Y1272517D01*
X421000Y1272475D01*
X421333Y1272558D01*
X421583Y1272767D01*
X421833Y1273142D01*
G01X424600Y1271600D02*
Y1274100D01*
X423058Y1272308D01*
X425142D01*
G01X427117Y1271600D02*
X427200Y1272142D01*
X427325Y1272600D01*
X427492Y1273017D01*
X427700Y1273475D01*
X428033Y1274100D01*
X426367D01*
G01X429508Y1273683D02*
X429758Y1273933D01*
X430050Y1274058D01*
X430383Y1274100D01*
X430800Y1274017D01*
X431092Y1273808D01*
X431175Y1273558D01*
X431133Y1273308D01*
X430967Y1273100D01*
X430133Y1272683D01*
X429758Y1272392D01*
X429508Y1271975D01*
X429425Y1271600D01*
X431175D01*
G01X426657Y1233071D02*
Y1235571D01*
X427698D01*
X428032Y1235446D01*
X428240Y1235279D01*
X428323Y1234946D01*
X428240Y1234613D01*
X427990Y1234404D01*
X427698Y1234279D01*
X426657D01*
G01X427698D02*
X428323Y1233071D01*
G01X429882Y1233363D02*
X430173Y1233154D01*
X430507Y1233071D01*
X430840Y1233154D01*
X431132Y1233404D01*
X431340Y1233779D01*
X431423Y1234154D01*
Y1234613D01*
X431340Y1234988D01*
X431132Y1235321D01*
X430882Y1235488D01*
X430590Y1235571D01*
X430257Y1235488D01*
X430007Y1235321D01*
X429840Y1235071D01*
X429757Y1234738D01*
X429840Y1234446D01*
X430048Y1234154D01*
X430298Y1233988D01*
X430590Y1233946D01*
X430923Y1234029D01*
X431173Y1234238D01*
X431423Y1234613D01*
G01X433690Y1235571D02*
X433357Y1235488D01*
X433107Y1235279D01*
X432940Y1235029D01*
X432815Y1234696D01*
X432773Y1234321D01*
X432815Y1233946D01*
X432940Y1233613D01*
X433107Y1233363D01*
X433357Y1233154D01*
X433690Y1233071D01*
X434023Y1233154D01*
X434273Y1233363D01*
X434440Y1233613D01*
X434565Y1233946D01*
X434607Y1234321D01*
X434565Y1234696D01*
X434440Y1235029D01*
X434273Y1235279D01*
X434023Y1235488D01*
X433690Y1235571D01*
G01X436707Y1233071D02*
X436790Y1233613D01*
X436915Y1234071D01*
X437082Y1234488D01*
X437290Y1234946D01*
X437623Y1235571D01*
X435957D01*
G01X439890Y1233071D02*
Y1235571D01*
X439390Y1235071D01*
G01Y1233071D02*
X440390D01*
G01X426657Y1237071D02*
Y1239571D01*
X427698D01*
X428032Y1239446D01*
X428240Y1239279D01*
X428323Y1238946D01*
X428240Y1238613D01*
X427990Y1238404D01*
X427698Y1238279D01*
X426657D01*
G01X427698D02*
X428323Y1237071D01*
G01X429882Y1237363D02*
X430173Y1237154D01*
X430507Y1237071D01*
X430840Y1237154D01*
X431132Y1237404D01*
X431340Y1237779D01*
X431423Y1238154D01*
Y1238613D01*
X431340Y1238988D01*
X431132Y1239321D01*
X430882Y1239488D01*
X430590Y1239571D01*
X430257Y1239488D01*
X430007Y1239321D01*
X429840Y1239071D01*
X429757Y1238738D01*
X429840Y1238446D01*
X430048Y1238154D01*
X430298Y1237988D01*
X430590Y1237946D01*
X430923Y1238029D01*
X431173Y1238238D01*
X431423Y1238613D01*
G01X433690Y1239571D02*
X433357Y1239488D01*
X433107Y1239279D01*
X432940Y1239029D01*
X432815Y1238696D01*
X432773Y1238321D01*
X432815Y1237946D01*
X432940Y1237613D01*
X433107Y1237363D01*
X433357Y1237154D01*
X433690Y1237071D01*
X434023Y1237154D01*
X434273Y1237363D01*
X434440Y1237613D01*
X434565Y1237946D01*
X434607Y1238321D01*
X434565Y1238696D01*
X434440Y1239029D01*
X434273Y1239279D01*
X434023Y1239488D01*
X433690Y1239571D01*
G01X436707Y1237071D02*
X436790Y1237613D01*
X436915Y1238071D01*
X437082Y1238488D01*
X437290Y1238946D01*
X437623Y1239571D01*
X435957D01*
G01X438973Y1237571D02*
X439223Y1237279D01*
X439557Y1237113D01*
X439932Y1237071D01*
X440265Y1237113D01*
X440598Y1237321D01*
X440807Y1237571D01*
X440848Y1237821D01*
X440765Y1238113D01*
X440473Y1238321D01*
X440182Y1238404D01*
X439807D01*
G01X440182D02*
X440432Y1238529D01*
X440640Y1238738D01*
X440723Y1238988D01*
X440640Y1239238D01*
X440432Y1239446D01*
X440057Y1239571D01*
X439682Y1239529D01*
X439307Y1239363D01*
G01X431000Y1225200D02*
X427000D01*
Y1217800D01*
G01X427227Y1241190D02*
Y1243690D01*
X428268D01*
X428602Y1243565D01*
X428810Y1243398D01*
X428893Y1243065D01*
X428810Y1242732D01*
X428560Y1242523D01*
X428268Y1242398D01*
X427227D01*
G01X428268D02*
X428893Y1241190D01*
G01X430452Y1241482D02*
X430743Y1241273D01*
X431077Y1241190D01*
X431410Y1241273D01*
X431702Y1241523D01*
X431910Y1241898D01*
X431993Y1242273D01*
Y1242732D01*
X431910Y1243107D01*
X431702Y1243440D01*
X431452Y1243607D01*
X431160Y1243690D01*
X430827Y1243607D01*
X430577Y1243440D01*
X430410Y1243190D01*
X430327Y1242857D01*
X430410Y1242565D01*
X430618Y1242273D01*
X430868Y1242107D01*
X431160Y1242065D01*
X431493Y1242148D01*
X431743Y1242357D01*
X431993Y1242732D01*
G01X433343Y1241565D02*
X433593Y1241357D01*
X433885Y1241232D01*
X434260Y1241190D01*
X434635Y1241273D01*
X434927Y1241440D01*
X435135Y1241732D01*
X435177Y1242065D01*
X435093Y1242398D01*
X434885Y1242607D01*
X434593Y1242773D01*
X434302Y1242815D01*
X434010Y1242773D01*
X433635Y1242607D01*
X433760Y1243690D01*
X434885D01*
G01X437360Y1241190D02*
X437652Y1241232D01*
X437985Y1241357D01*
X438193Y1241565D01*
X438277Y1241857D01*
X438193Y1242148D01*
X437943Y1242398D01*
X437568Y1242523D01*
X437152D01*
X436902Y1242607D01*
X436693Y1242815D01*
X436610Y1243107D01*
X436735Y1243398D01*
X437027Y1243607D01*
X437360Y1243690D01*
X437693Y1243607D01*
X437985Y1243398D01*
X438110Y1243107D01*
X438027Y1242815D01*
X437818Y1242607D01*
X437568Y1242523D01*
X437152D01*
X436777Y1242398D01*
X436527Y1242148D01*
X436443Y1241857D01*
X436527Y1241565D01*
X436735Y1241357D01*
X437068Y1241232D01*
X437360Y1241190D01*
G01X439543Y1241690D02*
X439793Y1241398D01*
X440127Y1241232D01*
X440502Y1241190D01*
X440835Y1241232D01*
X441168Y1241440D01*
X441377Y1241690D01*
X441418Y1241940D01*
X441335Y1242232D01*
X441043Y1242440D01*
X440752Y1242523D01*
X440377D01*
G01X440752D02*
X441002Y1242648D01*
X441210Y1242857D01*
X441293Y1243107D01*
X441210Y1243357D01*
X441002Y1243565D01*
X440627Y1243690D01*
X440252Y1243648D01*
X439877Y1243482D01*
G01X411200Y1229000D02*
X406000D01*
G01X411200Y1236000D02*
X403400D01*
G01X411200Y1229000D02*
Y1236000D01*
G01X446467Y1215667D02*
Y1218167D01*
X447508D01*
X447842Y1218042D01*
X448050Y1217875D01*
X448133Y1217542D01*
X448050Y1217209D01*
X447800Y1217000D01*
X447508Y1216875D01*
X446467D01*
G01X447508D02*
X448133Y1215667D01*
G01X449692Y1215959D02*
X449983Y1215750D01*
X450317Y1215667D01*
X450650Y1215750D01*
X450942Y1216000D01*
X451150Y1216375D01*
X451233Y1216750D01*
Y1217209D01*
X451150Y1217584D01*
X450942Y1217917D01*
X450692Y1218084D01*
X450400Y1218167D01*
X450067Y1218084D01*
X449817Y1217917D01*
X449650Y1217667D01*
X449567Y1217334D01*
X449650Y1217042D01*
X449858Y1216750D01*
X450108Y1216584D01*
X450400Y1216542D01*
X450733Y1216625D01*
X450983Y1216834D01*
X451233Y1217209D01*
G01X454000Y1215667D02*
Y1218167D01*
X452458Y1216375D01*
X454542D01*
G01X455892Y1215959D02*
X456183Y1215750D01*
X456517Y1215667D01*
X456850Y1215750D01*
X457142Y1216000D01*
X457350Y1216375D01*
X457433Y1216750D01*
Y1217209D01*
X457350Y1217584D01*
X457142Y1217917D01*
X456892Y1218084D01*
X456600Y1218167D01*
X456267Y1218084D01*
X456017Y1217917D01*
X455850Y1217667D01*
X455767Y1217334D01*
X455850Y1217042D01*
X456058Y1216750D01*
X456308Y1216584D01*
X456600Y1216542D01*
X456933Y1216625D01*
X457183Y1216834D01*
X457433Y1217209D01*
G01X460200Y1215667D02*
Y1218167D01*
X458658Y1216375D01*
X460742D01*
G01X426700Y1218000D02*
Y1222000D01*
X419300D01*
G01X417067Y1267600D02*
Y1270100D01*
X418108D01*
X418442Y1269975D01*
X418650Y1269808D01*
X418733Y1269475D01*
X418650Y1269142D01*
X418400Y1268933D01*
X418108Y1268808D01*
X417067D01*
G01X418108D02*
X418733Y1267600D01*
G01X420292Y1267892D02*
X420583Y1267683D01*
X420917Y1267600D01*
X421250Y1267683D01*
X421542Y1267933D01*
X421750Y1268308D01*
X421833Y1268683D01*
Y1269142D01*
X421750Y1269517D01*
X421542Y1269850D01*
X421292Y1270017D01*
X421000Y1270100D01*
X420667Y1270017D01*
X420417Y1269850D01*
X420250Y1269600D01*
X420167Y1269267D01*
X420250Y1268975D01*
X420458Y1268683D01*
X420708Y1268517D01*
X421000Y1268475D01*
X421333Y1268558D01*
X421583Y1268767D01*
X421833Y1269142D01*
G01X423308Y1268642D02*
X423600Y1268933D01*
X423850Y1269100D01*
X424183Y1269183D01*
X424475Y1269100D01*
X424683Y1268933D01*
X424850Y1268683D01*
X424892Y1268392D01*
X424850Y1268142D01*
X424683Y1267892D01*
X424433Y1267683D01*
X424142Y1267600D01*
X423808Y1267683D01*
X423517Y1267933D01*
X423350Y1268308D01*
X423308Y1268725D01*
X423392Y1269267D01*
X423517Y1269558D01*
X423725Y1269850D01*
X424017Y1270058D01*
X424308Y1270100D01*
X424600Y1270017D01*
X424808Y1269808D01*
G01X427200Y1270100D02*
X426867Y1270017D01*
X426617Y1269808D01*
X426450Y1269558D01*
X426325Y1269225D01*
X426283Y1268850D01*
X426325Y1268475D01*
X426450Y1268142D01*
X426617Y1267892D01*
X426867Y1267683D01*
X427200Y1267600D01*
X427533Y1267683D01*
X427783Y1267892D01*
X427950Y1268142D01*
X428075Y1268475D01*
X428117Y1268850D01*
X428075Y1269225D01*
X427950Y1269558D01*
X427783Y1269808D01*
X427533Y1270017D01*
X427200Y1270100D01*
G01X430300D02*
X429967Y1270017D01*
X429717Y1269808D01*
X429550Y1269558D01*
X429425Y1269225D01*
X429383Y1268850D01*
X429425Y1268475D01*
X429550Y1268142D01*
X429717Y1267892D01*
X429967Y1267683D01*
X430300Y1267600D01*
X430633Y1267683D01*
X430883Y1267892D01*
X431050Y1268142D01*
X431175Y1268475D01*
X431217Y1268850D01*
X431175Y1269225D01*
X431050Y1269558D01*
X430883Y1269808D01*
X430633Y1270017D01*
X430300Y1270100D01*
G01X420114Y1676100D02*
X419989Y1675850D01*
X419906Y1675558D01*
Y1675225D01*
X420031Y1674850D01*
X420239Y1674558D01*
X420489Y1674350D01*
X420906Y1674183D01*
X421281Y1674141D01*
X421656Y1674225D01*
X421906Y1674350D01*
X422156Y1674600D01*
X422323Y1674891D01*
X422406Y1675183D01*
Y1675475D01*
X422323Y1675766D01*
X422198Y1676016D01*
X422031Y1676225D01*
G01X422406Y1678283D02*
X419906D01*
X420406Y1677783D01*
G01X422406D02*
Y1678783D01*
G01Y1681383D02*
X419906D01*
X420406Y1680883D01*
G01X422406D02*
Y1681883D01*
G01X419906Y1684483D02*
X419989Y1684150D01*
X420198Y1683900D01*
X420448Y1683733D01*
X420781Y1683608D01*
X421156Y1683566D01*
X421531Y1683608D01*
X421864Y1683733D01*
X422114Y1683900D01*
X422323Y1684150D01*
X422406Y1684483D01*
X422323Y1684816D01*
X422114Y1685066D01*
X421864Y1685233D01*
X421531Y1685358D01*
X421156Y1685400D01*
X420781Y1685358D01*
X420448Y1685233D01*
X420198Y1685066D01*
X419989Y1684816D01*
X419906Y1684483D01*
G01X407008Y1682017D02*
X406883Y1681767D01*
X406800Y1681475D01*
Y1681142D01*
X406925Y1680767D01*
X407133Y1680475D01*
X407383Y1680267D01*
X407800Y1680100D01*
X408175Y1680058D01*
X408550Y1680142D01*
X408800Y1680267D01*
X409050Y1680517D01*
X409217Y1680808D01*
X409300Y1681100D01*
Y1681392D01*
X409217Y1681683D01*
X409092Y1681933D01*
X408925Y1682142D01*
G01X409008Y1683492D02*
X409217Y1683783D01*
X409300Y1684117D01*
X409217Y1684450D01*
X408967Y1684742D01*
X408592Y1684950D01*
X408217Y1685033D01*
X407758D01*
X407383Y1684950D01*
X407050Y1684742D01*
X406883Y1684492D01*
X406800Y1684200D01*
X406883Y1683867D01*
X407050Y1683617D01*
X407300Y1683450D01*
X407633Y1683367D01*
X407925Y1683450D01*
X408217Y1683658D01*
X408383Y1683908D01*
X408425Y1684200D01*
X408342Y1684533D01*
X408133Y1684783D01*
X407758Y1685033D01*
G01X409300Y1687800D02*
X406800D01*
X408592Y1686258D01*
Y1688342D01*
G01X409300Y1690400D02*
X406800D01*
X407300Y1689900D01*
G01X409300D02*
Y1690900D01*
G01X409008Y1692792D02*
X409217Y1693083D01*
X409300Y1693417D01*
X409217Y1693750D01*
X408967Y1694042D01*
X408592Y1694250D01*
X408217Y1694333D01*
X407758D01*
X407383Y1694250D01*
X407050Y1694042D01*
X406883Y1693792D01*
X406800Y1693500D01*
X406883Y1693167D01*
X407050Y1692917D01*
X407300Y1692750D01*
X407633Y1692667D01*
X407925Y1692750D01*
X408217Y1692958D01*
X408383Y1693208D01*
X408425Y1693500D01*
X408342Y1693833D01*
X408133Y1694083D01*
X407758Y1694333D01*
G01X420114Y1690330D02*
X419989Y1690080D01*
X419906Y1689788D01*
Y1689455D01*
X420031Y1689080D01*
X420239Y1688788D01*
X420489Y1688580D01*
X420906Y1688413D01*
X421281Y1688371D01*
X421656Y1688455D01*
X421906Y1688580D01*
X422156Y1688830D01*
X422323Y1689121D01*
X422406Y1689413D01*
Y1689705D01*
X422323Y1689996D01*
X422198Y1690246D01*
X422031Y1690455D01*
G01X422406Y1692513D02*
X419906D01*
X420406Y1692013D01*
G01X422406D02*
Y1693013D01*
G01Y1695613D02*
X419906D01*
X420406Y1695113D01*
G01X422406D02*
Y1696113D01*
G01Y1698713D02*
X419906D01*
X420406Y1698213D01*
G01X422406D02*
Y1699213D01*
G01X443456Y1674270D02*
X440956D01*
Y1675311D01*
X441081Y1675645D01*
X441248Y1675853D01*
X441581Y1675936D01*
X441914Y1675853D01*
X442123Y1675603D01*
X442248Y1675311D01*
Y1674270D01*
G01Y1675311D02*
X443456Y1675936D01*
G01Y1678203D02*
X440956D01*
X441456Y1677703D01*
G01X443456D02*
Y1678703D01*
G01Y1681303D02*
X440956D01*
X441456Y1680803D01*
G01X443456D02*
Y1681803D01*
G01Y1684403D02*
X443414Y1684695D01*
X443289Y1685028D01*
X443081Y1685236D01*
X442789Y1685320D01*
X442498Y1685236D01*
X442248Y1684986D01*
X442123Y1684611D01*
Y1684195D01*
X442039Y1683945D01*
X441831Y1683736D01*
X441539Y1683653D01*
X441248Y1683778D01*
X441039Y1684070D01*
X440956Y1684403D01*
X441039Y1684736D01*
X441248Y1685028D01*
X441539Y1685153D01*
X441831Y1685070D01*
X442039Y1684861D01*
X442123Y1684611D01*
Y1684195D01*
X442248Y1683820D01*
X442498Y1683570D01*
X442789Y1683486D01*
X443081Y1683570D01*
X443289Y1683778D01*
X443414Y1684111D01*
X443456Y1684403D01*
G01X431000Y1715700D02*
X427000D01*
Y1708300D01*
G01X404067Y1696009D02*
Y1698509D01*
X405108D01*
X405442Y1698384D01*
X405650Y1698217D01*
X405733Y1697884D01*
X405650Y1697551D01*
X405400Y1697342D01*
X405108Y1697217D01*
X404067D01*
G01X405108D02*
X405733Y1696009D01*
G01X407292Y1696301D02*
X407583Y1696092D01*
X407917Y1696009D01*
X408250Y1696092D01*
X408542Y1696342D01*
X408750Y1696717D01*
X408833Y1697092D01*
Y1697551D01*
X408750Y1697926D01*
X408542Y1698259D01*
X408292Y1698426D01*
X408000Y1698509D01*
X407667Y1698426D01*
X407417Y1698259D01*
X407250Y1698009D01*
X407167Y1697676D01*
X407250Y1697384D01*
X407458Y1697092D01*
X407708Y1696926D01*
X408000Y1696884D01*
X408333Y1696967D01*
X408583Y1697176D01*
X408833Y1697551D01*
G01X411100Y1698509D02*
X410767Y1698426D01*
X410517Y1698217D01*
X410350Y1697967D01*
X410225Y1697634D01*
X410183Y1697259D01*
X410225Y1696884D01*
X410350Y1696551D01*
X410517Y1696301D01*
X410767Y1696092D01*
X411100Y1696009D01*
X411433Y1696092D01*
X411683Y1696301D01*
X411850Y1696551D01*
X411975Y1696884D01*
X412017Y1697259D01*
X411975Y1697634D01*
X411850Y1697967D01*
X411683Y1698217D01*
X411433Y1698426D01*
X411100Y1698509D01*
G01X413283Y1696384D02*
X413533Y1696176D01*
X413825Y1696051D01*
X414200Y1696009D01*
X414575Y1696092D01*
X414867Y1696259D01*
X415075Y1696551D01*
X415117Y1696884D01*
X415033Y1697217D01*
X414825Y1697426D01*
X414533Y1697592D01*
X414242Y1697634D01*
X413950Y1697592D01*
X413575Y1697426D01*
X413700Y1698509D01*
X414825D01*
G01X417217Y1696009D02*
X417300Y1696551D01*
X417425Y1697009D01*
X417592Y1697426D01*
X417800Y1697884D01*
X418133Y1698509D01*
X416467D01*
G01X404067Y1700009D02*
Y1702509D01*
X405108D01*
X405442Y1702384D01*
X405650Y1702217D01*
X405733Y1701884D01*
X405650Y1701551D01*
X405400Y1701342D01*
X405108Y1701217D01*
X404067D01*
G01X405108D02*
X405733Y1700009D01*
G01X407292Y1700301D02*
X407583Y1700092D01*
X407917Y1700009D01*
X408250Y1700092D01*
X408542Y1700342D01*
X408750Y1700717D01*
X408833Y1701092D01*
Y1701551D01*
X408750Y1701926D01*
X408542Y1702259D01*
X408292Y1702426D01*
X408000Y1702509D01*
X407667Y1702426D01*
X407417Y1702259D01*
X407250Y1702009D01*
X407167Y1701676D01*
X407250Y1701384D01*
X407458Y1701092D01*
X407708Y1700926D01*
X408000Y1700884D01*
X408333Y1700967D01*
X408583Y1701176D01*
X408833Y1701551D01*
G01X411100Y1702509D02*
X410767Y1702426D01*
X410517Y1702217D01*
X410350Y1701967D01*
X410225Y1701634D01*
X410183Y1701259D01*
X410225Y1700884D01*
X410350Y1700551D01*
X410517Y1700301D01*
X410767Y1700092D01*
X411100Y1700009D01*
X411433Y1700092D01*
X411683Y1700301D01*
X411850Y1700551D01*
X411975Y1700884D01*
X412017Y1701259D01*
X411975Y1701634D01*
X411850Y1701967D01*
X411683Y1702217D01*
X411433Y1702426D01*
X411100Y1702509D01*
G01X413283Y1700384D02*
X413533Y1700176D01*
X413825Y1700051D01*
X414200Y1700009D01*
X414575Y1700092D01*
X414867Y1700259D01*
X415075Y1700551D01*
X415117Y1700884D01*
X415033Y1701217D01*
X414825Y1701426D01*
X414533Y1701592D01*
X414242Y1701634D01*
X413950Y1701592D01*
X413575Y1701426D01*
X413700Y1702509D01*
X414825D01*
G01X417300Y1700009D02*
X417592Y1700051D01*
X417925Y1700176D01*
X418133Y1700384D01*
X418217Y1700676D01*
X418133Y1700967D01*
X417883Y1701217D01*
X417508Y1701342D01*
X417092D01*
X416842Y1701426D01*
X416633Y1701634D01*
X416550Y1701926D01*
X416675Y1702217D01*
X416967Y1702426D01*
X417300Y1702509D01*
X417633Y1702426D01*
X417925Y1702217D01*
X418050Y1701926D01*
X417967Y1701634D01*
X417758Y1701426D01*
X417508Y1701342D01*
X417092D01*
X416717Y1701217D01*
X416467Y1700967D01*
X416383Y1700676D01*
X416467Y1700384D01*
X416675Y1700176D01*
X417008Y1700051D01*
X417300Y1700009D01*
G01X443456Y1688500D02*
X440956D01*
Y1689541D01*
X441081Y1689875D01*
X441248Y1690083D01*
X441581Y1690166D01*
X441914Y1690083D01*
X442123Y1689833D01*
X442248Y1689541D01*
Y1688500D01*
G01Y1689541D02*
X443456Y1690166D01*
G01Y1692433D02*
X440956D01*
X441456Y1691933D01*
G01X443456D02*
Y1692933D01*
G01Y1695533D02*
X440956D01*
X441456Y1695033D01*
G01X443456D02*
Y1696033D01*
G01X443164Y1697925D02*
X443373Y1698216D01*
X443456Y1698550D01*
X443373Y1698883D01*
X443123Y1699175D01*
X442748Y1699383D01*
X442373Y1699466D01*
X441914D01*
X441539Y1699383D01*
X441206Y1699175D01*
X441039Y1698925D01*
X440956Y1698633D01*
X441039Y1698300D01*
X441206Y1698050D01*
X441456Y1697883D01*
X441789Y1697800D01*
X442081Y1697883D01*
X442373Y1698091D01*
X442539Y1698341D01*
X442581Y1698633D01*
X442498Y1698966D01*
X442289Y1699216D01*
X441914Y1699466D01*
G01X431000Y1723700D02*
X427000D01*
Y1716300D01*
G01X425467Y1688667D02*
Y1691167D01*
X426508D01*
X426842Y1691042D01*
X427050Y1690875D01*
X427133Y1690542D01*
X427050Y1690209D01*
X426800Y1690000D01*
X426508Y1689875D01*
X425467D01*
G01X426508D02*
X427133Y1688667D01*
G01X428692Y1688959D02*
X428983Y1688750D01*
X429317Y1688667D01*
X429650Y1688750D01*
X429942Y1689000D01*
X430150Y1689375D01*
X430233Y1689750D01*
Y1690209D01*
X430150Y1690584D01*
X429942Y1690917D01*
X429692Y1691084D01*
X429400Y1691167D01*
X429067Y1691084D01*
X428817Y1690917D01*
X428650Y1690667D01*
X428567Y1690334D01*
X428650Y1690042D01*
X428858Y1689750D01*
X429108Y1689584D01*
X429400Y1689542D01*
X429733Y1689625D01*
X429983Y1689834D01*
X430233Y1690209D01*
G01X431583Y1689042D02*
X431833Y1688834D01*
X432125Y1688709D01*
X432500Y1688667D01*
X432875Y1688750D01*
X433167Y1688917D01*
X433375Y1689209D01*
X433417Y1689542D01*
X433333Y1689875D01*
X433125Y1690084D01*
X432833Y1690250D01*
X432542Y1690292D01*
X432250Y1690250D01*
X431875Y1690084D01*
X432000Y1691167D01*
X433125D01*
G01X434892Y1688959D02*
X435183Y1688750D01*
X435517Y1688667D01*
X435850Y1688750D01*
X436142Y1689000D01*
X436350Y1689375D01*
X436433Y1689750D01*
Y1690209D01*
X436350Y1690584D01*
X436142Y1690917D01*
X435892Y1691084D01*
X435600Y1691167D01*
X435267Y1691084D01*
X435017Y1690917D01*
X434850Y1690667D01*
X434767Y1690334D01*
X434850Y1690042D01*
X435058Y1689750D01*
X435308Y1689584D01*
X435600Y1689542D01*
X435933Y1689625D01*
X436183Y1689834D01*
X436433Y1690209D01*
G01X438700Y1688667D02*
Y1691167D01*
X438200Y1690667D01*
G01Y1688667D02*
X439200D01*
G01X426700Y1716500D02*
Y1720500D01*
X419300D01*
G01X424644Y1683394D02*
Y1685894D01*
X425685D01*
X426019Y1685769D01*
X426227Y1685602D01*
X426310Y1685269D01*
X426227Y1684936D01*
X425977Y1684727D01*
X425685Y1684602D01*
X424644D01*
G01X425685D02*
X426310Y1683394D01*
G01X427869Y1683686D02*
X428160Y1683477D01*
X428494Y1683394D01*
X428827Y1683477D01*
X429119Y1683727D01*
X429327Y1684102D01*
X429410Y1684477D01*
Y1684936D01*
X429327Y1685311D01*
X429119Y1685644D01*
X428869Y1685811D01*
X428577Y1685894D01*
X428244Y1685811D01*
X427994Y1685644D01*
X427827Y1685394D01*
X427744Y1685061D01*
X427827Y1684769D01*
X428035Y1684477D01*
X428285Y1684311D01*
X428577Y1684269D01*
X428910Y1684352D01*
X429160Y1684561D01*
X429410Y1684936D01*
G01X430760Y1683769D02*
X431010Y1683561D01*
X431302Y1683436D01*
X431677Y1683394D01*
X432052Y1683477D01*
X432344Y1683644D01*
X432552Y1683936D01*
X432594Y1684269D01*
X432510Y1684602D01*
X432302Y1684811D01*
X432010Y1684977D01*
X431719Y1685019D01*
X431427Y1684977D01*
X431052Y1684811D01*
X431177Y1685894D01*
X432302D01*
G01X434069Y1683686D02*
X434360Y1683477D01*
X434694Y1683394D01*
X435027Y1683477D01*
X435319Y1683727D01*
X435527Y1684102D01*
X435610Y1684477D01*
Y1684936D01*
X435527Y1685311D01*
X435319Y1685644D01*
X435069Y1685811D01*
X434777Y1685894D01*
X434444Y1685811D01*
X434194Y1685644D01*
X434027Y1685394D01*
X433944Y1685061D01*
X434027Y1684769D01*
X434235Y1684477D01*
X434485Y1684311D01*
X434777Y1684269D01*
X435110Y1684352D01*
X435360Y1684561D01*
X435610Y1684936D01*
G01X437877Y1685894D02*
X437544Y1685811D01*
X437294Y1685602D01*
X437127Y1685352D01*
X437002Y1685019D01*
X436960Y1684644D01*
X437002Y1684269D01*
X437127Y1683936D01*
X437294Y1683686D01*
X437544Y1683477D01*
X437877Y1683394D01*
X438210Y1683477D01*
X438460Y1683686D01*
X438627Y1683936D01*
X438752Y1684269D01*
X438794Y1684644D01*
X438752Y1685019D01*
X438627Y1685352D01*
X438460Y1685602D01*
X438210Y1685811D01*
X437877Y1685894D01*
G01X426700Y1708500D02*
Y1712500D01*
X419300D01*
G01X408099Y1729666D02*
Y1732166D01*
X409140D01*
X409474Y1732041D01*
X409682Y1731874D01*
X409765Y1731541D01*
X409682Y1731208D01*
X409432Y1730999D01*
X409140Y1730874D01*
X408099D01*
G01X409140D02*
X409765Y1729666D01*
G01X411324Y1729958D02*
X411615Y1729749D01*
X411949Y1729666D01*
X412282Y1729749D01*
X412574Y1729999D01*
X412782Y1730374D01*
X412865Y1730749D01*
Y1731208D01*
X412782Y1731583D01*
X412574Y1731916D01*
X412324Y1732083D01*
X412032Y1732166D01*
X411699Y1732083D01*
X411449Y1731916D01*
X411282Y1731666D01*
X411199Y1731333D01*
X411282Y1731041D01*
X411490Y1730749D01*
X411740Y1730583D01*
X412032Y1730541D01*
X412365Y1730624D01*
X412615Y1730833D01*
X412865Y1731208D01*
G01X415132Y1732166D02*
X414799Y1732083D01*
X414549Y1731874D01*
X414382Y1731624D01*
X414257Y1731291D01*
X414215Y1730916D01*
X414257Y1730541D01*
X414382Y1730208D01*
X414549Y1729958D01*
X414799Y1729749D01*
X415132Y1729666D01*
X415465Y1729749D01*
X415715Y1729958D01*
X415882Y1730208D01*
X416007Y1730541D01*
X416049Y1730916D01*
X416007Y1731291D01*
X415882Y1731624D01*
X415715Y1731874D01*
X415465Y1732083D01*
X415132Y1732166D01*
G01X417315Y1730041D02*
X417565Y1729833D01*
X417857Y1729708D01*
X418232Y1729666D01*
X418607Y1729749D01*
X418899Y1729916D01*
X419107Y1730208D01*
X419149Y1730541D01*
X419065Y1730874D01*
X418857Y1731083D01*
X418565Y1731249D01*
X418274Y1731291D01*
X417982Y1731249D01*
X417607Y1731083D01*
X417732Y1732166D01*
X418857D01*
G01X420415Y1730041D02*
X420665Y1729833D01*
X420957Y1729708D01*
X421332Y1729666D01*
X421707Y1729749D01*
X421999Y1729916D01*
X422207Y1730208D01*
X422249Y1730541D01*
X422165Y1730874D01*
X421957Y1731083D01*
X421665Y1731249D01*
X421374Y1731291D01*
X421082Y1731249D01*
X420707Y1731083D01*
X420832Y1732166D01*
X421957D01*
G01X408099Y1733666D02*
Y1736166D01*
X409140D01*
X409474Y1736041D01*
X409682Y1735874D01*
X409765Y1735541D01*
X409682Y1735208D01*
X409432Y1734999D01*
X409140Y1734874D01*
X408099D01*
G01X409140D02*
X409765Y1733666D01*
G01X411324Y1733958D02*
X411615Y1733749D01*
X411949Y1733666D01*
X412282Y1733749D01*
X412574Y1733999D01*
X412782Y1734374D01*
X412865Y1734749D01*
Y1735208D01*
X412782Y1735583D01*
X412574Y1735916D01*
X412324Y1736083D01*
X412032Y1736166D01*
X411699Y1736083D01*
X411449Y1735916D01*
X411282Y1735666D01*
X411199Y1735333D01*
X411282Y1735041D01*
X411490Y1734749D01*
X411740Y1734583D01*
X412032Y1734541D01*
X412365Y1734624D01*
X412615Y1734833D01*
X412865Y1735208D01*
G01X415132Y1736166D02*
X414799Y1736083D01*
X414549Y1735874D01*
X414382Y1735624D01*
X414257Y1735291D01*
X414215Y1734916D01*
X414257Y1734541D01*
X414382Y1734208D01*
X414549Y1733958D01*
X414799Y1733749D01*
X415132Y1733666D01*
X415465Y1733749D01*
X415715Y1733958D01*
X415882Y1734208D01*
X416007Y1734541D01*
X416049Y1734916D01*
X416007Y1735291D01*
X415882Y1735624D01*
X415715Y1735874D01*
X415465Y1736083D01*
X415132Y1736166D01*
G01X417315Y1734041D02*
X417565Y1733833D01*
X417857Y1733708D01*
X418232Y1733666D01*
X418607Y1733749D01*
X418899Y1733916D01*
X419107Y1734208D01*
X419149Y1734541D01*
X419065Y1734874D01*
X418857Y1735083D01*
X418565Y1735249D01*
X418274Y1735291D01*
X417982Y1735249D01*
X417607Y1735083D01*
X417732Y1736166D01*
X418857D01*
G01X420540Y1734708D02*
X420832Y1734999D01*
X421082Y1735166D01*
X421415Y1735249D01*
X421707Y1735166D01*
X421915Y1734999D01*
X422082Y1734749D01*
X422124Y1734458D01*
X422082Y1734208D01*
X421915Y1733958D01*
X421665Y1733749D01*
X421374Y1733666D01*
X421040Y1733749D01*
X420749Y1733999D01*
X420582Y1734374D01*
X420540Y1734791D01*
X420624Y1735333D01*
X420749Y1735624D01*
X420957Y1735916D01*
X421249Y1736124D01*
X421540Y1736166D01*
X421832Y1736083D01*
X422040Y1735874D01*
G01X500881Y1477905D02*
X501548Y1478405D01*
X502048Y1479238D01*
X502381Y1480405D01*
X502048Y1481405D01*
X501381Y1482072D01*
X500215Y1482572D01*
X495715D01*
Y1472572D01*
X501215D01*
X502381Y1473239D01*
X503048Y1474239D01*
X503381Y1475405D01*
X503048Y1476572D01*
X502048Y1477572D01*
X500881Y1477905D01*
X495715D01*
G01X512148Y1472572D02*
Y1482572D01*
X505981Y1475405D01*
X514315D01*
G01X520748Y1472572D02*
X521915Y1472739D01*
X523248Y1473239D01*
X524081Y1474072D01*
X524415Y1475239D01*
X524081Y1476405D01*
X523081Y1477405D01*
X521581Y1477905D01*
X519915D01*
X518915Y1478239D01*
X518081Y1479072D01*
X517748Y1480239D01*
X518248Y1481405D01*
X519414Y1482239D01*
X520748Y1482572D01*
X522081Y1482239D01*
X523248Y1481405D01*
X523748Y1480239D01*
X523415Y1479072D01*
X522581Y1478239D01*
X521581Y1477905D01*
X519915D01*
X518415Y1477405D01*
X517415Y1476405D01*
X517081Y1475239D01*
X517415Y1474072D01*
X518248Y1473239D01*
X519581Y1472739D01*
X520748Y1472572D01*
G01X531348Y1472239D02*
X531015Y1472405D01*
Y1472739D01*
X531348Y1472905D01*
X531681Y1472739D01*
Y1472405D01*
X531348Y1472239D01*
G01X541948Y1482572D02*
X540614Y1482239D01*
X539615Y1481405D01*
X538948Y1480405D01*
X538448Y1479072D01*
X538281Y1477572D01*
X538448Y1476072D01*
X538948Y1474739D01*
X539615Y1473738D01*
X540614Y1472905D01*
X541948Y1472572D01*
X543281Y1472905D01*
X544281Y1473738D01*
X544948Y1474739D01*
X545448Y1476072D01*
X545615Y1477572D01*
X545448Y1479072D01*
X544948Y1480405D01*
X544281Y1481405D01*
X543281Y1482239D01*
X541948Y1482572D01*
G01X552548D02*
X551214Y1482239D01*
X550215Y1481405D01*
X549548Y1480405D01*
X549048Y1479072D01*
X548881Y1477572D01*
X549048Y1476072D01*
X549548Y1474739D01*
X550215Y1473738D01*
X551214Y1472905D01*
X552548Y1472572D01*
X553881Y1472905D01*
X554881Y1473738D01*
X555548Y1474739D01*
X556048Y1476072D01*
X556215Y1477572D01*
X556048Y1479072D01*
X555548Y1480405D01*
X554881Y1481405D01*
X553881Y1482239D01*
X552548Y1482572D01*
G01X563148Y1472572D02*
X561814Y1472739D01*
X560648Y1473405D01*
X559648Y1474405D01*
X558981Y1475572D01*
X558648Y1476905D01*
Y1478239D01*
X558981Y1479572D01*
X559648Y1480739D01*
X560648Y1481739D01*
X561814Y1482405D01*
X563148Y1482572D01*
X564481Y1482405D01*
X565648Y1481739D01*
X566648Y1480739D01*
X567315Y1479572D01*
X567648Y1478239D01*
Y1476905D01*
X567315Y1475572D01*
X566648Y1474405D01*
X565648Y1473405D01*
X564481Y1472739D01*
X563148Y1472572D01*
G01X564481Y1475239D02*
X566481Y1472572D01*
G01X573748Y1482572D02*
X572414Y1482239D01*
X571415Y1481405D01*
X570748Y1480405D01*
X570248Y1479072D01*
X570081Y1477572D01*
X570248Y1476072D01*
X570748Y1474739D01*
X571415Y1473738D01*
X572414Y1472905D01*
X573748Y1472572D01*
X575081Y1472905D01*
X576081Y1473738D01*
X576748Y1474739D01*
X577248Y1476072D01*
X577415Y1477572D01*
X577248Y1479072D01*
X576748Y1480405D01*
X576081Y1481405D01*
X575081Y1482239D01*
X573748Y1482572D01*
G01X586348Y1472572D02*
Y1482572D01*
X580181Y1475405D01*
X588515D01*
G01X594948Y1472239D02*
X594615Y1472405D01*
Y1472739D01*
X594948Y1472905D01*
X595281Y1472739D01*
Y1472405D01*
X594948Y1472239D01*
G01X605548Y1482572D02*
X604214Y1482239D01*
X603215Y1481405D01*
X602548Y1480405D01*
X602048Y1479072D01*
X601881Y1477572D01*
X602048Y1476072D01*
X602548Y1474739D01*
X603215Y1473738D01*
X604214Y1472905D01*
X605548Y1472572D01*
X606881Y1472905D01*
X607881Y1473738D01*
X608548Y1474739D01*
X609048Y1476072D01*
X609215Y1477572D01*
X609048Y1479072D01*
X608548Y1480405D01*
X607881Y1481405D01*
X606881Y1482239D01*
X605548Y1482572D01*
G01X616148D02*
X614814Y1482239D01*
X613815Y1481405D01*
X613148Y1480405D01*
X612648Y1479072D01*
X612481Y1477572D01*
X612648Y1476072D01*
X613148Y1474739D01*
X613815Y1473738D01*
X614814Y1472905D01*
X616148Y1472572D01*
X617481Y1472905D01*
X618481Y1473738D01*
X619148Y1474739D01*
X619648Y1476072D01*
X619815Y1477572D01*
X619648Y1479072D01*
X619148Y1480405D01*
X618481Y1481405D01*
X617481Y1482239D01*
X616148Y1482572D01*
G01X626748Y1472572D02*
Y1482572D01*
X624748Y1480572D01*
G01Y1472572D02*
X628748D01*
G01X637348D02*
Y1482572D01*
X635348Y1480572D01*
G01Y1472572D02*
X639348D01*
G01X498038Y1489972D02*
Y1499972D01*
X496038Y1497972D01*
G01Y1489972D02*
X500038D01*
G01X504971Y1491472D02*
X505971Y1490639D01*
X507138Y1490139D01*
X508638Y1489972D01*
X510138Y1490305D01*
X511305Y1490972D01*
X512138Y1492139D01*
X512305Y1493472D01*
X511971Y1494805D01*
X511138Y1495639D01*
X509971Y1496305D01*
X508805Y1496472D01*
X507638Y1496305D01*
X506138Y1495639D01*
X506638Y1499972D01*
X511138D01*
G01X516071Y1494138D02*
X517238Y1495305D01*
X518238Y1495972D01*
X519571Y1496305D01*
X520738Y1495972D01*
X521571Y1495305D01*
X522238Y1494305D01*
X522405Y1493139D01*
X522238Y1492139D01*
X521571Y1491138D01*
X520571Y1490305D01*
X519405Y1489972D01*
X518071Y1490305D01*
X516905Y1491305D01*
X516238Y1492805D01*
X516071Y1494472D01*
X516405Y1496638D01*
X516905Y1497805D01*
X517738Y1498972D01*
X518905Y1499805D01*
X520071Y1499972D01*
X521238Y1499639D01*
X522071Y1498805D01*
G01X526671Y1494138D02*
X527838Y1495305D01*
X528838Y1495972D01*
X530171Y1496305D01*
X531338Y1495972D01*
X532171Y1495305D01*
X532838Y1494305D01*
X533005Y1493139D01*
X532838Y1492139D01*
X532171Y1491138D01*
X531171Y1490305D01*
X530005Y1489972D01*
X528671Y1490305D01*
X527505Y1491305D01*
X526838Y1492805D01*
X526671Y1494472D01*
X527005Y1496638D01*
X527505Y1497805D01*
X528338Y1498972D01*
X529505Y1499805D01*
X530671Y1499972D01*
X531838Y1499639D01*
X532671Y1498805D01*
G01X537605Y1491138D02*
X538771Y1490305D01*
X540105Y1489972D01*
X541438Y1490305D01*
X542605Y1491305D01*
X543438Y1492805D01*
X543771Y1494305D01*
Y1496139D01*
X543438Y1497639D01*
X542605Y1498972D01*
X541605Y1499639D01*
X540438Y1499972D01*
X539104Y1499639D01*
X538105Y1498972D01*
X537438Y1497972D01*
X537105Y1496638D01*
X537438Y1495472D01*
X538271Y1494305D01*
X539271Y1493638D01*
X540438Y1493472D01*
X541771Y1493805D01*
X542771Y1494639D01*
X543771Y1496139D01*
G01X548871Y1493305D02*
X553205D01*
G01X561638Y1489972D02*
Y1499972D01*
X559638Y1497972D01*
G01Y1489972D02*
X563638D01*
G01X496665Y1453892D02*
Y1463892D01*
X500998Y1455559D01*
X505331Y1463892D01*
Y1453892D01*
G01X507431D02*
X511598Y1463892D01*
X515765Y1453892D01*
G01X514265Y1457392D02*
X508931D01*
G01X518531Y1453892D02*
Y1463892D01*
X521865D01*
X523198Y1463392D01*
X524198Y1462725D01*
X525031Y1461725D01*
X525698Y1460558D01*
X525865Y1458892D01*
X525698Y1457225D01*
X525031Y1456059D01*
X524198Y1455058D01*
X523198Y1454392D01*
X521865Y1453892D01*
X518531D01*
G01X536131D02*
X529465D01*
Y1463892D01*
X536131D01*
G01X533465Y1459059D02*
X529465D01*
G01X551998Y1463892D02*
X555998D01*
G01X553998D02*
Y1453892D01*
G01X551998D02*
X555998D01*
G01X560765D02*
Y1463892D01*
X568431Y1453892D01*
Y1463892D01*
G01X585798D02*
Y1453892D01*
G01X581965Y1463892D02*
X589631D01*
G01X592231Y1453892D02*
X596398Y1463892D01*
X600565Y1453892D01*
G01X599065Y1457392D02*
X593731D01*
G01X604998Y1463892D02*
X608998D01*
G01X606998D02*
Y1453892D01*
G01X604998D02*
X608998D01*
G01X612598Y1463892D02*
X614931Y1453892D01*
X617598Y1463892D01*
X620265Y1453892D01*
X622598Y1463892D01*
G01X624031Y1453892D02*
X628198Y1463892D01*
X632365Y1453892D01*
G01X630865Y1457392D02*
X625531D01*
G01X634965Y1453892D02*
Y1463892D01*
X642631Y1453892D01*
Y1463892D01*
G01X497365Y1519932D02*
Y1509932D01*
X504031D01*
G01X511298Y1516598D02*
Y1509932D01*
G01Y1519265D02*
X510965Y1519432D01*
Y1519765D01*
X511298Y1519932D01*
X511631Y1519765D01*
Y1519432D01*
X511298Y1519265D01*
G01X519565Y1507432D02*
X520731Y1506765D01*
X522065Y1506599D01*
X523231Y1506765D01*
X524231Y1507599D01*
X524898Y1508765D01*
Y1516598D01*
G01Y1515265D02*
X524231Y1515932D01*
X523231Y1516432D01*
X522065Y1516598D01*
X520731Y1516265D01*
X519898Y1515599D01*
X519231Y1514432D01*
X518898Y1513265D01*
X519065Y1512265D01*
X519731Y1511098D01*
X520731Y1510265D01*
X522065Y1509932D01*
X523065Y1510099D01*
X524231Y1510765D01*
X524898Y1511432D01*
G01X529665Y1509932D02*
Y1519932D01*
G01Y1515099D02*
X530498Y1515932D01*
X531331Y1516432D01*
X532665Y1516598D01*
X533665Y1516432D01*
X534831Y1515765D01*
X535331Y1514765D01*
Y1509932D01*
G01X543098Y1519932D02*
Y1509932D01*
G01X540765Y1516598D02*
X545431D01*
G01X550865Y1509932D02*
Y1516598D01*
G01Y1514932D02*
X551531Y1515765D01*
X552531Y1516432D01*
X553865Y1516598D01*
X555031Y1516432D01*
X556031Y1515765D01*
X556531Y1514599D01*
Y1509932D01*
G01X564298Y1516598D02*
Y1509932D01*
G01Y1519265D02*
X563965Y1519432D01*
Y1519765D01*
X564298Y1519932D01*
X564631Y1519765D01*
Y1519432D01*
X564298Y1519265D01*
G01X572065Y1509932D02*
Y1516598D01*
G01Y1514932D02*
X572731Y1515765D01*
X573731Y1516432D01*
X575065Y1516598D01*
X576231Y1516432D01*
X577231Y1515765D01*
X577731Y1514599D01*
Y1509932D01*
G01X583165Y1507432D02*
X584331Y1506765D01*
X585665Y1506599D01*
X586831Y1506765D01*
X587831Y1507599D01*
X588498Y1508765D01*
Y1516598D01*
G01Y1515265D02*
X587831Y1515932D01*
X586831Y1516432D01*
X585665Y1516598D01*
X584331Y1516265D01*
X583498Y1515599D01*
X582831Y1514432D01*
X582498Y1513265D01*
X582665Y1512265D01*
X583331Y1511098D01*
X584331Y1510265D01*
X585665Y1509932D01*
X586665Y1510099D01*
X587831Y1510765D01*
X588498Y1511432D01*
G01X603365Y1509932D02*
Y1519932D01*
X607365D01*
X608698Y1519432D01*
X609698Y1518265D01*
X610031Y1516932D01*
X609698Y1515599D01*
X608865Y1514599D01*
X607365Y1514098D01*
X603365D01*
G01X613631Y1509932D02*
Y1519932D01*
X616965D01*
X618298Y1519432D01*
X619298Y1518765D01*
X620131Y1517765D01*
X620798Y1516598D01*
X620965Y1514932D01*
X620798Y1513265D01*
X620131Y1512099D01*
X619298Y1511098D01*
X618298Y1510432D01*
X616965Y1509932D01*
X613631D01*
G01X624565D02*
Y1519932D01*
X628565D01*
X629898Y1519432D01*
X630898Y1518265D01*
X631231Y1516932D01*
X630898Y1515599D01*
X630065Y1514599D01*
X628565Y1514098D01*
X624565D01*
G01X639831Y1515265D02*
X640498Y1515765D01*
X640998Y1516598D01*
X641331Y1517765D01*
X640998Y1518765D01*
X640331Y1519432D01*
X639165Y1519932D01*
X634665D01*
Y1509932D01*
X640165D01*
X641331Y1510599D01*
X641998Y1511599D01*
X642331Y1512765D01*
X641998Y1513932D01*
X640998Y1514932D01*
X639831Y1515265D01*
X634665D01*
G01X656365Y1509932D02*
Y1519932D01*
X660365D01*
X661698Y1519432D01*
X662698Y1518265D01*
X663031Y1516932D01*
X662698Y1515599D01*
X661865Y1514599D01*
X660365Y1514098D01*
X656365D01*
G01X666131Y1519932D02*
X670298Y1509932D01*
X674465Y1519932D01*
G01X680898D02*
Y1509932D01*
G01X677065Y1519932D02*
X684731D01*
G01X602667Y1164000D02*
Y1174000D01*
X606833D01*
X608167Y1173500D01*
X609000Y1172833D01*
X609333Y1171500D01*
X609000Y1170167D01*
X608000Y1169333D01*
X606833Y1168833D01*
X602667D01*
G01X606833D02*
X609333Y1164000D01*
G01X616600D02*
X615266Y1164167D01*
X614100Y1164833D01*
X613100Y1165833D01*
X612433Y1167000D01*
X612100Y1168333D01*
Y1169667D01*
X612433Y1171000D01*
X613100Y1172167D01*
X614100Y1173167D01*
X615266Y1173833D01*
X616600Y1174000D01*
X617933Y1173833D01*
X619100Y1173167D01*
X620100Y1172167D01*
X620767Y1171000D01*
X621100Y1169667D01*
Y1168333D01*
X620767Y1167000D01*
X620100Y1165833D01*
X619100Y1164833D01*
X617933Y1164167D01*
X616600Y1164000D01*
G01X623700D02*
Y1174000D01*
G01X630700D02*
Y1164000D01*
G01Y1169000D02*
X623700D01*
G01X634300Y1165333D02*
X635633Y1164500D01*
X637133Y1164000D01*
X638467D01*
X639800Y1164500D01*
X640800Y1165333D01*
X641300Y1166500D01*
X640967Y1167666D01*
X640133Y1168667D01*
X638633Y1169333D01*
X636633Y1169667D01*
X635467Y1170333D01*
X634967Y1171500D01*
X635300Y1172667D01*
X636133Y1173500D01*
X637300Y1174000D01*
X638467D01*
X639633Y1173667D01*
X640633Y1172833D01*
G01X661667Y1169833D02*
X660500Y1170500D01*
X659500Y1170666D01*
X658167Y1170333D01*
X657167Y1169667D01*
X656500Y1168500D01*
X656333Y1167333D01*
X656500Y1166167D01*
X657167Y1165166D01*
X658167Y1164333D01*
X659500Y1164000D01*
X660667Y1164333D01*
X661667Y1165000D01*
G01X669600Y1164000D02*
X668600Y1164167D01*
X667600Y1164833D01*
X666933Y1166000D01*
X666600Y1167333D01*
X666933Y1168667D01*
X667600Y1169833D01*
X668600Y1170500D01*
X669600Y1170666D01*
X670600Y1170500D01*
X671600Y1169833D01*
X672267Y1168667D01*
X672433Y1167333D01*
X672267Y1166000D01*
X671600Y1164833D01*
X670600Y1164167D01*
X669600Y1164000D01*
G01X675200D02*
Y1170666D01*
G01Y1168833D02*
X675700Y1169667D01*
X676533Y1170333D01*
X677700Y1170666D01*
X678866Y1170333D01*
X679700Y1169667D01*
X680200Y1168833D01*
Y1164000D01*
G01Y1168833D02*
X680700Y1169667D01*
X681533Y1170333D01*
X682700Y1170666D01*
X683867Y1170333D01*
X684700Y1169667D01*
X685200Y1168667D01*
Y1164000D01*
G01X687800Y1160667D02*
Y1170666D01*
G01Y1169167D02*
X688633Y1170000D01*
X689466Y1170500D01*
X690800Y1170666D01*
X691967Y1170500D01*
X693133Y1169667D01*
X693633Y1168500D01*
X693800Y1167333D01*
X693633Y1166167D01*
X693133Y1165000D01*
X692133Y1164333D01*
X690800Y1164000D01*
X689633Y1164167D01*
X688467Y1164667D01*
X687800Y1165333D01*
G01X701400Y1164000D02*
Y1174000D01*
G01X712000Y1170666D02*
Y1164000D01*
G01Y1173333D02*
X711667Y1173500D01*
Y1173833D01*
X712000Y1174000D01*
X712333Y1173833D01*
Y1173500D01*
X712000Y1173333D01*
G01X725600Y1164000D02*
Y1170666D01*
G01Y1169500D02*
X724933Y1170167D01*
X723933Y1170500D01*
X722767Y1170666D01*
X721600Y1170333D01*
X720600Y1169667D01*
X719933Y1168667D01*
X719600Y1167333D01*
X719933Y1166000D01*
X720600Y1165000D01*
X721600Y1164333D01*
X722767Y1164000D01*
X723933Y1164167D01*
X724933Y1164667D01*
X725600Y1165333D01*
G01X730367Y1164000D02*
Y1170666D01*
G01Y1169000D02*
X731033Y1169833D01*
X732033Y1170500D01*
X733367Y1170666D01*
X734533Y1170500D01*
X735533Y1169833D01*
X736033Y1168667D01*
Y1164000D01*
G01X746467Y1169833D02*
X745300Y1170500D01*
X744300Y1170666D01*
X742967Y1170333D01*
X741967Y1169667D01*
X741300Y1168500D01*
X741133Y1167333D01*
X741300Y1166167D01*
X741967Y1165166D01*
X742967Y1164333D01*
X744300Y1164000D01*
X745467Y1164333D01*
X746467Y1165000D01*
G01X751900Y1168500D02*
X757233D01*
X756733Y1169667D01*
X755900Y1170333D01*
X754733Y1170666D01*
X753567Y1170500D01*
X752567Y1170000D01*
X751900Y1168833D01*
X751567Y1167833D01*
Y1166833D01*
X751900Y1165833D01*
X752733Y1164833D01*
X753733Y1164167D01*
X754900Y1164000D01*
X756067Y1164333D01*
X757233Y1165333D01*
G01X557585Y1160280D02*
X559835D01*
G01X557585Y1154400D02*
Y1160280D01*
G01X559835Y1154400D02*
X557585D01*
G01X558935Y1157435D02*
X557585D01*
G01X563335Y1156070D02*
Y1160280D01*
G01X563105Y1155185D02*
X563335Y1156070D01*
G01X562655Y1154600D02*
X563105Y1155185D01*
G01X562090Y1154400D02*
X562655Y1154600D01*
G01X561525D02*
X562090Y1154400D01*
G01X561075Y1155185D02*
X561525Y1154600D01*
G01X560850Y1156070D02*
X561075Y1155185D01*
G01X560850Y1160280D02*
Y1156070D01*
G01X569300Y1154495D02*
X568855Y1154400D01*
G01X569700Y1154890D02*
X569300Y1154495D01*
G01X570035Y1155480D02*
X569700Y1154890D01*
G01X570265Y1156165D02*
X570035Y1155480D01*
G01X570375Y1156950D02*
X570265Y1156165D01*
G01X570375Y1157730D02*
Y1156950D01*
G01X570265Y1158515D02*
X570375Y1157730D01*
G01X570035Y1159200D02*
X570265Y1158515D01*
G01X569700Y1159790D02*
X570035Y1159200D01*
G01X569300Y1160185D02*
X569700Y1159790D01*
G01X568855Y1160280D02*
X569300Y1160185D01*
G01X568405D02*
X568855Y1160280D01*
G01X568005Y1159790D02*
X568405Y1160185D01*
G01X567670Y1159200D02*
X568005Y1159790D01*
G01X567440Y1158515D02*
X567670Y1159200D01*
G01X567330Y1157730D02*
X567440Y1158515D01*
G01X567330Y1156950D02*
Y1157730D01*
G01X567440Y1156165D02*
X567330Y1156950D01*
G01X567670Y1155480D02*
X567440Y1156165D01*
G01X568005Y1154890D02*
X567670Y1155480D01*
G01X568405Y1154495D02*
X568005Y1154890D01*
G01X568855Y1154400D02*
X568405Y1154495D01*
G01X571280Y1154400D02*
Y1158320D01*
G01X573190Y1157140D02*
Y1154400D01*
G01X573020Y1157830D02*
X573190Y1157140D01*
G01X572680Y1158220D02*
X573020Y1157830D01*
G01X572290Y1158320D02*
X572680Y1158220D01*
G01X571835D02*
X572290Y1158320D01*
G01X571500Y1157830D02*
X571835Y1158220D01*
G01X571280Y1157340D02*
X571500Y1157830D01*
G01X575615Y1154400D02*
Y1160280D01*
G01X579445Y1155085D02*
X580180Y1158320D01*
G01X579105Y1153520D02*
X579445Y1155085D01*
G01X578885Y1153025D02*
X579105Y1153520D01*
G01X578600Y1152635D02*
X578885Y1153025D01*
G01X578150Y1152440D02*
X578600Y1152635D01*
G01X577810D02*
X578150Y1152440D01*
G01X578380Y1158320D02*
X579445Y1155085D01*
G01X696600Y55400D02*
Y27600D01*
X724400D01*
Y55400D01*
X696600D01*
G01X751206Y1972507D02*
Y1975007D01*
X752247D01*
X752581Y1974882D01*
X752789Y1974715D01*
X752872Y1974382D01*
X752789Y1974049D01*
X752539Y1973840D01*
X752247Y1973715D01*
X751206D01*
G01X752247D02*
X752872Y1972507D01*
G01X754431Y1972799D02*
X754722Y1972590D01*
X755056Y1972507D01*
X755389Y1972590D01*
X755681Y1972840D01*
X755889Y1973215D01*
X755972Y1973590D01*
Y1974049D01*
X755889Y1974424D01*
X755681Y1974757D01*
X755431Y1974924D01*
X755139Y1975007D01*
X754806Y1974924D01*
X754556Y1974757D01*
X754389Y1974507D01*
X754306Y1974174D01*
X754389Y1973882D01*
X754597Y1973590D01*
X754847Y1973424D01*
X755139Y1973382D01*
X755472Y1973465D01*
X755722Y1973674D01*
X755972Y1974049D01*
G01X758156Y1972507D02*
X758239Y1973049D01*
X758364Y1973507D01*
X758531Y1973924D01*
X758739Y1974382D01*
X759072Y1975007D01*
X757406D01*
G01X761256Y1972507D02*
X761339Y1973049D01*
X761464Y1973507D01*
X761631Y1973924D01*
X761839Y1974382D01*
X762172Y1975007D01*
X760506D01*
G01X763647Y1973549D02*
X763939Y1973840D01*
X764189Y1974007D01*
X764522Y1974090D01*
X764814Y1974007D01*
X765022Y1973840D01*
X765189Y1973590D01*
X765231Y1973299D01*
X765189Y1973049D01*
X765022Y1972799D01*
X764772Y1972590D01*
X764481Y1972507D01*
X764147Y1972590D01*
X763856Y1972840D01*
X763689Y1973215D01*
X763647Y1973632D01*
X763731Y1974174D01*
X763856Y1974465D01*
X764064Y1974757D01*
X764356Y1974965D01*
X764647Y1975007D01*
X764939Y1974924D01*
X765147Y1974715D01*
G01X758214Y1970282D02*
Y1966282D01*
X765614D01*
G01X750239Y1953974D02*
X747739D01*
Y1955015D01*
X747864Y1955349D01*
X748031Y1955557D01*
X748364Y1955640D01*
X748697Y1955557D01*
X748906Y1955307D01*
X749031Y1955015D01*
Y1953974D01*
G01Y1955015D02*
X750239Y1955640D01*
G01X749947Y1957199D02*
X750156Y1957490D01*
X750239Y1957824D01*
X750156Y1958157D01*
X749906Y1958449D01*
X749531Y1958657D01*
X749156Y1958740D01*
X748697D01*
X748322Y1958657D01*
X747989Y1958449D01*
X747822Y1958199D01*
X747739Y1957907D01*
X747822Y1957574D01*
X747989Y1957324D01*
X748239Y1957157D01*
X748572Y1957074D01*
X748864Y1957157D01*
X749156Y1957365D01*
X749322Y1957615D01*
X749364Y1957907D01*
X749281Y1958240D01*
X749072Y1958490D01*
X748697Y1958740D01*
G01X750239Y1961507D02*
X747739D01*
X749531Y1959965D01*
Y1962049D01*
G01X749947Y1963399D02*
X750156Y1963690D01*
X750239Y1964024D01*
X750156Y1964357D01*
X749906Y1964649D01*
X749531Y1964857D01*
X749156Y1964940D01*
X748697D01*
X748322Y1964857D01*
X747989Y1964649D01*
X747822Y1964399D01*
X747739Y1964107D01*
X747822Y1963774D01*
X747989Y1963524D01*
X748239Y1963357D01*
X748572Y1963274D01*
X748864Y1963357D01*
X749156Y1963565D01*
X749322Y1963815D01*
X749364Y1964107D01*
X749281Y1964440D01*
X749072Y1964690D01*
X748697Y1964940D01*
G01X749864Y1966290D02*
X750072Y1966540D01*
X750197Y1966832D01*
X750239Y1967207D01*
X750156Y1967582D01*
X749989Y1967874D01*
X749697Y1968082D01*
X749364Y1968124D01*
X749031Y1968040D01*
X748822Y1967832D01*
X748656Y1967540D01*
X748614Y1967249D01*
X748656Y1966957D01*
X748822Y1966582D01*
X747739Y1966707D01*
Y1967832D01*
G01X762739Y1957807D02*
X766739D01*
Y1965207D01*
G01X754239Y1953974D02*
X751739D01*
Y1955015D01*
X751864Y1955349D01*
X752031Y1955557D01*
X752364Y1955640D01*
X752697Y1955557D01*
X752906Y1955307D01*
X753031Y1955015D01*
Y1953974D01*
G01Y1955015D02*
X754239Y1955640D01*
G01X753947Y1957199D02*
X754156Y1957490D01*
X754239Y1957824D01*
X754156Y1958157D01*
X753906Y1958449D01*
X753531Y1958657D01*
X753156Y1958740D01*
X752697D01*
X752322Y1958657D01*
X751989Y1958449D01*
X751822Y1958199D01*
X751739Y1957907D01*
X751822Y1957574D01*
X751989Y1957324D01*
X752239Y1957157D01*
X752572Y1957074D01*
X752864Y1957157D01*
X753156Y1957365D01*
X753322Y1957615D01*
X753364Y1957907D01*
X753281Y1958240D01*
X753072Y1958490D01*
X752697Y1958740D01*
G01X754239Y1960924D02*
X753697Y1961007D01*
X753239Y1961132D01*
X752822Y1961299D01*
X752364Y1961507D01*
X751739Y1961840D01*
Y1960174D01*
G01X753197Y1963315D02*
X752906Y1963607D01*
X752739Y1963857D01*
X752656Y1964190D01*
X752739Y1964482D01*
X752906Y1964690D01*
X753156Y1964857D01*
X753447Y1964899D01*
X753697Y1964857D01*
X753947Y1964690D01*
X754156Y1964440D01*
X754239Y1964149D01*
X754156Y1963815D01*
X753906Y1963524D01*
X753531Y1963357D01*
X753114Y1963315D01*
X752572Y1963399D01*
X752281Y1963524D01*
X751989Y1963732D01*
X751781Y1964024D01*
X751739Y1964315D01*
X751822Y1964607D01*
X752031Y1964815D01*
G01X751739Y1967207D02*
X751822Y1966874D01*
X752031Y1966624D01*
X752281Y1966457D01*
X752614Y1966332D01*
X752989Y1966290D01*
X753364Y1966332D01*
X753697Y1966457D01*
X753947Y1966624D01*
X754156Y1966874D01*
X754239Y1967207D01*
X754156Y1967540D01*
X753947Y1967790D01*
X753697Y1967957D01*
X753364Y1968082D01*
X752989Y1968124D01*
X752614Y1968082D01*
X752281Y1967957D01*
X752031Y1967790D01*
X751822Y1967540D01*
X751739Y1967207D01*
G01X833289Y158217D02*
X830789D01*
Y159258D01*
X830914Y159592D01*
X831081Y159800D01*
X831414Y159883D01*
X831747Y159800D01*
X831956Y159550D01*
X832081Y159258D01*
Y158217D01*
G01Y159258D02*
X833289Y159883D01*
G01X832789Y161233D02*
X833081Y161483D01*
X833247Y161817D01*
X833289Y162192D01*
X833247Y162525D01*
X833039Y162858D01*
X832789Y163067D01*
X832539Y163108D01*
X832247Y163025D01*
X832039Y162733D01*
X831956Y162442D01*
Y162067D01*
G01Y162442D02*
X831831Y162692D01*
X831622Y162900D01*
X831372Y162983D01*
X831122Y162900D01*
X830914Y162692D01*
X830789Y162317D01*
X830831Y161942D01*
X830997Y161567D01*
G01X831206Y164458D02*
X830956Y164708D01*
X830831Y165000D01*
X830789Y165333D01*
X830872Y165750D01*
X831081Y166042D01*
X831331Y166125D01*
X831581Y166083D01*
X831789Y165917D01*
X832206Y165083D01*
X832497Y164708D01*
X832914Y164458D01*
X833289Y164375D01*
Y166125D01*
G01Y168350D02*
X833247Y168642D01*
X833122Y168975D01*
X832914Y169183D01*
X832622Y169267D01*
X832331Y169183D01*
X832081Y168933D01*
X831956Y168558D01*
Y168142D01*
X831872Y167892D01*
X831664Y167683D01*
X831372Y167600D01*
X831081Y167725D01*
X830872Y168017D01*
X830789Y168350D01*
X830872Y168683D01*
X831081Y168975D01*
X831372Y169100D01*
X831664Y169017D01*
X831872Y168808D01*
X831956Y168558D01*
Y168142D01*
X832081Y167767D01*
X832331Y167517D01*
X832622Y167433D01*
X832914Y167517D01*
X833122Y167725D01*
X833247Y168058D01*
X833289Y168350D01*
G01X830500Y172300D02*
X834500D01*
Y179700D01*
G01X825289Y158217D02*
X822789D01*
Y159258D01*
X822914Y159592D01*
X823081Y159800D01*
X823414Y159883D01*
X823747Y159800D01*
X823956Y159550D01*
X824081Y159258D01*
Y158217D01*
G01Y159258D02*
X825289Y159883D01*
G01X824789Y161233D02*
X825081Y161483D01*
X825247Y161817D01*
X825289Y162192D01*
X825247Y162525D01*
X825039Y162858D01*
X824789Y163067D01*
X824539Y163108D01*
X824247Y163025D01*
X824039Y162733D01*
X823956Y162442D01*
Y162067D01*
G01Y162442D02*
X823831Y162692D01*
X823622Y162900D01*
X823372Y162983D01*
X823122Y162900D01*
X822914Y162692D01*
X822789Y162317D01*
X822831Y161942D01*
X822997Y161567D01*
G01X823206Y164458D02*
X822956Y164708D01*
X822831Y165000D01*
X822789Y165333D01*
X822872Y165750D01*
X823081Y166042D01*
X823331Y166125D01*
X823581Y166083D01*
X823789Y165917D01*
X824206Y165083D01*
X824497Y164708D01*
X824914Y164458D01*
X825289Y164375D01*
Y166125D01*
G01X824997Y167642D02*
X825206Y167933D01*
X825289Y168267D01*
X825206Y168600D01*
X824956Y168892D01*
X824581Y169100D01*
X824206Y169183D01*
X823747D01*
X823372Y169100D01*
X823039Y168892D01*
X822872Y168642D01*
X822789Y168350D01*
X822872Y168017D01*
X823039Y167767D01*
X823289Y167600D01*
X823622Y167517D01*
X823914Y167600D01*
X824206Y167808D01*
X824372Y168058D01*
X824414Y168350D01*
X824331Y168683D01*
X824122Y168933D01*
X823747Y169183D01*
G01X822500Y172300D02*
X826500D01*
Y179700D01*
G01X837289Y158217D02*
X834789D01*
Y159258D01*
X834914Y159592D01*
X835081Y159800D01*
X835414Y159883D01*
X835747Y159800D01*
X835956Y159550D01*
X836081Y159258D01*
Y158217D01*
G01Y159258D02*
X837289Y159883D01*
G01X836789Y161233D02*
X837081Y161483D01*
X837247Y161817D01*
X837289Y162192D01*
X837247Y162525D01*
X837039Y162858D01*
X836789Y163067D01*
X836539Y163108D01*
X836247Y163025D01*
X836039Y162733D01*
X835956Y162442D01*
Y162067D01*
G01Y162442D02*
X835831Y162692D01*
X835622Y162900D01*
X835372Y162983D01*
X835122Y162900D01*
X834914Y162692D01*
X834789Y162317D01*
X834831Y161942D01*
X834997Y161567D01*
G01X836789Y164333D02*
X837081Y164583D01*
X837247Y164917D01*
X837289Y165292D01*
X837247Y165625D01*
X837039Y165958D01*
X836789Y166167D01*
X836539Y166208D01*
X836247Y166125D01*
X836039Y165833D01*
X835956Y165542D01*
Y165167D01*
G01Y165542D02*
X835831Y165792D01*
X835622Y166000D01*
X835372Y166083D01*
X835122Y166000D01*
X834914Y165792D01*
X834789Y165417D01*
X834831Y165042D01*
X834997Y164667D01*
G01X836247Y167558D02*
X835956Y167850D01*
X835789Y168100D01*
X835706Y168433D01*
X835789Y168725D01*
X835956Y168933D01*
X836206Y169100D01*
X836497Y169142D01*
X836747Y169100D01*
X836997Y168933D01*
X837206Y168683D01*
X837289Y168392D01*
X837206Y168058D01*
X836956Y167767D01*
X836581Y167600D01*
X836164Y167558D01*
X835622Y167642D01*
X835331Y167767D01*
X835039Y167975D01*
X834831Y168267D01*
X834789Y168558D01*
X834872Y168850D01*
X835081Y169058D01*
G01X838500Y179700D02*
X834500D01*
Y172300D01*
G01X829289Y158217D02*
X826789D01*
Y159258D01*
X826914Y159592D01*
X827081Y159800D01*
X827414Y159883D01*
X827747Y159800D01*
X827956Y159550D01*
X828081Y159258D01*
Y158217D01*
G01Y159258D02*
X829289Y159883D01*
G01X828789Y161233D02*
X829081Y161483D01*
X829247Y161817D01*
X829289Y162192D01*
X829247Y162525D01*
X829039Y162858D01*
X828789Y163067D01*
X828539Y163108D01*
X828247Y163025D01*
X828039Y162733D01*
X827956Y162442D01*
Y162067D01*
G01Y162442D02*
X827831Y162692D01*
X827622Y162900D01*
X827372Y162983D01*
X827122Y162900D01*
X826914Y162692D01*
X826789Y162317D01*
X826831Y161942D01*
X826997Y161567D01*
G01X828789Y164333D02*
X829081Y164583D01*
X829247Y164917D01*
X829289Y165292D01*
X829247Y165625D01*
X829039Y165958D01*
X828789Y166167D01*
X828539Y166208D01*
X828247Y166125D01*
X828039Y165833D01*
X827956Y165542D01*
Y165167D01*
G01Y165542D02*
X827831Y165792D01*
X827622Y166000D01*
X827372Y166083D01*
X827122Y166000D01*
X826914Y165792D01*
X826789Y165417D01*
X826831Y165042D01*
X826997Y164667D01*
G01X829289Y168267D02*
X828747Y168350D01*
X828289Y168475D01*
X827872Y168642D01*
X827414Y168850D01*
X826789Y169183D01*
Y167517D01*
G01X830500Y179700D02*
X826500D01*
Y172300D01*
G01X817289Y158217D02*
X814789D01*
Y159258D01*
X814914Y159592D01*
X815081Y159800D01*
X815414Y159883D01*
X815747Y159800D01*
X815956Y159550D01*
X816081Y159258D01*
Y158217D01*
G01Y159258D02*
X817289Y159883D01*
G01X816789Y161233D02*
X817081Y161483D01*
X817247Y161817D01*
X817289Y162192D01*
X817247Y162525D01*
X817039Y162858D01*
X816789Y163067D01*
X816539Y163108D01*
X816247Y163025D01*
X816039Y162733D01*
X815956Y162442D01*
Y162067D01*
G01Y162442D02*
X815831Y162692D01*
X815622Y162900D01*
X815372Y162983D01*
X815122Y162900D01*
X814914Y162692D01*
X814789Y162317D01*
X814831Y161942D01*
X814997Y161567D01*
G01X815206Y164458D02*
X814956Y164708D01*
X814831Y165000D01*
X814789Y165333D01*
X814872Y165750D01*
X815081Y166042D01*
X815331Y166125D01*
X815581Y166083D01*
X815789Y165917D01*
X816206Y165083D01*
X816497Y164708D01*
X816914Y164458D01*
X817289Y164375D01*
Y166125D01*
G01Y168267D02*
X816747Y168350D01*
X816289Y168475D01*
X815872Y168642D01*
X815414Y168850D01*
X814789Y169183D01*
Y167517D01*
G01X814500Y172300D02*
X818500D01*
Y179700D01*
G01X821289Y158217D02*
X818789D01*
Y159258D01*
X818914Y159592D01*
X819081Y159800D01*
X819414Y159883D01*
X819747Y159800D01*
X819956Y159550D01*
X820081Y159258D01*
Y158217D01*
G01Y159258D02*
X821289Y159883D01*
G01X820789Y161233D02*
X821081Y161483D01*
X821247Y161817D01*
X821289Y162192D01*
X821247Y162525D01*
X821039Y162858D01*
X820789Y163067D01*
X820539Y163108D01*
X820247Y163025D01*
X820039Y162733D01*
X819956Y162442D01*
Y162067D01*
G01Y162442D02*
X819831Y162692D01*
X819622Y162900D01*
X819372Y162983D01*
X819122Y162900D01*
X818914Y162692D01*
X818789Y162317D01*
X818831Y161942D01*
X818997Y161567D01*
G01X820789Y164333D02*
X821081Y164583D01*
X821247Y164917D01*
X821289Y165292D01*
X821247Y165625D01*
X821039Y165958D01*
X820789Y166167D01*
X820539Y166208D01*
X820247Y166125D01*
X820039Y165833D01*
X819956Y165542D01*
Y165167D01*
G01Y165542D02*
X819831Y165792D01*
X819622Y166000D01*
X819372Y166083D01*
X819122Y166000D01*
X818914Y165792D01*
X818789Y165417D01*
X818831Y165042D01*
X818997Y164667D01*
G01X821289Y168350D02*
X821247Y168642D01*
X821122Y168975D01*
X820914Y169183D01*
X820622Y169267D01*
X820331Y169183D01*
X820081Y168933D01*
X819956Y168558D01*
Y168142D01*
X819872Y167892D01*
X819664Y167683D01*
X819372Y167600D01*
X819081Y167725D01*
X818872Y168017D01*
X818789Y168350D01*
X818872Y168683D01*
X819081Y168975D01*
X819372Y169100D01*
X819664Y169017D01*
X819872Y168808D01*
X819956Y168558D01*
Y168142D01*
X820081Y167767D01*
X820331Y167517D01*
X820622Y167433D01*
X820914Y167517D01*
X821122Y167725D01*
X821247Y168058D01*
X821289Y168350D01*
G01X822500Y179700D02*
X818500D01*
Y172300D01*
G01X779557Y190661D02*
Y193161D01*
X780598D01*
X780932Y193036D01*
X781140Y192869D01*
X781223Y192536D01*
X781140Y192203D01*
X780890Y191994D01*
X780598Y191869D01*
X779557D01*
G01X780598D02*
X781223Y190661D01*
G01X782573Y191161D02*
X782823Y190869D01*
X783157Y190703D01*
X783532Y190661D01*
X783865Y190703D01*
X784198Y190911D01*
X784407Y191161D01*
X784448Y191411D01*
X784365Y191703D01*
X784073Y191911D01*
X783782Y191994D01*
X783407D01*
G01X783782D02*
X784032Y192119D01*
X784240Y192328D01*
X784323Y192578D01*
X784240Y192828D01*
X784032Y193036D01*
X783657Y193161D01*
X783282Y193119D01*
X782907Y192953D01*
G01X785673Y191161D02*
X785923Y190869D01*
X786257Y190703D01*
X786632Y190661D01*
X786965Y190703D01*
X787298Y190911D01*
X787507Y191161D01*
X787548Y191411D01*
X787465Y191703D01*
X787173Y191911D01*
X786882Y191994D01*
X786507D01*
G01X786882D02*
X787132Y192119D01*
X787340Y192328D01*
X787423Y192578D01*
X787340Y192828D01*
X787132Y193036D01*
X786757Y193161D01*
X786382Y193119D01*
X786007Y192953D01*
G01X790190Y190661D02*
Y193161D01*
X788648Y191369D01*
X790732D01*
G01X797300Y195000D02*
Y191000D01*
X804700D01*
G01X803550Y178630D02*
X806050D01*
G01X803550Y177672D02*
Y179588D01*
G01X806050Y180897D02*
X803550D01*
Y181897D01*
X803675Y182230D01*
X803967Y182480D01*
X804300Y182563D01*
X804633Y182480D01*
X804883Y182272D01*
X805008Y181897D01*
Y180897D01*
G01Y184038D02*
X804717Y184330D01*
X804550Y184580D01*
X804467Y184913D01*
X804550Y185205D01*
X804717Y185413D01*
X804967Y185580D01*
X805258Y185622D01*
X805508Y185580D01*
X805758Y185413D01*
X805967Y185163D01*
X806050Y184872D01*
X805967Y184538D01*
X805717Y184247D01*
X805342Y184080D01*
X804925Y184038D01*
X804383Y184122D01*
X804092Y184247D01*
X803800Y184455D01*
X803592Y184747D01*
X803550Y185038D01*
X803633Y185330D01*
X803842Y185538D01*
G01X824740Y188663D02*
X832740D01*
Y200613D01*
X824740D01*
Y188663D01*
G01X829187Y207862D02*
X828937Y207987D01*
X828645Y208070D01*
X828312D01*
X827937Y207945D01*
X827645Y207737D01*
X827437Y207487D01*
X827270Y207070D01*
X827228Y206695D01*
X827312Y206320D01*
X827437Y206070D01*
X827687Y205820D01*
X827978Y205653D01*
X828270Y205570D01*
X828562D01*
X828853Y205653D01*
X829103Y205778D01*
X829312Y205945D01*
G01X830453Y206070D02*
X830703Y205778D01*
X831037Y205612D01*
X831412Y205570D01*
X831745Y205612D01*
X832078Y205820D01*
X832287Y206070D01*
X832328Y206320D01*
X832245Y206612D01*
X831953Y206820D01*
X831662Y206903D01*
X831287D01*
G01X831662D02*
X831912Y207028D01*
X832120Y207237D01*
X832203Y207487D01*
X832120Y207737D01*
X831912Y207945D01*
X831537Y208070D01*
X831162Y208028D01*
X830787Y207862D01*
G01X834970Y205570D02*
Y208070D01*
X833428Y206278D01*
X835512D01*
G01X836778Y207653D02*
X837028Y207903D01*
X837320Y208028D01*
X837653Y208070D01*
X838070Y207987D01*
X838362Y207778D01*
X838445Y207528D01*
X838403Y207278D01*
X838237Y207070D01*
X837403Y206653D01*
X837028Y206362D01*
X836778Y205945D01*
X836695Y205570D01*
X838445D01*
G01X779557Y195661D02*
Y198161D01*
X780598D01*
X780932Y198036D01*
X781140Y197869D01*
X781223Y197536D01*
X781140Y197203D01*
X780890Y196994D01*
X780598Y196869D01*
X779557D01*
G01X780598D02*
X781223Y195661D01*
G01X782573Y196161D02*
X782823Y195869D01*
X783157Y195703D01*
X783532Y195661D01*
X783865Y195703D01*
X784198Y195911D01*
X784407Y196161D01*
X784448Y196411D01*
X784365Y196703D01*
X784073Y196911D01*
X783782Y196994D01*
X783407D01*
G01X783782D02*
X784032Y197119D01*
X784240Y197328D01*
X784323Y197578D01*
X784240Y197828D01*
X784032Y198036D01*
X783657Y198161D01*
X783282Y198119D01*
X782907Y197953D01*
G01X785798Y197744D02*
X786048Y197994D01*
X786340Y198119D01*
X786673Y198161D01*
X787090Y198078D01*
X787382Y197869D01*
X787465Y197619D01*
X787423Y197369D01*
X787257Y197161D01*
X786423Y196744D01*
X786048Y196453D01*
X785798Y196036D01*
X785715Y195661D01*
X787465D01*
G01X788898Y196703D02*
X789190Y196994D01*
X789440Y197161D01*
X789773Y197244D01*
X790065Y197161D01*
X790273Y196994D01*
X790440Y196744D01*
X790482Y196453D01*
X790440Y196203D01*
X790273Y195953D01*
X790023Y195744D01*
X789732Y195661D01*
X789398Y195744D01*
X789107Y195994D01*
X788940Y196369D01*
X788898Y196786D01*
X788982Y197328D01*
X789107Y197619D01*
X789315Y197911D01*
X789607Y198119D01*
X789898Y198161D01*
X790190Y198078D01*
X790398Y197869D01*
G01X797300Y200000D02*
Y196000D01*
X804700D01*
G01X815233Y206040D02*
Y204248D01*
X815400Y203873D01*
X815733Y203623D01*
X816150Y203540D01*
X816567Y203623D01*
X816900Y203873D01*
X817067Y204248D01*
Y206040D01*
G01X819750Y203540D02*
Y206040D01*
X818208Y204248D01*
X820292D01*
G01X822350Y203540D02*
X822642Y203582D01*
X822975Y203707D01*
X823183Y203915D01*
X823267Y204207D01*
X823183Y204498D01*
X822933Y204748D01*
X822558Y204873D01*
X822142D01*
X821892Y204957D01*
X821683Y205165D01*
X821600Y205457D01*
X821725Y205748D01*
X822017Y205957D01*
X822350Y206040D01*
X822683Y205957D01*
X822975Y205748D01*
X823100Y205457D01*
X823017Y205165D01*
X822808Y204957D01*
X822558Y204873D01*
X822142D01*
X821767Y204748D01*
X821517Y204498D01*
X821433Y204207D01*
X821517Y203915D01*
X821725Y203707D01*
X822058Y203582D01*
X822350Y203540D01*
G01X830890Y200613D02*
X828890Y198613D01*
X826890Y200613D01*
G01X824277Y323297D02*
X824152Y323047D01*
X824069Y322755D01*
Y322422D01*
X824194Y322047D01*
X824402Y321755D01*
X824652Y321547D01*
X825069Y321380D01*
X825444Y321338D01*
X825819Y321422D01*
X826069Y321547D01*
X826319Y321797D01*
X826486Y322088D01*
X826569Y322380D01*
Y322672D01*
X826486Y322963D01*
X826361Y323213D01*
X826194Y323422D01*
G01X826069Y324563D02*
X826361Y324813D01*
X826527Y325147D01*
X826569Y325522D01*
X826527Y325855D01*
X826319Y326188D01*
X826069Y326397D01*
X825819Y326438D01*
X825527Y326355D01*
X825319Y326063D01*
X825236Y325772D01*
Y325397D01*
G01Y325772D02*
X825111Y326022D01*
X824902Y326230D01*
X824652Y326313D01*
X824402Y326230D01*
X824194Y326022D01*
X824069Y325647D01*
X824111Y325272D01*
X824277Y324897D01*
G01X826569Y328580D02*
X826527Y328872D01*
X826402Y329205D01*
X826194Y329413D01*
X825902Y329497D01*
X825611Y329413D01*
X825361Y329163D01*
X825236Y328788D01*
Y328372D01*
X825152Y328122D01*
X824944Y327913D01*
X824652Y327830D01*
X824361Y327955D01*
X824152Y328247D01*
X824069Y328580D01*
X824152Y328913D01*
X824361Y329205D01*
X824652Y329330D01*
X824944Y329247D01*
X825152Y329038D01*
X825236Y328788D01*
Y328372D01*
X825361Y327997D01*
X825611Y327747D01*
X825902Y327663D01*
X826194Y327747D01*
X826402Y327955D01*
X826527Y328288D01*
X826569Y328580D01*
G01X825527Y330888D02*
X825236Y331180D01*
X825069Y331430D01*
X824986Y331763D01*
X825069Y332055D01*
X825236Y332263D01*
X825486Y332430D01*
X825777Y332472D01*
X826027Y332430D01*
X826277Y332263D01*
X826486Y332013D01*
X826569Y331722D01*
X826486Y331388D01*
X826236Y331097D01*
X825861Y330930D01*
X825444Y330888D01*
X824902Y330972D01*
X824611Y331097D01*
X824319Y331305D01*
X824111Y331597D01*
X824069Y331888D01*
X824152Y332180D01*
X824361Y332388D01*
G01X815677Y335140D02*
Y337640D01*
X816718D01*
X817052Y337515D01*
X817260Y337348D01*
X817343Y337015D01*
X817260Y336682D01*
X817010Y336473D01*
X816718Y336348D01*
X815677D01*
G01X816718D02*
X817343Y335140D01*
G01X819610D02*
Y337640D01*
X819110Y337140D01*
G01Y335140D02*
X820110D01*
G01X823210D02*
Y337640D01*
X821668Y335848D01*
X823752D01*
G01X825018Y337223D02*
X825268Y337473D01*
X825560Y337598D01*
X825893Y337640D01*
X826310Y337557D01*
X826602Y337348D01*
X826685Y337098D01*
X826643Y336848D01*
X826477Y336640D01*
X825643Y336223D01*
X825268Y335932D01*
X825018Y335515D01*
X824935Y335140D01*
X826685D01*
G01X822569Y321547D02*
X820069D01*
Y322588D01*
X820194Y322922D01*
X820361Y323130D01*
X820694Y323213D01*
X821027Y323130D01*
X821236Y322880D01*
X821361Y322588D01*
Y321547D01*
G01Y322588D02*
X822569Y323213D01*
G01X822194Y324563D02*
X822402Y324813D01*
X822527Y325105D01*
X822569Y325480D01*
X822486Y325855D01*
X822319Y326147D01*
X822027Y326355D01*
X821694Y326397D01*
X821361Y326313D01*
X821152Y326105D01*
X820986Y325813D01*
X820944Y325522D01*
X820986Y325230D01*
X821152Y324855D01*
X820069Y324980D01*
Y326105D01*
G01X822569Y328497D02*
X822027Y328580D01*
X821569Y328705D01*
X821152Y328872D01*
X820694Y329080D01*
X820069Y329413D01*
Y327747D01*
G01Y331680D02*
X820152Y331347D01*
X820361Y331097D01*
X820611Y330930D01*
X820944Y330805D01*
X821319Y330763D01*
X821694Y330805D01*
X822027Y330930D01*
X822277Y331097D01*
X822486Y331347D01*
X822569Y331680D01*
X822486Y332013D01*
X822277Y332263D01*
X822027Y332430D01*
X821694Y332555D01*
X821319Y332597D01*
X820944Y332555D01*
X820611Y332430D01*
X820361Y332263D01*
X820152Y332013D01*
X820069Y331680D01*
G01X836167Y319375D02*
X836375Y319708D01*
X836500Y320083D01*
Y320417D01*
X836375Y320750D01*
X836167Y321000D01*
X835875Y321125D01*
X835583Y321042D01*
X835333Y320833D01*
X835167Y320458D01*
X835083Y319958D01*
X834917Y319667D01*
X834625Y319542D01*
X834333Y319625D01*
X834125Y319833D01*
X834000Y320125D01*
Y320417D01*
X834083Y320708D01*
X834292Y320958D01*
G01X836500Y322517D02*
X834000D01*
Y323558D01*
X834125Y323892D01*
X834292Y324100D01*
X834625Y324183D01*
X834958Y324100D01*
X835167Y323850D01*
X835292Y323558D01*
Y322517D01*
G01Y323558D02*
X836500Y324183D01*
G01Y326450D02*
X834000D01*
X834500Y325950D01*
G01X836500D02*
Y326950D01*
G01X834000Y329550D02*
X834083Y329217D01*
X834292Y328967D01*
X834542Y328800D01*
X834875Y328675D01*
X835250Y328633D01*
X835625Y328675D01*
X835958Y328800D01*
X836208Y328967D01*
X836417Y329217D01*
X836500Y329550D01*
X836417Y329883D01*
X836208Y330133D01*
X835958Y330300D01*
X835625Y330425D01*
X835250Y330467D01*
X834875Y330425D01*
X834542Y330300D01*
X834292Y330133D01*
X834083Y329883D01*
X834000Y329550D01*
G01X836208Y331942D02*
X836417Y332233D01*
X836500Y332567D01*
X836417Y332900D01*
X836167Y333192D01*
X835792Y333400D01*
X835417Y333483D01*
X834958D01*
X834583Y333400D01*
X834250Y333192D01*
X834083Y332942D01*
X834000Y332650D01*
X834083Y332317D01*
X834250Y332067D01*
X834500Y331900D01*
X834833Y331817D01*
X835125Y331900D01*
X835417Y332108D01*
X835583Y332358D01*
X835625Y332650D01*
X835542Y332983D01*
X835333Y333233D01*
X834958Y333483D01*
G01X836208Y335042D02*
X836417Y335333D01*
X836500Y335667D01*
X836417Y336000D01*
X836167Y336292D01*
X835792Y336500D01*
X835417Y336583D01*
X834958D01*
X834583Y336500D01*
X834250Y336292D01*
X834083Y336042D01*
X834000Y335750D01*
X834083Y335417D01*
X834250Y335167D01*
X834500Y335000D01*
X834833Y334917D01*
X835125Y335000D01*
X835417Y335208D01*
X835583Y335458D01*
X835625Y335750D01*
X835542Y336083D01*
X835333Y336333D01*
X834958Y336583D01*
G01X840167Y319375D02*
X840375Y319708D01*
X840500Y320083D01*
Y320417D01*
X840375Y320750D01*
X840167Y321000D01*
X839875Y321125D01*
X839583Y321042D01*
X839333Y320833D01*
X839167Y320458D01*
X839083Y319958D01*
X838917Y319667D01*
X838625Y319542D01*
X838333Y319625D01*
X838125Y319833D01*
X838000Y320125D01*
Y320417D01*
X838083Y320708D01*
X838292Y320958D01*
G01X840500Y322517D02*
X838000D01*
Y323558D01*
X838125Y323892D01*
X838292Y324100D01*
X838625Y324183D01*
X838958Y324100D01*
X839167Y323850D01*
X839292Y323558D01*
Y322517D01*
G01Y323558D02*
X840500Y324183D01*
G01Y326450D02*
X838000D01*
X838500Y325950D01*
G01X840500D02*
Y326950D01*
G01Y329550D02*
X838000D01*
X838500Y329050D01*
G01X840500D02*
Y330050D01*
G01X838000Y332650D02*
X838083Y332317D01*
X838292Y332067D01*
X838542Y331900D01*
X838875Y331775D01*
X839250Y331733D01*
X839625Y331775D01*
X839958Y331900D01*
X840208Y332067D01*
X840417Y332317D01*
X840500Y332650D01*
X840417Y332983D01*
X840208Y333233D01*
X839958Y333400D01*
X839625Y333525D01*
X839250Y333567D01*
X838875Y333525D01*
X838542Y333400D01*
X838292Y333233D01*
X838083Y332983D01*
X838000Y332650D01*
G01Y335750D02*
X838083Y335417D01*
X838292Y335167D01*
X838542Y335000D01*
X838875Y334875D01*
X839250Y334833D01*
X839625Y334875D01*
X839958Y335000D01*
X840208Y335167D01*
X840417Y335417D01*
X840500Y335750D01*
X840417Y336083D01*
X840208Y336333D01*
X839958Y336500D01*
X839625Y336625D01*
X839250Y336667D01*
X838875Y336625D01*
X838542Y336500D01*
X838292Y336333D01*
X838083Y336083D01*
X838000Y335750D01*
G01X818069Y321547D02*
X815569D01*
Y322588D01*
X815694Y322922D01*
X815861Y323130D01*
X816194Y323213D01*
X816527Y323130D01*
X816736Y322880D01*
X816861Y322588D01*
Y321547D01*
G01Y322588D02*
X818069Y323213D01*
G01X817694Y324563D02*
X817902Y324813D01*
X818027Y325105D01*
X818069Y325480D01*
X817986Y325855D01*
X817819Y326147D01*
X817527Y326355D01*
X817194Y326397D01*
X816861Y326313D01*
X816652Y326105D01*
X816486Y325813D01*
X816444Y325522D01*
X816486Y325230D01*
X816652Y324855D01*
X815569Y324980D01*
Y326105D01*
G01X817694Y327663D02*
X817902Y327913D01*
X818027Y328205D01*
X818069Y328580D01*
X817986Y328955D01*
X817819Y329247D01*
X817527Y329455D01*
X817194Y329497D01*
X816861Y329413D01*
X816652Y329205D01*
X816486Y328913D01*
X816444Y328622D01*
X816486Y328330D01*
X816652Y327955D01*
X815569Y328080D01*
Y329205D01*
G01X817694Y330763D02*
X817902Y331013D01*
X818027Y331305D01*
X818069Y331680D01*
X817986Y332055D01*
X817819Y332347D01*
X817527Y332555D01*
X817194Y332597D01*
X816861Y332513D01*
X816652Y332305D01*
X816486Y332013D01*
X816444Y331722D01*
X816486Y331430D01*
X816652Y331055D01*
X815569Y331180D01*
Y332305D01*
G01X825900Y383000D02*
X825567Y383042D01*
X825275Y383208D01*
X825025Y383458D01*
X824858Y383750D01*
X824775Y384083D01*
Y384417D01*
X824858Y384750D01*
X825025Y385042D01*
X825275Y385292D01*
X825567Y385458D01*
X825900Y385500D01*
X826233Y385458D01*
X826525Y385292D01*
X826775Y385042D01*
X826942Y384750D01*
X827025Y384417D01*
Y384083D01*
X826942Y383750D01*
X826775Y383458D01*
X826525Y383208D01*
X826233Y383042D01*
X825900Y383000D01*
G01X826233Y383667D02*
X826733Y383000D01*
G01X829500D02*
Y385500D01*
X827958Y383708D01*
X830042D01*
G01X832017Y383000D02*
X832100Y383542D01*
X832225Y384000D01*
X832392Y384417D01*
X832600Y384875D01*
X832933Y385500D01*
X831267D01*
G01X823500Y380400D02*
Y367400D01*
G01D02*
X837500D01*
G01D02*
Y380400D01*
G01D02*
X823500D01*
G01X808000Y349400D02*
X807958Y349067D01*
X807792Y348775D01*
X807542Y348525D01*
X807250Y348358D01*
X806917Y348275D01*
X806583D01*
X806250Y348358D01*
X805958Y348525D01*
X805708Y348775D01*
X805542Y349067D01*
X805500Y349400D01*
X805542Y349733D01*
X805708Y350025D01*
X805958Y350275D01*
X806250Y350442D01*
X806583Y350525D01*
X806917D01*
X807250Y350442D01*
X807542Y350275D01*
X807792Y350025D01*
X807958Y349733D01*
X808000Y349400D01*
G01X807333Y349733D02*
X808000Y350233D01*
G01Y352500D02*
X805500D01*
X806000Y352000D01*
G01X808000D02*
Y353000D01*
G01X805917Y354808D02*
X805667Y355058D01*
X805542Y355350D01*
X805500Y355683D01*
X805583Y356100D01*
X805792Y356392D01*
X806042Y356475D01*
X806292Y356433D01*
X806500Y356267D01*
X806917Y355433D01*
X807208Y355058D01*
X807625Y354808D01*
X808000Y354725D01*
Y356475D01*
G01X830500Y366000D02*
X817500D01*
G01D02*
Y352000D01*
G01D02*
X830500D01*
G01D02*
Y366000D01*
G01X802467Y381500D02*
Y384000D01*
X803508D01*
X803842Y383875D01*
X804050Y383708D01*
X804133Y383375D01*
X804050Y383042D01*
X803800Y382833D01*
X803508Y382708D01*
X802467D01*
G01X803508D02*
X804133Y381500D01*
G01X805692Y381792D02*
X805983Y381583D01*
X806317Y381500D01*
X806650Y381583D01*
X806942Y381833D01*
X807150Y382208D01*
X807233Y382583D01*
Y383042D01*
X807150Y383417D01*
X806942Y383750D01*
X806692Y383917D01*
X806400Y384000D01*
X806067Y383917D01*
X805817Y383750D01*
X805650Y383500D01*
X805567Y383167D01*
X805650Y382875D01*
X805858Y382583D01*
X806108Y382417D01*
X806400Y382375D01*
X806733Y382458D01*
X806983Y382667D01*
X807233Y383042D01*
G01X809500Y381500D02*
X809792Y381542D01*
X810125Y381667D01*
X810333Y381875D01*
X810417Y382167D01*
X810333Y382458D01*
X810083Y382708D01*
X809708Y382833D01*
X809292D01*
X809042Y382917D01*
X808833Y383125D01*
X808750Y383417D01*
X808875Y383708D01*
X809167Y383917D01*
X809500Y384000D01*
X809833Y383917D01*
X810125Y383708D01*
X810250Y383417D01*
X810167Y383125D01*
X809958Y382917D01*
X809708Y382833D01*
X809292D01*
X808917Y382708D01*
X808667Y382458D01*
X808583Y382167D01*
X808667Y381875D01*
X808875Y381667D01*
X809208Y381542D01*
X809500Y381500D01*
G01X812600Y384000D02*
X812267Y383917D01*
X812017Y383708D01*
X811850Y383458D01*
X811725Y383125D01*
X811683Y382750D01*
X811725Y382375D01*
X811850Y382042D01*
X812017Y381792D01*
X812267Y381583D01*
X812600Y381500D01*
X812933Y381583D01*
X813183Y381792D01*
X813350Y382042D01*
X813475Y382375D01*
X813517Y382750D01*
X813475Y383125D01*
X813350Y383458D01*
X813183Y383708D01*
X812933Y383917D01*
X812600Y384000D01*
G01X814783Y381875D02*
X815033Y381667D01*
X815325Y381542D01*
X815700Y381500D01*
X816075Y381583D01*
X816367Y381750D01*
X816575Y382042D01*
X816617Y382375D01*
X816533Y382708D01*
X816325Y382917D01*
X816033Y383083D01*
X815742Y383125D01*
X815450Y383083D01*
X815075Y382917D01*
X815200Y384000D01*
X816325D01*
G01X809975Y379775D02*
Y375775D01*
X817375D01*
G01X838150Y368450D02*
X842150D01*
Y375850D01*
G01X829700Y347000D02*
Y351000D01*
X822300D01*
G01X822000Y339300D02*
X826000D01*
Y346700D01*
G01X821500D02*
X817500D01*
Y339300D01*
G01X802000Y363967D02*
X799500D01*
Y365008D01*
X799625Y365342D01*
X799792Y365550D01*
X800125Y365633D01*
X800458Y365550D01*
X800667Y365300D01*
X800792Y365008D01*
Y363967D01*
G01Y365008D02*
X802000Y365633D01*
G01X801708Y367192D02*
X801917Y367483D01*
X802000Y367817D01*
X801917Y368150D01*
X801667Y368442D01*
X801292Y368650D01*
X800917Y368733D01*
X800458D01*
X800083Y368650D01*
X799750Y368442D01*
X799583Y368192D01*
X799500Y367900D01*
X799583Y367567D01*
X799750Y367317D01*
X800000Y367150D01*
X800333Y367067D01*
X800625Y367150D01*
X800917Y367358D01*
X801083Y367608D01*
X801125Y367900D01*
X801042Y368233D01*
X800833Y368483D01*
X800458Y368733D01*
G01X801625Y370083D02*
X801833Y370333D01*
X801958Y370625D01*
X802000Y371000D01*
X801917Y371375D01*
X801750Y371667D01*
X801458Y371875D01*
X801125Y371917D01*
X800792Y371833D01*
X800583Y371625D01*
X800417Y371333D01*
X800375Y371042D01*
X800417Y370750D01*
X800583Y370375D01*
X799500Y370500D01*
Y371625D01*
G01Y374100D02*
X799583Y373767D01*
X799792Y373517D01*
X800042Y373350D01*
X800375Y373225D01*
X800750Y373183D01*
X801125Y373225D01*
X801458Y373350D01*
X801708Y373517D01*
X801917Y373767D01*
X802000Y374100D01*
X801917Y374433D01*
X801708Y374683D01*
X801458Y374850D01*
X801125Y374975D01*
X800750Y375017D01*
X800375Y374975D01*
X800042Y374850D01*
X799792Y374683D01*
X799583Y374433D01*
X799500Y374100D01*
G01X800958Y376408D02*
X800667Y376700D01*
X800500Y376950D01*
X800417Y377283D01*
X800500Y377575D01*
X800667Y377783D01*
X800917Y377950D01*
X801208Y377992D01*
X801458Y377950D01*
X801708Y377783D01*
X801917Y377533D01*
X802000Y377242D01*
X801917Y376908D01*
X801667Y376617D01*
X801292Y376450D01*
X800875Y376408D01*
X800333Y376492D01*
X800042Y376617D01*
X799750Y376825D01*
X799542Y377117D01*
X799500Y377408D01*
X799583Y377700D01*
X799792Y377908D01*
G01X814500Y367300D02*
X818500D01*
Y374700D01*
G01X806000Y363967D02*
X803500D01*
Y365008D01*
X803625Y365342D01*
X803792Y365550D01*
X804125Y365633D01*
X804458Y365550D01*
X804667Y365300D01*
X804792Y365008D01*
Y363967D01*
G01Y365008D02*
X806000Y365633D01*
G01X805708Y367192D02*
X805917Y367483D01*
X806000Y367817D01*
X805917Y368150D01*
X805667Y368442D01*
X805292Y368650D01*
X804917Y368733D01*
X804458D01*
X804083Y368650D01*
X803750Y368442D01*
X803583Y368192D01*
X803500Y367900D01*
X803583Y367567D01*
X803750Y367317D01*
X804000Y367150D01*
X804333Y367067D01*
X804625Y367150D01*
X804917Y367358D01*
X805083Y367608D01*
X805125Y367900D01*
X805042Y368233D01*
X804833Y368483D01*
X804458Y368733D01*
G01X806000Y370917D02*
X805458Y371000D01*
X805000Y371125D01*
X804583Y371292D01*
X804125Y371500D01*
X803500Y371833D01*
Y370167D01*
G01X804958Y373308D02*
X804667Y373600D01*
X804500Y373850D01*
X804417Y374183D01*
X804500Y374475D01*
X804667Y374683D01*
X804917Y374850D01*
X805208Y374892D01*
X805458Y374850D01*
X805708Y374683D01*
X805917Y374433D01*
X806000Y374142D01*
X805917Y373808D01*
X805667Y373517D01*
X805292Y373350D01*
X804875Y373308D01*
X804333Y373392D01*
X804042Y373517D01*
X803750Y373725D01*
X803542Y374017D01*
X803500Y374308D01*
X803583Y374600D01*
X803792Y374808D01*
G01X806000Y377700D02*
X803500D01*
X805292Y376158D01*
Y378242D01*
G01X823000Y374700D02*
X819000D01*
Y367300D01*
G01X803834Y348483D02*
X801334D01*
Y349317D01*
X801459Y349650D01*
X801626Y349900D01*
X801876Y350108D01*
X802167Y350275D01*
X802584Y350317D01*
X803001Y350275D01*
X803292Y350108D01*
X803542Y349900D01*
X803709Y349650D01*
X803834Y349317D01*
Y348483D01*
G01X801751Y351708D02*
X801501Y351958D01*
X801376Y352250D01*
X801334Y352583D01*
X801417Y353000D01*
X801626Y353292D01*
X801876Y353375D01*
X802126Y353333D01*
X802334Y353167D01*
X802751Y352333D01*
X803042Y351958D01*
X803459Y351708D01*
X803834Y351625D01*
Y353375D01*
G01X801751Y354808D02*
X801501Y355058D01*
X801376Y355350D01*
X801334Y355683D01*
X801417Y356100D01*
X801626Y356392D01*
X801876Y356475D01*
X802126Y356433D01*
X802334Y356267D01*
X802751Y355433D01*
X803042Y355058D01*
X803459Y354808D01*
X803834Y354725D01*
Y356475D01*
G01X809500Y344000D02*
Y360100D01*
G01X816500Y344000D02*
X809500D01*
G01X816500Y360100D02*
Y344000D01*
G01X809500Y360100D02*
X816500D01*
G01X825367Y728927D02*
X825242Y728677D01*
X825159Y728385D01*
Y728052D01*
X825284Y727677D01*
X825492Y727385D01*
X825742Y727177D01*
X826159Y727010D01*
X826534Y726968D01*
X826909Y727052D01*
X827159Y727177D01*
X827409Y727427D01*
X827576Y727718D01*
X827659Y728010D01*
Y728302D01*
X827576Y728593D01*
X827451Y728843D01*
X827284Y729052D01*
G01X827159Y730193D02*
X827451Y730443D01*
X827617Y730777D01*
X827659Y731152D01*
X827617Y731485D01*
X827409Y731818D01*
X827159Y732027D01*
X826909Y732068D01*
X826617Y731985D01*
X826409Y731693D01*
X826326Y731402D01*
Y731027D01*
G01Y731402D02*
X826201Y731652D01*
X825992Y731860D01*
X825742Y731943D01*
X825492Y731860D01*
X825284Y731652D01*
X825159Y731277D01*
X825201Y730902D01*
X825367Y730527D01*
G01X827659Y734210D02*
X827617Y734502D01*
X827492Y734835D01*
X827284Y735043D01*
X826992Y735127D01*
X826701Y735043D01*
X826451Y734793D01*
X826326Y734418D01*
Y734002D01*
X826242Y733752D01*
X826034Y733543D01*
X825742Y733460D01*
X825451Y733585D01*
X825242Y733877D01*
X825159Y734210D01*
X825242Y734543D01*
X825451Y734835D01*
X825742Y734960D01*
X826034Y734877D01*
X826242Y734668D01*
X826326Y734418D01*
Y734002D01*
X826451Y733627D01*
X826701Y733377D01*
X826992Y733293D01*
X827284Y733377D01*
X827492Y733585D01*
X827617Y733918D01*
X827659Y734210D01*
G01X827284Y736393D02*
X827492Y736643D01*
X827617Y736935D01*
X827659Y737310D01*
X827576Y737685D01*
X827409Y737977D01*
X827117Y738185D01*
X826784Y738227D01*
X826451Y738143D01*
X826242Y737935D01*
X826076Y737643D01*
X826034Y737352D01*
X826076Y737060D01*
X826242Y736685D01*
X825159Y736810D01*
Y737935D01*
G01X823500Y785900D02*
Y772900D01*
G01D02*
X837500D01*
G01D02*
Y785900D01*
G01X808000Y755400D02*
X807958Y755067D01*
X807792Y754775D01*
X807542Y754525D01*
X807250Y754358D01*
X806917Y754275D01*
X806583D01*
X806250Y754358D01*
X805958Y754525D01*
X805708Y754775D01*
X805542Y755067D01*
X805500Y755400D01*
X805542Y755733D01*
X805708Y756025D01*
X805958Y756275D01*
X806250Y756442D01*
X806583Y756525D01*
X806917D01*
X807250Y756442D01*
X807542Y756275D01*
X807792Y756025D01*
X807958Y755733D01*
X808000Y755400D01*
G01X807333Y755733D02*
X808000Y756233D01*
G01Y758500D02*
X805500D01*
X806000Y758000D01*
G01X808000D02*
Y759000D01*
G01Y761600D02*
X805500D01*
X806000Y761100D01*
G01X808000D02*
Y762100D01*
G01X830500Y771500D02*
X817500D01*
G01D02*
Y757500D01*
G01D02*
X830500D01*
G01D02*
Y771500D01*
G01X838150Y773950D02*
X842150D01*
Y781350D01*
G01X818287Y740201D02*
Y742701D01*
X819328D01*
X819662Y742576D01*
X819870Y742409D01*
X819953Y742076D01*
X819870Y741743D01*
X819620Y741534D01*
X819328Y741409D01*
X818287D01*
G01X819328D02*
X819953Y740201D01*
G01X822220D02*
Y742701D01*
X821720Y742201D01*
G01Y740201D02*
X822720D01*
G01X825820D02*
Y742701D01*
X824278Y740909D01*
X826362D01*
G01X828420Y740201D02*
Y742701D01*
X827920Y742201D01*
G01Y740201D02*
X828920D01*
G01X829700Y752500D02*
Y756500D01*
X822300D01*
G01X823659Y727177D02*
X821159D01*
Y728218D01*
X821284Y728552D01*
X821451Y728760D01*
X821784Y728843D01*
X822117Y728760D01*
X822326Y728510D01*
X822451Y728218D01*
Y727177D01*
G01Y728218D02*
X823659Y728843D01*
G01X823284Y730193D02*
X823492Y730443D01*
X823617Y730735D01*
X823659Y731110D01*
X823576Y731485D01*
X823409Y731777D01*
X823117Y731985D01*
X822784Y732027D01*
X822451Y731943D01*
X822242Y731735D01*
X822076Y731443D01*
X822034Y731152D01*
X822076Y730860D01*
X822242Y730485D01*
X821159Y730610D01*
Y731735D01*
G01X822617Y733418D02*
X822326Y733710D01*
X822159Y733960D01*
X822076Y734293D01*
X822159Y734585D01*
X822326Y734793D01*
X822576Y734960D01*
X822867Y735002D01*
X823117Y734960D01*
X823367Y734793D01*
X823576Y734543D01*
X823659Y734252D01*
X823576Y733918D01*
X823326Y733627D01*
X822951Y733460D01*
X822534Y733418D01*
X821992Y733502D01*
X821701Y733627D01*
X821409Y733835D01*
X821201Y734127D01*
X821159Y734418D01*
X821242Y734710D01*
X821451Y734918D01*
G01X823367Y736602D02*
X823576Y736893D01*
X823659Y737227D01*
X823576Y737560D01*
X823326Y737852D01*
X822951Y738060D01*
X822576Y738143D01*
X822117D01*
X821742Y738060D01*
X821409Y737852D01*
X821242Y737602D01*
X821159Y737310D01*
X821242Y736977D01*
X821409Y736727D01*
X821659Y736560D01*
X821992Y736477D01*
X822284Y736560D01*
X822576Y736768D01*
X822742Y737018D01*
X822784Y737310D01*
X822701Y737643D01*
X822492Y737893D01*
X822117Y738143D01*
G01X822000Y744800D02*
X826000D01*
Y752200D01*
G01X838167Y724875D02*
X838375Y725208D01*
X838500Y725583D01*
Y725917D01*
X838375Y726250D01*
X838167Y726500D01*
X837875Y726625D01*
X837583Y726542D01*
X837333Y726333D01*
X837167Y725958D01*
X837083Y725458D01*
X836917Y725167D01*
X836625Y725042D01*
X836333Y725125D01*
X836125Y725333D01*
X836000Y725625D01*
Y725917D01*
X836083Y726208D01*
X836292Y726458D01*
G01X838500Y728017D02*
X836000D01*
Y729058D01*
X836125Y729392D01*
X836292Y729600D01*
X836625Y729683D01*
X836958Y729600D01*
X837167Y729350D01*
X837292Y729058D01*
Y728017D01*
G01Y729058D02*
X838500Y729683D01*
G01Y731950D02*
X836000D01*
X836500Y731450D01*
G01X838500D02*
Y732450D01*
G01X836000Y735050D02*
X836083Y734717D01*
X836292Y734467D01*
X836542Y734300D01*
X836875Y734175D01*
X837250Y734133D01*
X837625Y734175D01*
X837958Y734300D01*
X838208Y734467D01*
X838417Y734717D01*
X838500Y735050D01*
X838417Y735383D01*
X838208Y735633D01*
X837958Y735800D01*
X837625Y735925D01*
X837250Y735967D01*
X836875Y735925D01*
X836542Y735800D01*
X836292Y735633D01*
X836083Y735383D01*
X836000Y735050D01*
G01X838208Y737442D02*
X838417Y737733D01*
X838500Y738067D01*
X838417Y738400D01*
X838167Y738692D01*
X837792Y738900D01*
X837417Y738983D01*
X836958D01*
X836583Y738900D01*
X836250Y738692D01*
X836083Y738442D01*
X836000Y738150D01*
X836083Y737817D01*
X836250Y737567D01*
X836500Y737400D01*
X836833Y737317D01*
X837125Y737400D01*
X837417Y737608D01*
X837583Y737858D01*
X837625Y738150D01*
X837542Y738483D01*
X837333Y738733D01*
X836958Y738983D01*
G01X838500Y741167D02*
X837958Y741250D01*
X837500Y741375D01*
X837083Y741542D01*
X836625Y741750D01*
X836000Y742083D01*
Y740417D01*
G01X819159Y727177D02*
X816659D01*
Y728218D01*
X816784Y728552D01*
X816951Y728760D01*
X817284Y728843D01*
X817617Y728760D01*
X817826Y728510D01*
X817951Y728218D01*
Y727177D01*
G01Y728218D02*
X819159Y728843D01*
G01X818784Y730193D02*
X818992Y730443D01*
X819117Y730735D01*
X819159Y731110D01*
X819076Y731485D01*
X818909Y731777D01*
X818617Y731985D01*
X818284Y732027D01*
X817951Y731943D01*
X817742Y731735D01*
X817576Y731443D01*
X817534Y731152D01*
X817576Y730860D01*
X817742Y730485D01*
X816659Y730610D01*
Y731735D01*
G01X818784Y733293D02*
X818992Y733543D01*
X819117Y733835D01*
X819159Y734210D01*
X819076Y734585D01*
X818909Y734877D01*
X818617Y735085D01*
X818284Y735127D01*
X817951Y735043D01*
X817742Y734835D01*
X817576Y734543D01*
X817534Y734252D01*
X817576Y733960D01*
X817742Y733585D01*
X816659Y733710D01*
Y734835D01*
G01X819159Y737810D02*
X816659D01*
X818451Y736268D01*
Y738352D01*
G01X821500Y752200D02*
X817500D01*
Y744800D01*
G01X803500Y767467D02*
X801000D01*
Y768508D01*
X801125Y768842D01*
X801292Y769050D01*
X801625Y769133D01*
X801958Y769050D01*
X802167Y768800D01*
X802292Y768508D01*
Y767467D01*
G01Y768508D02*
X803500Y769133D01*
G01X803208Y770692D02*
X803417Y770983D01*
X803500Y771317D01*
X803417Y771650D01*
X803167Y771942D01*
X802792Y772150D01*
X802417Y772233D01*
X801958D01*
X801583Y772150D01*
X801250Y771942D01*
X801083Y771692D01*
X801000Y771400D01*
X801083Y771067D01*
X801250Y770817D01*
X801500Y770650D01*
X801833Y770567D01*
X802125Y770650D01*
X802417Y770858D01*
X802583Y771108D01*
X802625Y771400D01*
X802542Y771733D01*
X802333Y771983D01*
X801958Y772233D01*
G01X803125Y773583D02*
X803333Y773833D01*
X803458Y774125D01*
X803500Y774500D01*
X803417Y774875D01*
X803250Y775167D01*
X802958Y775375D01*
X802625Y775417D01*
X802292Y775333D01*
X802083Y775125D01*
X801917Y774833D01*
X801875Y774542D01*
X801917Y774250D01*
X802083Y773875D01*
X801000Y774000D01*
Y775125D01*
G01Y777600D02*
X801083Y777267D01*
X801292Y777017D01*
X801542Y776850D01*
X801875Y776725D01*
X802250Y776683D01*
X802625Y776725D01*
X802958Y776850D01*
X803208Y777017D01*
X803417Y777267D01*
X803500Y777600D01*
X803417Y777933D01*
X803208Y778183D01*
X802958Y778350D01*
X802625Y778475D01*
X802250Y778517D01*
X801875Y778475D01*
X801542Y778350D01*
X801292Y778183D01*
X801083Y777933D01*
X801000Y777600D01*
G01X803000Y779783D02*
X803292Y780033D01*
X803458Y780367D01*
X803500Y780742D01*
X803458Y781075D01*
X803250Y781408D01*
X803000Y781617D01*
X802750Y781658D01*
X802458Y781575D01*
X802250Y781283D01*
X802167Y780992D01*
Y780617D01*
G01Y780992D02*
X802042Y781242D01*
X801833Y781450D01*
X801583Y781533D01*
X801333Y781450D01*
X801125Y781242D01*
X801000Y780867D01*
X801042Y780492D01*
X801208Y780117D01*
G01X814500Y772800D02*
X818500D01*
Y780200D01*
G01X807500Y767467D02*
X805000D01*
Y768508D01*
X805125Y768842D01*
X805292Y769050D01*
X805625Y769133D01*
X805958Y769050D01*
X806167Y768800D01*
X806292Y768508D01*
Y767467D01*
G01Y768508D02*
X807500Y769133D01*
G01X807208Y770692D02*
X807417Y770983D01*
X807500Y771317D01*
X807417Y771650D01*
X807167Y771942D01*
X806792Y772150D01*
X806417Y772233D01*
X805958D01*
X805583Y772150D01*
X805250Y771942D01*
X805083Y771692D01*
X805000Y771400D01*
X805083Y771067D01*
X805250Y770817D01*
X805500Y770650D01*
X805833Y770567D01*
X806125Y770650D01*
X806417Y770858D01*
X806583Y771108D01*
X806625Y771400D01*
X806542Y771733D01*
X806333Y771983D01*
X805958Y772233D01*
G01X807500Y774417D02*
X806958Y774500D01*
X806500Y774625D01*
X806083Y774792D01*
X805625Y775000D01*
X805000Y775333D01*
Y773667D01*
G01X806458Y776808D02*
X806167Y777100D01*
X806000Y777350D01*
X805917Y777683D01*
X806000Y777975D01*
X806167Y778183D01*
X806417Y778350D01*
X806708Y778392D01*
X806958Y778350D01*
X807208Y778183D01*
X807417Y777933D01*
X807500Y777642D01*
X807417Y777308D01*
X807167Y777017D01*
X806792Y776850D01*
X806375Y776808D01*
X805833Y776892D01*
X805542Y777017D01*
X805250Y777225D01*
X805042Y777517D01*
X805000Y777808D01*
X805083Y778100D01*
X805292Y778308D01*
G01X807000Y779783D02*
X807292Y780033D01*
X807458Y780367D01*
X807500Y780742D01*
X807458Y781075D01*
X807250Y781408D01*
X807000Y781617D01*
X806750Y781658D01*
X806458Y781575D01*
X806250Y781283D01*
X806167Y780992D01*
Y780617D01*
G01Y780992D02*
X806042Y781242D01*
X805833Y781450D01*
X805583Y781533D01*
X805333Y781450D01*
X805125Y781242D01*
X805000Y780867D01*
X805042Y780492D01*
X805208Y780117D01*
G01X823000Y780200D02*
X819000D01*
Y772800D01*
G01X803834Y754483D02*
X801334D01*
Y755317D01*
X801459Y755650D01*
X801626Y755900D01*
X801876Y756108D01*
X802167Y756275D01*
X802584Y756317D01*
X803001Y756275D01*
X803292Y756108D01*
X803542Y755900D01*
X803709Y755650D01*
X803834Y755317D01*
Y754483D01*
G01X801751Y757708D02*
X801501Y757958D01*
X801376Y758250D01*
X801334Y758583D01*
X801417Y759000D01*
X801626Y759292D01*
X801876Y759375D01*
X802126Y759333D01*
X802334Y759167D01*
X802751Y758333D01*
X803042Y757958D01*
X803459Y757708D01*
X803834Y757625D01*
Y759375D01*
G01Y761600D02*
X801334D01*
X801834Y761100D01*
G01X803834D02*
Y762100D01*
G01X809500Y749500D02*
Y765600D01*
G01X816500Y749500D02*
X809500D01*
G01X816500Y765600D02*
Y749500D01*
G01X809500Y765600D02*
X816500D01*
G01X823900Y787500D02*
X823567Y787542D01*
X823275Y787708D01*
X823025Y787958D01*
X822858Y788250D01*
X822775Y788583D01*
Y788917D01*
X822858Y789250D01*
X823025Y789542D01*
X823275Y789792D01*
X823567Y789958D01*
X823900Y790000D01*
X824233Y789958D01*
X824525Y789792D01*
X824775Y789542D01*
X824942Y789250D01*
X825025Y788917D01*
Y788583D01*
X824942Y788250D01*
X824775Y787958D01*
X824525Y787708D01*
X824233Y787542D01*
X823900Y787500D01*
G01X824233Y788167D02*
X824733Y787500D01*
G01X827500D02*
Y790000D01*
X825958Y788208D01*
X828042D01*
G01X829308Y789583D02*
X829558Y789833D01*
X829850Y789958D01*
X830183Y790000D01*
X830600Y789917D01*
X830892Y789708D01*
X830975Y789458D01*
X830933Y789208D01*
X830767Y789000D01*
X829933Y788583D01*
X829558Y788292D01*
X829308Y787875D01*
X829225Y787500D01*
X830975D01*
G01X837500Y785900D02*
X823500D01*
G01X802967Y787000D02*
Y789500D01*
X804008D01*
X804342Y789375D01*
X804550Y789208D01*
X804633Y788875D01*
X804550Y788542D01*
X804300Y788333D01*
X804008Y788208D01*
X802967D01*
G01X804008D02*
X804633Y787000D01*
G01X806192Y787292D02*
X806483Y787083D01*
X806817Y787000D01*
X807150Y787083D01*
X807442Y787333D01*
X807650Y787708D01*
X807733Y788083D01*
Y788542D01*
X807650Y788917D01*
X807442Y789250D01*
X807192Y789417D01*
X806900Y789500D01*
X806567Y789417D01*
X806317Y789250D01*
X806150Y789000D01*
X806067Y788667D01*
X806150Y788375D01*
X806358Y788083D01*
X806608Y787917D01*
X806900Y787875D01*
X807233Y787958D01*
X807483Y788167D01*
X807733Y788542D01*
G01X809917Y787000D02*
X810000Y787542D01*
X810125Y788000D01*
X810292Y788417D01*
X810500Y788875D01*
X810833Y789500D01*
X809167D01*
G01X812392Y787292D02*
X812683Y787083D01*
X813017Y787000D01*
X813350Y787083D01*
X813642Y787333D01*
X813850Y787708D01*
X813933Y788083D01*
Y788542D01*
X813850Y788917D01*
X813642Y789250D01*
X813392Y789417D01*
X813100Y789500D01*
X812767Y789417D01*
X812517Y789250D01*
X812350Y789000D01*
X812267Y788667D01*
X812350Y788375D01*
X812558Y788083D01*
X812808Y787917D01*
X813100Y787875D01*
X813433Y787958D01*
X813683Y788167D01*
X813933Y788542D01*
G01X815492Y787292D02*
X815783Y787083D01*
X816117Y787000D01*
X816450Y787083D01*
X816742Y787333D01*
X816950Y787708D01*
X817033Y788083D01*
Y788542D01*
X816950Y788917D01*
X816742Y789250D01*
X816492Y789417D01*
X816200Y789500D01*
X815867Y789417D01*
X815617Y789250D01*
X815450Y789000D01*
X815367Y788667D01*
X815450Y788375D01*
X815658Y788083D01*
X815908Y787917D01*
X816200Y787875D01*
X816533Y787958D01*
X816783Y788167D01*
X817033Y788542D01*
G01X809975Y785275D02*
Y781275D01*
X817375D01*
G01X824717Y1133657D02*
X824592Y1133407D01*
X824509Y1133115D01*
Y1132782D01*
X824634Y1132407D01*
X824842Y1132115D01*
X825092Y1131907D01*
X825509Y1131740D01*
X825884Y1131698D01*
X826259Y1131782D01*
X826509Y1131907D01*
X826759Y1132157D01*
X826926Y1132448D01*
X827009Y1132740D01*
Y1133032D01*
X826926Y1133323D01*
X826801Y1133573D01*
X826634Y1133782D01*
G01X826509Y1134923D02*
X826801Y1135173D01*
X826967Y1135507D01*
X827009Y1135882D01*
X826967Y1136215D01*
X826759Y1136548D01*
X826509Y1136757D01*
X826259Y1136798D01*
X825967Y1136715D01*
X825759Y1136423D01*
X825676Y1136132D01*
Y1135757D01*
G01Y1136132D02*
X825551Y1136382D01*
X825342Y1136590D01*
X825092Y1136673D01*
X824842Y1136590D01*
X824634Y1136382D01*
X824509Y1136007D01*
X824551Y1135632D01*
X824717Y1135257D01*
G01X827009Y1138940D02*
X826967Y1139232D01*
X826842Y1139565D01*
X826634Y1139773D01*
X826342Y1139857D01*
X826051Y1139773D01*
X825801Y1139523D01*
X825676Y1139148D01*
Y1138732D01*
X825592Y1138482D01*
X825384Y1138273D01*
X825092Y1138190D01*
X824801Y1138315D01*
X824592Y1138607D01*
X824509Y1138940D01*
X824592Y1139273D01*
X824801Y1139565D01*
X825092Y1139690D01*
X825384Y1139607D01*
X825592Y1139398D01*
X825676Y1139148D01*
Y1138732D01*
X825801Y1138357D01*
X826051Y1138107D01*
X826342Y1138023D01*
X826634Y1138107D01*
X826842Y1138315D01*
X826967Y1138648D01*
X827009Y1138940D01*
G01Y1142540D02*
X824509D01*
X826301Y1140998D01*
Y1143082D01*
G01X823009Y1131907D02*
X820509D01*
Y1132948D01*
X820634Y1133282D01*
X820801Y1133490D01*
X821134Y1133573D01*
X821467Y1133490D01*
X821676Y1133240D01*
X821801Y1132948D01*
Y1131907D01*
G01Y1132948D02*
X823009Y1133573D01*
G01X822634Y1134923D02*
X822842Y1135173D01*
X822967Y1135465D01*
X823009Y1135840D01*
X822926Y1136215D01*
X822759Y1136507D01*
X822467Y1136715D01*
X822134Y1136757D01*
X821801Y1136673D01*
X821592Y1136465D01*
X821426Y1136173D01*
X821384Y1135882D01*
X821426Y1135590D01*
X821592Y1135215D01*
X820509Y1135340D01*
Y1136465D01*
G01X821967Y1138148D02*
X821676Y1138440D01*
X821509Y1138690D01*
X821426Y1139023D01*
X821509Y1139315D01*
X821676Y1139523D01*
X821926Y1139690D01*
X822217Y1139732D01*
X822467Y1139690D01*
X822717Y1139523D01*
X822926Y1139273D01*
X823009Y1138982D01*
X822926Y1138648D01*
X822676Y1138357D01*
X822301Y1138190D01*
X821884Y1138148D01*
X821342Y1138232D01*
X821051Y1138357D01*
X820759Y1138565D01*
X820551Y1138857D01*
X820509Y1139148D01*
X820592Y1139440D01*
X820801Y1139648D01*
G01X823009Y1142040D02*
X822967Y1142332D01*
X822842Y1142665D01*
X822634Y1142873D01*
X822342Y1142957D01*
X822051Y1142873D01*
X821801Y1142623D01*
X821676Y1142248D01*
Y1141832D01*
X821592Y1141582D01*
X821384Y1141373D01*
X821092Y1141290D01*
X820801Y1141415D01*
X820592Y1141707D01*
X820509Y1142040D01*
X820592Y1142373D01*
X820801Y1142665D01*
X821092Y1142790D01*
X821384Y1142707D01*
X821592Y1142498D01*
X821676Y1142248D01*
Y1141832D01*
X821801Y1141457D01*
X822051Y1141207D01*
X822342Y1141123D01*
X822634Y1141207D01*
X822842Y1141415D01*
X822967Y1141748D01*
X823009Y1142040D01*
G01X836667Y1130875D02*
X836875Y1131208D01*
X837000Y1131583D01*
Y1131917D01*
X836875Y1132250D01*
X836667Y1132500D01*
X836375Y1132625D01*
X836083Y1132542D01*
X835833Y1132333D01*
X835667Y1131958D01*
X835583Y1131458D01*
X835417Y1131167D01*
X835125Y1131042D01*
X834833Y1131125D01*
X834625Y1131333D01*
X834500Y1131625D01*
Y1131917D01*
X834583Y1132208D01*
X834792Y1132458D01*
G01X837000Y1134017D02*
X834500D01*
Y1135058D01*
X834625Y1135392D01*
X834792Y1135600D01*
X835125Y1135683D01*
X835458Y1135600D01*
X835667Y1135350D01*
X835792Y1135058D01*
Y1134017D01*
G01Y1135058D02*
X837000Y1135683D01*
G01Y1137950D02*
X834500D01*
X835000Y1137450D01*
G01X837000D02*
Y1138450D01*
G01X834500Y1141050D02*
X834583Y1140717D01*
X834792Y1140467D01*
X835042Y1140300D01*
X835375Y1140175D01*
X835750Y1140133D01*
X836125Y1140175D01*
X836458Y1140300D01*
X836708Y1140467D01*
X836917Y1140717D01*
X837000Y1141050D01*
X836917Y1141383D01*
X836708Y1141633D01*
X836458Y1141800D01*
X836125Y1141925D01*
X835750Y1141967D01*
X835375Y1141925D01*
X835042Y1141800D01*
X834792Y1141633D01*
X834583Y1141383D01*
X834500Y1141050D01*
G01X836708Y1143442D02*
X836917Y1143733D01*
X837000Y1144067D01*
X836917Y1144400D01*
X836667Y1144692D01*
X836292Y1144900D01*
X835917Y1144983D01*
X835458D01*
X835083Y1144900D01*
X834750Y1144692D01*
X834583Y1144442D01*
X834500Y1144150D01*
X834583Y1143817D01*
X834750Y1143567D01*
X835000Y1143400D01*
X835333Y1143317D01*
X835625Y1143400D01*
X835917Y1143608D01*
X836083Y1143858D01*
X836125Y1144150D01*
X836042Y1144483D01*
X835833Y1144733D01*
X835458Y1144983D01*
G01X836625Y1146333D02*
X836833Y1146583D01*
X836958Y1146875D01*
X837000Y1147250D01*
X836917Y1147625D01*
X836750Y1147917D01*
X836458Y1148125D01*
X836125Y1148167D01*
X835792Y1148083D01*
X835583Y1147875D01*
X835417Y1147583D01*
X835375Y1147292D01*
X835417Y1147000D01*
X835583Y1146625D01*
X834500Y1146750D01*
Y1147875D01*
G01X840667Y1130875D02*
X840875Y1131208D01*
X841000Y1131583D01*
Y1131917D01*
X840875Y1132250D01*
X840667Y1132500D01*
X840375Y1132625D01*
X840083Y1132542D01*
X839833Y1132333D01*
X839667Y1131958D01*
X839583Y1131458D01*
X839417Y1131167D01*
X839125Y1131042D01*
X838833Y1131125D01*
X838625Y1131333D01*
X838500Y1131625D01*
Y1131917D01*
X838583Y1132208D01*
X838792Y1132458D01*
G01X841000Y1134017D02*
X838500D01*
Y1135058D01*
X838625Y1135392D01*
X838792Y1135600D01*
X839125Y1135683D01*
X839458Y1135600D01*
X839667Y1135350D01*
X839792Y1135058D01*
Y1134017D01*
G01Y1135058D02*
X841000Y1135683D01*
G01Y1137950D02*
X838500D01*
X839000Y1137450D01*
G01X841000D02*
Y1138450D01*
G01X838500Y1141050D02*
X838583Y1140717D01*
X838792Y1140467D01*
X839042Y1140300D01*
X839375Y1140175D01*
X839750Y1140133D01*
X840125Y1140175D01*
X840458Y1140300D01*
X840708Y1140467D01*
X840917Y1140717D01*
X841000Y1141050D01*
X840917Y1141383D01*
X840708Y1141633D01*
X840458Y1141800D01*
X840125Y1141925D01*
X839750Y1141967D01*
X839375Y1141925D01*
X839042Y1141800D01*
X838792Y1141633D01*
X838583Y1141383D01*
X838500Y1141050D01*
G01X840708Y1143442D02*
X840917Y1143733D01*
X841000Y1144067D01*
X840917Y1144400D01*
X840667Y1144692D01*
X840292Y1144900D01*
X839917Y1144983D01*
X839458D01*
X839083Y1144900D01*
X838750Y1144692D01*
X838583Y1144442D01*
X838500Y1144150D01*
X838583Y1143817D01*
X838750Y1143567D01*
X839000Y1143400D01*
X839333Y1143317D01*
X839625Y1143400D01*
X839917Y1143608D01*
X840083Y1143858D01*
X840125Y1144150D01*
X840042Y1144483D01*
X839833Y1144733D01*
X839458Y1144983D01*
G01X839958Y1146458D02*
X839667Y1146750D01*
X839500Y1147000D01*
X839417Y1147333D01*
X839500Y1147625D01*
X839667Y1147833D01*
X839917Y1148000D01*
X840208Y1148042D01*
X840458Y1148000D01*
X840708Y1147833D01*
X840917Y1147583D01*
X841000Y1147292D01*
X840917Y1146958D01*
X840667Y1146667D01*
X840292Y1146500D01*
X839875Y1146458D01*
X839333Y1146542D01*
X839042Y1146667D01*
X838750Y1146875D01*
X838542Y1147167D01*
X838500Y1147458D01*
X838583Y1147750D01*
X838792Y1147958D01*
G01X818509Y1131907D02*
X816009D01*
Y1132948D01*
X816134Y1133282D01*
X816301Y1133490D01*
X816634Y1133573D01*
X816967Y1133490D01*
X817176Y1133240D01*
X817301Y1132948D01*
Y1131907D01*
G01Y1132948D02*
X818509Y1133573D01*
G01X818134Y1134923D02*
X818342Y1135173D01*
X818467Y1135465D01*
X818509Y1135840D01*
X818426Y1136215D01*
X818259Y1136507D01*
X817967Y1136715D01*
X817634Y1136757D01*
X817301Y1136673D01*
X817092Y1136465D01*
X816926Y1136173D01*
X816884Y1135882D01*
X816926Y1135590D01*
X817092Y1135215D01*
X816009Y1135340D01*
Y1136465D01*
G01X818134Y1138023D02*
X818342Y1138273D01*
X818467Y1138565D01*
X818509Y1138940D01*
X818426Y1139315D01*
X818259Y1139607D01*
X817967Y1139815D01*
X817634Y1139857D01*
X817301Y1139773D01*
X817092Y1139565D01*
X816926Y1139273D01*
X816884Y1138982D01*
X816926Y1138690D01*
X817092Y1138315D01*
X816009Y1138440D01*
Y1139565D01*
G01X818009Y1141123D02*
X818301Y1141373D01*
X818467Y1141707D01*
X818509Y1142082D01*
X818467Y1142415D01*
X818259Y1142748D01*
X818009Y1142957D01*
X817759Y1142998D01*
X817467Y1142915D01*
X817259Y1142623D01*
X817176Y1142332D01*
Y1141957D01*
G01Y1142332D02*
X817051Y1142582D01*
X816842Y1142790D01*
X816592Y1142873D01*
X816342Y1142790D01*
X816134Y1142582D01*
X816009Y1142207D01*
X816051Y1141832D01*
X816217Y1141457D01*
G01X824900Y1193000D02*
X824567Y1193042D01*
X824275Y1193208D01*
X824025Y1193458D01*
X823858Y1193750D01*
X823775Y1194083D01*
Y1194417D01*
X823858Y1194750D01*
X824025Y1195042D01*
X824275Y1195292D01*
X824567Y1195458D01*
X824900Y1195500D01*
X825233Y1195458D01*
X825525Y1195292D01*
X825775Y1195042D01*
X825942Y1194750D01*
X826025Y1194417D01*
Y1194083D01*
X825942Y1193750D01*
X825775Y1193458D01*
X825525Y1193208D01*
X825233Y1193042D01*
X824900Y1193000D01*
G01X825233Y1193667D02*
X825733Y1193000D01*
G01X827083Y1193500D02*
X827333Y1193208D01*
X827667Y1193042D01*
X828042Y1193000D01*
X828375Y1193042D01*
X828708Y1193250D01*
X828917Y1193500D01*
X828958Y1193750D01*
X828875Y1194042D01*
X828583Y1194250D01*
X828292Y1194333D01*
X827917D01*
G01X828292D02*
X828542Y1194458D01*
X828750Y1194667D01*
X828833Y1194917D01*
X828750Y1195167D01*
X828542Y1195375D01*
X828167Y1195500D01*
X827792Y1195458D01*
X827417Y1195292D01*
G01X830308Y1194042D02*
X830600Y1194333D01*
X830850Y1194500D01*
X831183Y1194583D01*
X831475Y1194500D01*
X831683Y1194333D01*
X831850Y1194083D01*
X831892Y1193792D01*
X831850Y1193542D01*
X831683Y1193292D01*
X831433Y1193083D01*
X831142Y1193000D01*
X830808Y1193083D01*
X830517Y1193333D01*
X830350Y1193708D01*
X830308Y1194125D01*
X830392Y1194667D01*
X830517Y1194958D01*
X830725Y1195250D01*
X831017Y1195458D01*
X831308Y1195500D01*
X831600Y1195417D01*
X831808Y1195208D01*
G01X823500Y1191400D02*
Y1178400D01*
G01D02*
X837500D01*
G01D02*
Y1191400D01*
G01D02*
X823500D01*
G01X808000Y1160900D02*
X807958Y1160567D01*
X807792Y1160275D01*
X807542Y1160025D01*
X807250Y1159858D01*
X806917Y1159775D01*
X806583D01*
X806250Y1159858D01*
X805958Y1160025D01*
X805708Y1160275D01*
X805542Y1160567D01*
X805500Y1160900D01*
X805542Y1161233D01*
X805708Y1161525D01*
X805958Y1161775D01*
X806250Y1161942D01*
X806583Y1162025D01*
X806917D01*
X807250Y1161942D01*
X807542Y1161775D01*
X807792Y1161525D01*
X807958Y1161233D01*
X808000Y1160900D01*
G01X807333Y1161233D02*
X808000Y1161733D01*
G01Y1164000D02*
X805500D01*
X806000Y1163500D01*
G01X808000D02*
Y1164500D01*
G01X805500Y1167100D02*
X805583Y1166767D01*
X805792Y1166517D01*
X806042Y1166350D01*
X806375Y1166225D01*
X806750Y1166183D01*
X807125Y1166225D01*
X807458Y1166350D01*
X807708Y1166517D01*
X807917Y1166767D01*
X808000Y1167100D01*
X807917Y1167433D01*
X807708Y1167683D01*
X807458Y1167850D01*
X807125Y1167975D01*
X806750Y1168017D01*
X806375Y1167975D01*
X806042Y1167850D01*
X805792Y1167683D01*
X805583Y1167433D01*
X805500Y1167100D01*
G01X830500Y1177000D02*
X817500D01*
G01D02*
Y1163000D01*
G01D02*
X830500D01*
G01D02*
Y1177000D01*
G01X804467Y1192400D02*
Y1194900D01*
X805508D01*
X805842Y1194775D01*
X806050Y1194608D01*
X806133Y1194275D01*
X806050Y1193942D01*
X805800Y1193733D01*
X805508Y1193608D01*
X804467D01*
G01X805508D02*
X806133Y1192400D01*
G01X807692Y1192692D02*
X807983Y1192483D01*
X808317Y1192400D01*
X808650Y1192483D01*
X808942Y1192733D01*
X809150Y1193108D01*
X809233Y1193483D01*
Y1193942D01*
X809150Y1194317D01*
X808942Y1194650D01*
X808692Y1194817D01*
X808400Y1194900D01*
X808067Y1194817D01*
X807817Y1194650D01*
X807650Y1194400D01*
X807567Y1194067D01*
X807650Y1193775D01*
X807858Y1193483D01*
X808108Y1193317D01*
X808400Y1193275D01*
X808733Y1193358D01*
X808983Y1193567D01*
X809233Y1193942D01*
G01X811417Y1192400D02*
X811500Y1192942D01*
X811625Y1193400D01*
X811792Y1193817D01*
X812000Y1194275D01*
X812333Y1194900D01*
X810667D01*
G01X813892Y1192692D02*
X814183Y1192483D01*
X814517Y1192400D01*
X814850Y1192483D01*
X815142Y1192733D01*
X815350Y1193108D01*
X815433Y1193483D01*
Y1193942D01*
X815350Y1194317D01*
X815142Y1194650D01*
X814892Y1194817D01*
X814600Y1194900D01*
X814267Y1194817D01*
X814017Y1194650D01*
X813850Y1194400D01*
X813767Y1194067D01*
X813850Y1193775D01*
X814058Y1193483D01*
X814308Y1193317D01*
X814600Y1193275D01*
X814933Y1193358D01*
X815183Y1193567D01*
X815433Y1193942D01*
G01X816783Y1192900D02*
X817033Y1192608D01*
X817367Y1192442D01*
X817742Y1192400D01*
X818075Y1192442D01*
X818408Y1192650D01*
X818617Y1192900D01*
X818658Y1193150D01*
X818575Y1193442D01*
X818283Y1193650D01*
X817992Y1193733D01*
X817617D01*
G01X817992D02*
X818242Y1193858D01*
X818450Y1194067D01*
X818533Y1194317D01*
X818450Y1194567D01*
X818242Y1194775D01*
X817867Y1194900D01*
X817492Y1194858D01*
X817117Y1194692D01*
G01X809975Y1190775D02*
Y1186775D01*
X817375D01*
G01X838150Y1179450D02*
X842150D01*
Y1186850D01*
G01X816517Y1145500D02*
Y1148000D01*
X817558D01*
X817892Y1147875D01*
X818100Y1147708D01*
X818183Y1147375D01*
X818100Y1147042D01*
X817850Y1146833D01*
X817558Y1146708D01*
X816517D01*
G01X817558D02*
X818183Y1145500D01*
G01X820450D02*
Y1148000D01*
X819950Y1147500D01*
G01Y1145500D02*
X820950D01*
G01X822633Y1146000D02*
X822883Y1145708D01*
X823217Y1145542D01*
X823592Y1145500D01*
X823925Y1145542D01*
X824258Y1145750D01*
X824467Y1146000D01*
X824508Y1146250D01*
X824425Y1146542D01*
X824133Y1146750D01*
X823842Y1146833D01*
X823467D01*
G01X823842D02*
X824092Y1146958D01*
X824300Y1147167D01*
X824383Y1147417D01*
X824300Y1147667D01*
X824092Y1147875D01*
X823717Y1148000D01*
X823342Y1147958D01*
X822967Y1147792D01*
G01X825942Y1145792D02*
X826233Y1145583D01*
X826567Y1145500D01*
X826900Y1145583D01*
X827192Y1145833D01*
X827400Y1146208D01*
X827483Y1146583D01*
Y1147042D01*
X827400Y1147417D01*
X827192Y1147750D01*
X826942Y1147917D01*
X826650Y1148000D01*
X826317Y1147917D01*
X826067Y1147750D01*
X825900Y1147500D01*
X825817Y1147167D01*
X825900Y1146875D01*
X826108Y1146583D01*
X826358Y1146417D01*
X826650Y1146375D01*
X826983Y1146458D01*
X827233Y1146667D01*
X827483Y1147042D01*
G01X829700Y1158000D02*
Y1162000D01*
X822300D01*
G01X822000Y1150300D02*
X826000D01*
Y1157700D01*
G01X821500D02*
X817500D01*
Y1150300D01*
G01X802000Y1173467D02*
X799500D01*
Y1174508D01*
X799625Y1174842D01*
X799792Y1175050D01*
X800125Y1175133D01*
X800458Y1175050D01*
X800667Y1174800D01*
X800792Y1174508D01*
Y1173467D01*
G01Y1174508D02*
X802000Y1175133D01*
G01X801708Y1176692D02*
X801917Y1176983D01*
X802000Y1177317D01*
X801917Y1177650D01*
X801667Y1177942D01*
X801292Y1178150D01*
X800917Y1178233D01*
X800458D01*
X800083Y1178150D01*
X799750Y1177942D01*
X799583Y1177692D01*
X799500Y1177400D01*
X799583Y1177067D01*
X799750Y1176817D01*
X800000Y1176650D01*
X800333Y1176567D01*
X800625Y1176650D01*
X800917Y1176858D01*
X801083Y1177108D01*
X801125Y1177400D01*
X801042Y1177733D01*
X800833Y1177983D01*
X800458Y1178233D01*
G01X801625Y1179583D02*
X801833Y1179833D01*
X801958Y1180125D01*
X802000Y1180500D01*
X801917Y1180875D01*
X801750Y1181167D01*
X801458Y1181375D01*
X801125Y1181417D01*
X800792Y1181333D01*
X800583Y1181125D01*
X800417Y1180833D01*
X800375Y1180542D01*
X800417Y1180250D01*
X800583Y1179875D01*
X799500Y1180000D01*
Y1181125D01*
G01Y1183600D02*
X799583Y1183267D01*
X799792Y1183017D01*
X800042Y1182850D01*
X800375Y1182725D01*
X800750Y1182683D01*
X801125Y1182725D01*
X801458Y1182850D01*
X801708Y1183017D01*
X801917Y1183267D01*
X802000Y1183600D01*
X801917Y1183933D01*
X801708Y1184183D01*
X801458Y1184350D01*
X801125Y1184475D01*
X800750Y1184517D01*
X800375Y1184475D01*
X800042Y1184350D01*
X799792Y1184183D01*
X799583Y1183933D01*
X799500Y1183600D01*
G01X802000Y1186700D02*
X799500D01*
X800000Y1186200D01*
G01X802000D02*
Y1187200D01*
G01X814500Y1178300D02*
X818500D01*
Y1185700D01*
G01X806000Y1173467D02*
X803500D01*
Y1174508D01*
X803625Y1174842D01*
X803792Y1175050D01*
X804125Y1175133D01*
X804458Y1175050D01*
X804667Y1174800D01*
X804792Y1174508D01*
Y1173467D01*
G01Y1174508D02*
X806000Y1175133D01*
G01X805708Y1176692D02*
X805917Y1176983D01*
X806000Y1177317D01*
X805917Y1177650D01*
X805667Y1177942D01*
X805292Y1178150D01*
X804917Y1178233D01*
X804458D01*
X804083Y1178150D01*
X803750Y1177942D01*
X803583Y1177692D01*
X803500Y1177400D01*
X803583Y1177067D01*
X803750Y1176817D01*
X804000Y1176650D01*
X804333Y1176567D01*
X804625Y1176650D01*
X804917Y1176858D01*
X805083Y1177108D01*
X805125Y1177400D01*
X805042Y1177733D01*
X804833Y1177983D01*
X804458Y1178233D01*
G01X806000Y1180417D02*
X805458Y1180500D01*
X805000Y1180625D01*
X804583Y1180792D01*
X804125Y1181000D01*
X803500Y1181333D01*
Y1179667D01*
G01X804958Y1182808D02*
X804667Y1183100D01*
X804500Y1183350D01*
X804417Y1183683D01*
X804500Y1183975D01*
X804667Y1184183D01*
X804917Y1184350D01*
X805208Y1184392D01*
X805458Y1184350D01*
X805708Y1184183D01*
X805917Y1183933D01*
X806000Y1183642D01*
X805917Y1183308D01*
X805667Y1183017D01*
X805292Y1182850D01*
X804875Y1182808D01*
X804333Y1182892D01*
X804042Y1183017D01*
X803750Y1183225D01*
X803542Y1183517D01*
X803500Y1183808D01*
X803583Y1184100D01*
X803792Y1184308D01*
G01X803917Y1185908D02*
X803667Y1186158D01*
X803542Y1186450D01*
X803500Y1186783D01*
X803583Y1187200D01*
X803792Y1187492D01*
X804042Y1187575D01*
X804292Y1187533D01*
X804500Y1187367D01*
X804917Y1186533D01*
X805208Y1186158D01*
X805625Y1185908D01*
X806000Y1185825D01*
Y1187575D01*
G01X823000Y1185700D02*
X819000D01*
Y1178300D01*
G01X803834Y1159983D02*
X801334D01*
Y1160817D01*
X801459Y1161150D01*
X801626Y1161400D01*
X801876Y1161608D01*
X802167Y1161775D01*
X802584Y1161817D01*
X803001Y1161775D01*
X803292Y1161608D01*
X803542Y1161400D01*
X803709Y1161150D01*
X803834Y1160817D01*
Y1159983D01*
G01X801751Y1163208D02*
X801501Y1163458D01*
X801376Y1163750D01*
X801334Y1164083D01*
X801417Y1164500D01*
X801626Y1164792D01*
X801876Y1164875D01*
X802126Y1164833D01*
X802334Y1164667D01*
X802751Y1163833D01*
X803042Y1163458D01*
X803459Y1163208D01*
X803834Y1163125D01*
Y1164875D01*
G01X801334Y1167100D02*
X801417Y1166767D01*
X801626Y1166517D01*
X801876Y1166350D01*
X802209Y1166225D01*
X802584Y1166183D01*
X802959Y1166225D01*
X803292Y1166350D01*
X803542Y1166517D01*
X803751Y1166767D01*
X803834Y1167100D01*
X803751Y1167433D01*
X803542Y1167683D01*
X803292Y1167850D01*
X802959Y1167975D01*
X802584Y1168017D01*
X802209Y1167975D01*
X801876Y1167850D01*
X801626Y1167683D01*
X801417Y1167433D01*
X801334Y1167100D01*
G01X809500Y1155000D02*
Y1171100D01*
G01X816500Y1155000D02*
X809500D01*
G01X816500Y1171100D02*
Y1155000D01*
G01X809500Y1171100D02*
X816500D01*
G01X807397Y1544427D02*
X807272Y1544177D01*
X807189Y1543885D01*
Y1543552D01*
X807314Y1543177D01*
X807522Y1542885D01*
X807772Y1542677D01*
X808189Y1542510D01*
X808564Y1542468D01*
X808939Y1542552D01*
X809189Y1542677D01*
X809439Y1542927D01*
X809606Y1543218D01*
X809689Y1543510D01*
Y1543802D01*
X809606Y1544093D01*
X809481Y1544343D01*
X809314Y1544552D01*
G01X809189Y1545693D02*
X809481Y1545943D01*
X809647Y1546277D01*
X809689Y1546652D01*
X809647Y1546985D01*
X809439Y1547318D01*
X809189Y1547527D01*
X808939Y1547568D01*
X808647Y1547485D01*
X808439Y1547193D01*
X808356Y1546902D01*
Y1546527D01*
G01Y1546902D02*
X808231Y1547152D01*
X808022Y1547360D01*
X807772Y1547443D01*
X807522Y1547360D01*
X807314Y1547152D01*
X807189Y1546777D01*
X807231Y1546402D01*
X807397Y1546027D01*
G01X809689Y1549710D02*
X809647Y1550002D01*
X809522Y1550335D01*
X809314Y1550543D01*
X809022Y1550627D01*
X808731Y1550543D01*
X808481Y1550293D01*
X808356Y1549918D01*
Y1549502D01*
X808272Y1549252D01*
X808064Y1549043D01*
X807772Y1548960D01*
X807481Y1549085D01*
X807272Y1549377D01*
X807189Y1549710D01*
X807272Y1550043D01*
X807481Y1550335D01*
X807772Y1550460D01*
X808064Y1550377D01*
X808272Y1550168D01*
X808356Y1549918D01*
Y1549502D01*
X808481Y1549127D01*
X808731Y1548877D01*
X809022Y1548793D01*
X809314Y1548877D01*
X809522Y1549085D01*
X809647Y1549418D01*
X809689Y1549710D01*
G01X809189Y1551893D02*
X809481Y1552143D01*
X809647Y1552477D01*
X809689Y1552852D01*
X809647Y1553185D01*
X809439Y1553518D01*
X809189Y1553727D01*
X808939Y1553768D01*
X808647Y1553685D01*
X808439Y1553393D01*
X808356Y1553102D01*
Y1552727D01*
G01Y1553102D02*
X808231Y1553352D01*
X808022Y1553560D01*
X807772Y1553643D01*
X807522Y1553560D01*
X807314Y1553352D01*
X807189Y1552977D01*
X807231Y1552602D01*
X807397Y1552227D01*
G01X807500Y1567450D02*
X807458Y1567117D01*
X807292Y1566825D01*
X807042Y1566575D01*
X806750Y1566408D01*
X806417Y1566325D01*
X806083D01*
X805750Y1566408D01*
X805458Y1566575D01*
X805208Y1566825D01*
X805042Y1567117D01*
X805000Y1567450D01*
X805042Y1567783D01*
X805208Y1568075D01*
X805458Y1568325D01*
X805750Y1568492D01*
X806083Y1568575D01*
X806417D01*
X806750Y1568492D01*
X807042Y1568325D01*
X807292Y1568075D01*
X807458Y1567783D01*
X807500Y1567450D01*
G01X806833Y1567783D02*
X807500Y1568283D01*
G01X807208Y1569842D02*
X807417Y1570133D01*
X807500Y1570467D01*
X807417Y1570800D01*
X807167Y1571092D01*
X806792Y1571300D01*
X806417Y1571383D01*
X805958D01*
X805583Y1571300D01*
X805250Y1571092D01*
X805083Y1570842D01*
X805000Y1570550D01*
X805083Y1570217D01*
X805250Y1569967D01*
X805500Y1569800D01*
X805833Y1569717D01*
X806125Y1569800D01*
X806417Y1570008D01*
X806583Y1570258D01*
X806625Y1570550D01*
X806542Y1570883D01*
X806333Y1571133D01*
X805958Y1571383D01*
G01X817500Y1582500D02*
Y1568500D01*
G01D02*
X830500D01*
G01D02*
Y1582500D01*
G01X822975Y1551933D02*
X823308Y1551725D01*
X823683Y1551600D01*
X824017D01*
X824350Y1551725D01*
X824600Y1551933D01*
X824725Y1552225D01*
X824642Y1552517D01*
X824433Y1552767D01*
X824058Y1552933D01*
X823558Y1553017D01*
X823267Y1553183D01*
X823142Y1553475D01*
X823225Y1553767D01*
X823433Y1553975D01*
X823725Y1554100D01*
X824017D01*
X824308Y1554017D01*
X824558Y1553808D01*
G01X826117Y1551600D02*
Y1554100D01*
X827158D01*
X827492Y1553975D01*
X827700Y1553808D01*
X827783Y1553475D01*
X827700Y1553142D01*
X827450Y1552933D01*
X827158Y1552808D01*
X826117D01*
G01X827158D02*
X827783Y1551600D01*
G01X830050D02*
Y1554100D01*
X829550Y1553600D01*
G01Y1551600D02*
X830550D01*
G01X833150Y1554100D02*
X832817Y1554017D01*
X832567Y1553808D01*
X832400Y1553558D01*
X832275Y1553225D01*
X832233Y1552850D01*
X832275Y1552475D01*
X832400Y1552142D01*
X832567Y1551892D01*
X832817Y1551683D01*
X833150Y1551600D01*
X833483Y1551683D01*
X833733Y1551892D01*
X833900Y1552142D01*
X834025Y1552475D01*
X834067Y1552850D01*
X834025Y1553225D01*
X833900Y1553558D01*
X833733Y1553808D01*
X833483Y1554017D01*
X833150Y1554100D01*
G01X835542Y1551892D02*
X835833Y1551683D01*
X836167Y1551600D01*
X836500Y1551683D01*
X836792Y1551933D01*
X837000Y1552308D01*
X837083Y1552683D01*
Y1553142D01*
X837000Y1553517D01*
X836792Y1553850D01*
X836542Y1554017D01*
X836250Y1554100D01*
X835917Y1554017D01*
X835667Y1553850D01*
X835500Y1553600D01*
X835417Y1553267D01*
X835500Y1552975D01*
X835708Y1552683D01*
X835958Y1552517D01*
X836250Y1552475D01*
X836583Y1552558D01*
X836833Y1552767D01*
X837083Y1553142D01*
G01X838433Y1552100D02*
X838683Y1551808D01*
X839017Y1551642D01*
X839392Y1551600D01*
X839725Y1551642D01*
X840058Y1551850D01*
X840267Y1552100D01*
X840308Y1552350D01*
X840225Y1552642D01*
X839933Y1552850D01*
X839642Y1552933D01*
X839267D01*
G01X839642D02*
X839892Y1553058D01*
X840100Y1553267D01*
X840183Y1553517D01*
X840100Y1553767D01*
X839892Y1553975D01*
X839517Y1554100D01*
X839142Y1554058D01*
X838767Y1553892D01*
G01X825075Y1547433D02*
X825408Y1547225D01*
X825783Y1547100D01*
X826117D01*
X826450Y1547225D01*
X826700Y1547433D01*
X826825Y1547725D01*
X826742Y1548017D01*
X826533Y1548267D01*
X826158Y1548433D01*
X825658Y1548517D01*
X825367Y1548683D01*
X825242Y1548975D01*
X825325Y1549267D01*
X825533Y1549475D01*
X825825Y1549600D01*
X826117D01*
X826408Y1549517D01*
X826658Y1549308D01*
G01X828217Y1547100D02*
Y1549600D01*
X829258D01*
X829592Y1549475D01*
X829800Y1549308D01*
X829883Y1548975D01*
X829800Y1548642D01*
X829550Y1548433D01*
X829258Y1548308D01*
X828217D01*
G01X829258D02*
X829883Y1547100D01*
G01X832150D02*
Y1549600D01*
X831650Y1549100D01*
G01Y1547100D02*
X832650D01*
G01X835250Y1549600D02*
X834917Y1549517D01*
X834667Y1549308D01*
X834500Y1549058D01*
X834375Y1548725D01*
X834333Y1548350D01*
X834375Y1547975D01*
X834500Y1547642D01*
X834667Y1547392D01*
X834917Y1547183D01*
X835250Y1547100D01*
X835583Y1547183D01*
X835833Y1547392D01*
X836000Y1547642D01*
X836125Y1547975D01*
X836167Y1548350D01*
X836125Y1548725D01*
X836000Y1549058D01*
X835833Y1549308D01*
X835583Y1549517D01*
X835250Y1549600D01*
G01X837642Y1547392D02*
X837933Y1547183D01*
X838267Y1547100D01*
X838600Y1547183D01*
X838892Y1547433D01*
X839100Y1547808D01*
X839183Y1548183D01*
Y1548642D01*
X839100Y1549017D01*
X838892Y1549350D01*
X838642Y1549517D01*
X838350Y1549600D01*
X838017Y1549517D01*
X837767Y1549350D01*
X837600Y1549100D01*
X837517Y1548767D01*
X837600Y1548475D01*
X837808Y1548183D01*
X838058Y1548017D01*
X838350Y1547975D01*
X838683Y1548058D01*
X838933Y1548267D01*
X839183Y1548642D01*
G01X841950Y1547100D02*
Y1549600D01*
X840408Y1547808D01*
X842492D01*
G01X801097Y1556001D02*
Y1558501D01*
X802138D01*
X802472Y1558376D01*
X802680Y1558209D01*
X802763Y1557876D01*
X802680Y1557543D01*
X802430Y1557334D01*
X802138Y1557209D01*
X801097D01*
G01X802138D02*
X802763Y1556001D01*
G01X805030D02*
Y1558501D01*
X804530Y1558001D01*
G01Y1556001D02*
X805530D01*
G01X807213Y1556501D02*
X807463Y1556209D01*
X807797Y1556043D01*
X808172Y1556001D01*
X808505Y1556043D01*
X808838Y1556251D01*
X809047Y1556501D01*
X809088Y1556751D01*
X809005Y1557043D01*
X808713Y1557251D01*
X808422Y1557334D01*
X808047D01*
G01X808422D02*
X808672Y1557459D01*
X808880Y1557668D01*
X808963Y1557918D01*
X808880Y1558168D01*
X808672Y1558376D01*
X808297Y1558501D01*
X807922Y1558459D01*
X807547Y1558293D01*
G01X811230Y1556001D02*
X811522Y1556043D01*
X811855Y1556168D01*
X812063Y1556376D01*
X812147Y1556668D01*
X812063Y1556959D01*
X811813Y1557209D01*
X811438Y1557334D01*
X811022D01*
X810772Y1557418D01*
X810563Y1557626D01*
X810480Y1557918D01*
X810605Y1558209D01*
X810897Y1558418D01*
X811230Y1558501D01*
X811563Y1558418D01*
X811855Y1558209D01*
X811980Y1557918D01*
X811897Y1557626D01*
X811688Y1557418D01*
X811438Y1557334D01*
X811022D01*
X810647Y1557209D01*
X810397Y1556959D01*
X810313Y1556668D01*
X810397Y1556376D01*
X810605Y1556168D01*
X810938Y1556043D01*
X811230Y1556001D01*
G01X829700Y1563500D02*
Y1567500D01*
X822300D01*
G01X805689Y1542677D02*
X803189D01*
Y1543718D01*
X803314Y1544052D01*
X803481Y1544260D01*
X803814Y1544343D01*
X804147Y1544260D01*
X804356Y1544010D01*
X804481Y1543718D01*
Y1542677D01*
G01Y1543718D02*
X805689Y1544343D01*
G01X805314Y1545693D02*
X805522Y1545943D01*
X805647Y1546235D01*
X805689Y1546610D01*
X805606Y1546985D01*
X805439Y1547277D01*
X805147Y1547485D01*
X804814Y1547527D01*
X804481Y1547443D01*
X804272Y1547235D01*
X804106Y1546943D01*
X804064Y1546652D01*
X804106Y1546360D01*
X804272Y1545985D01*
X803189Y1546110D01*
Y1547235D01*
G01X804647Y1548918D02*
X804356Y1549210D01*
X804189Y1549460D01*
X804106Y1549793D01*
X804189Y1550085D01*
X804356Y1550293D01*
X804606Y1550460D01*
X804897Y1550502D01*
X805147Y1550460D01*
X805397Y1550293D01*
X805606Y1550043D01*
X805689Y1549752D01*
X805606Y1549418D01*
X805356Y1549127D01*
X804981Y1548960D01*
X804564Y1548918D01*
X804022Y1549002D01*
X803731Y1549127D01*
X803439Y1549335D01*
X803231Y1549627D01*
X803189Y1549918D01*
X803272Y1550210D01*
X803481Y1550418D01*
G01X805689Y1552727D02*
X805147Y1552810D01*
X804689Y1552935D01*
X804272Y1553102D01*
X803814Y1553310D01*
X803189Y1553643D01*
Y1551977D01*
G01X822000Y1555800D02*
X826000D01*
Y1563200D01*
G01X801189Y1542677D02*
X798689D01*
Y1543718D01*
X798814Y1544052D01*
X798981Y1544260D01*
X799314Y1544343D01*
X799647Y1544260D01*
X799856Y1544010D01*
X799981Y1543718D01*
Y1542677D01*
G01Y1543718D02*
X801189Y1544343D01*
G01X800814Y1545693D02*
X801022Y1545943D01*
X801147Y1546235D01*
X801189Y1546610D01*
X801106Y1546985D01*
X800939Y1547277D01*
X800647Y1547485D01*
X800314Y1547527D01*
X799981Y1547443D01*
X799772Y1547235D01*
X799606Y1546943D01*
X799564Y1546652D01*
X799606Y1546360D01*
X799772Y1545985D01*
X798689Y1546110D01*
Y1547235D01*
G01X800814Y1548793D02*
X801022Y1549043D01*
X801147Y1549335D01*
X801189Y1549710D01*
X801106Y1550085D01*
X800939Y1550377D01*
X800647Y1550585D01*
X800314Y1550627D01*
X799981Y1550543D01*
X799772Y1550335D01*
X799606Y1550043D01*
X799564Y1549752D01*
X799606Y1549460D01*
X799772Y1549085D01*
X798689Y1549210D01*
Y1550335D01*
G01X799106Y1552018D02*
X798856Y1552268D01*
X798731Y1552560D01*
X798689Y1552893D01*
X798772Y1553310D01*
X798981Y1553602D01*
X799231Y1553685D01*
X799481Y1553643D01*
X799689Y1553477D01*
X800106Y1552643D01*
X800397Y1552268D01*
X800814Y1552018D01*
X801189Y1551935D01*
Y1553685D01*
G01X821500Y1563200D02*
X817500D01*
Y1555800D01*
G01X803334Y1566483D02*
X800834D01*
Y1567317D01*
X800959Y1567650D01*
X801126Y1567900D01*
X801376Y1568108D01*
X801667Y1568275D01*
X802084Y1568317D01*
X802501Y1568275D01*
X802792Y1568108D01*
X803042Y1567900D01*
X803209Y1567650D01*
X803334Y1567317D01*
Y1566483D01*
G01Y1570500D02*
X800834D01*
X801334Y1570000D01*
G01X803334D02*
Y1571000D01*
G01X803042Y1572892D02*
X803251Y1573183D01*
X803334Y1573517D01*
X803251Y1573850D01*
X803001Y1574142D01*
X802626Y1574350D01*
X802251Y1574433D01*
X801792D01*
X801417Y1574350D01*
X801084Y1574142D01*
X800917Y1573892D01*
X800834Y1573600D01*
X800917Y1573267D01*
X801084Y1573017D01*
X801334Y1572850D01*
X801667Y1572767D01*
X801959Y1572850D01*
X802251Y1573058D01*
X802417Y1573308D01*
X802459Y1573600D01*
X802376Y1573933D01*
X802167Y1574183D01*
X801792Y1574433D01*
G01X809500Y1560500D02*
Y1576600D01*
G01X816500Y1560500D02*
X809500D01*
G01X816500Y1576600D02*
Y1560500D01*
G01X826400Y1598500D02*
X826067Y1598542D01*
X825775Y1598708D01*
X825525Y1598958D01*
X825358Y1599250D01*
X825275Y1599583D01*
Y1599917D01*
X825358Y1600250D01*
X825525Y1600542D01*
X825775Y1600792D01*
X826067Y1600958D01*
X826400Y1601000D01*
X826733Y1600958D01*
X827025Y1600792D01*
X827275Y1600542D01*
X827442Y1600250D01*
X827525Y1599917D01*
Y1599583D01*
X827442Y1599250D01*
X827275Y1598958D01*
X827025Y1598708D01*
X826733Y1598542D01*
X826400Y1598500D01*
G01X826733Y1599167D02*
X827233Y1598500D01*
G01X828583Y1599000D02*
X828833Y1598708D01*
X829167Y1598542D01*
X829542Y1598500D01*
X829875Y1598542D01*
X830208Y1598750D01*
X830417Y1599000D01*
X830458Y1599250D01*
X830375Y1599542D01*
X830083Y1599750D01*
X829792Y1599833D01*
X829417D01*
G01X829792D02*
X830042Y1599958D01*
X830250Y1600167D01*
X830333Y1600417D01*
X830250Y1600667D01*
X830042Y1600875D01*
X829667Y1601000D01*
X829292Y1600958D01*
X828917Y1600792D01*
G01X832600Y1598500D02*
Y1601000D01*
X832100Y1600500D01*
G01Y1598500D02*
X833100D01*
G01X823500Y1596900D02*
Y1583900D01*
G01D02*
X837500D01*
G01D02*
Y1596900D01*
G01D02*
X823500D01*
G01X830500Y1582500D02*
X817500D01*
G01X802467Y1598000D02*
Y1600500D01*
X803508D01*
X803842Y1600375D01*
X804050Y1600208D01*
X804133Y1599875D01*
X804050Y1599542D01*
X803800Y1599333D01*
X803508Y1599208D01*
X802467D01*
G01X803508D02*
X804133Y1598000D01*
G01X805692Y1598292D02*
X805983Y1598083D01*
X806317Y1598000D01*
X806650Y1598083D01*
X806942Y1598333D01*
X807150Y1598708D01*
X807233Y1599083D01*
Y1599542D01*
X807150Y1599917D01*
X806942Y1600250D01*
X806692Y1600417D01*
X806400Y1600500D01*
X806067Y1600417D01*
X805817Y1600250D01*
X805650Y1600000D01*
X805567Y1599667D01*
X805650Y1599375D01*
X805858Y1599083D01*
X806108Y1598917D01*
X806400Y1598875D01*
X806733Y1598958D01*
X806983Y1599167D01*
X807233Y1599542D01*
G01X809417Y1598000D02*
X809500Y1598542D01*
X809625Y1599000D01*
X809792Y1599417D01*
X810000Y1599875D01*
X810333Y1600500D01*
X808667D01*
G01X812600Y1598000D02*
X812892Y1598042D01*
X813225Y1598167D01*
X813433Y1598375D01*
X813517Y1598667D01*
X813433Y1598958D01*
X813183Y1599208D01*
X812808Y1599333D01*
X812392D01*
X812142Y1599417D01*
X811933Y1599625D01*
X811850Y1599917D01*
X811975Y1600208D01*
X812267Y1600417D01*
X812600Y1600500D01*
X812933Y1600417D01*
X813225Y1600208D01*
X813350Y1599917D01*
X813267Y1599625D01*
X813058Y1599417D01*
X812808Y1599333D01*
X812392D01*
X812017Y1599208D01*
X811767Y1598958D01*
X811683Y1598667D01*
X811767Y1598375D01*
X811975Y1598167D01*
X812308Y1598042D01*
X812600Y1598000D01*
G01X814783Y1598375D02*
X815033Y1598167D01*
X815325Y1598042D01*
X815700Y1598000D01*
X816075Y1598083D01*
X816367Y1598250D01*
X816575Y1598542D01*
X816617Y1598875D01*
X816533Y1599208D01*
X816325Y1599417D01*
X816033Y1599583D01*
X815742Y1599625D01*
X815450Y1599583D01*
X815075Y1599417D01*
X815200Y1600500D01*
X816325D01*
G01X809975Y1596275D02*
Y1592275D01*
X817375D01*
G01X838150Y1584950D02*
X842150D01*
Y1592350D01*
G01X805000Y1577967D02*
X802500D01*
Y1579008D01*
X802625Y1579342D01*
X802792Y1579550D01*
X803125Y1579633D01*
X803458Y1579550D01*
X803667Y1579300D01*
X803792Y1579008D01*
Y1577967D01*
G01Y1579008D02*
X805000Y1579633D01*
G01X804708Y1581192D02*
X804917Y1581483D01*
X805000Y1581817D01*
X804917Y1582150D01*
X804667Y1582442D01*
X804292Y1582650D01*
X803917Y1582733D01*
X803458D01*
X803083Y1582650D01*
X802750Y1582442D01*
X802583Y1582192D01*
X802500Y1581900D01*
X802583Y1581567D01*
X802750Y1581317D01*
X803000Y1581150D01*
X803333Y1581067D01*
X803625Y1581150D01*
X803917Y1581358D01*
X804083Y1581608D01*
X804125Y1581900D01*
X804042Y1582233D01*
X803833Y1582483D01*
X803458Y1582733D01*
G01X805000Y1585500D02*
X802500D01*
X804292Y1583958D01*
Y1586042D01*
G01X804708Y1587392D02*
X804917Y1587683D01*
X805000Y1588017D01*
X804917Y1588350D01*
X804667Y1588642D01*
X804292Y1588850D01*
X803917Y1588933D01*
X803458D01*
X803083Y1588850D01*
X802750Y1588642D01*
X802583Y1588392D01*
X802500Y1588100D01*
X802583Y1587767D01*
X802750Y1587517D01*
X803000Y1587350D01*
X803333Y1587267D01*
X803625Y1587350D01*
X803917Y1587558D01*
X804083Y1587808D01*
X804125Y1588100D01*
X804042Y1588433D01*
X803833Y1588683D01*
X803458Y1588933D01*
G01X804708Y1590492D02*
X804917Y1590783D01*
X805000Y1591117D01*
X804917Y1591450D01*
X804667Y1591742D01*
X804292Y1591950D01*
X803917Y1592033D01*
X803458D01*
X803083Y1591950D01*
X802750Y1591742D01*
X802583Y1591492D01*
X802500Y1591200D01*
X802583Y1590867D01*
X802750Y1590617D01*
X803000Y1590450D01*
X803333Y1590367D01*
X803625Y1590450D01*
X803917Y1590658D01*
X804083Y1590908D01*
X804125Y1591200D01*
X804042Y1591533D01*
X803833Y1591783D01*
X803458Y1592033D01*
G01X814500Y1583800D02*
X818500D01*
Y1591200D01*
G01X809000Y1577967D02*
X806500D01*
Y1579008D01*
X806625Y1579342D01*
X806792Y1579550D01*
X807125Y1579633D01*
X807458Y1579550D01*
X807667Y1579300D01*
X807792Y1579008D01*
Y1577967D01*
G01Y1579008D02*
X809000Y1579633D01*
G01X808708Y1581192D02*
X808917Y1581483D01*
X809000Y1581817D01*
X808917Y1582150D01*
X808667Y1582442D01*
X808292Y1582650D01*
X807917Y1582733D01*
X807458D01*
X807083Y1582650D01*
X806750Y1582442D01*
X806583Y1582192D01*
X806500Y1581900D01*
X806583Y1581567D01*
X806750Y1581317D01*
X807000Y1581150D01*
X807333Y1581067D01*
X807625Y1581150D01*
X807917Y1581358D01*
X808083Y1581608D01*
X808125Y1581900D01*
X808042Y1582233D01*
X807833Y1582483D01*
X807458Y1582733D01*
G01X809000Y1584917D02*
X808458Y1585000D01*
X808000Y1585125D01*
X807583Y1585292D01*
X807125Y1585500D01*
X806500Y1585833D01*
Y1584167D01*
G01X807958Y1587308D02*
X807667Y1587600D01*
X807500Y1587850D01*
X807417Y1588183D01*
X807500Y1588475D01*
X807667Y1588683D01*
X807917Y1588850D01*
X808208Y1588892D01*
X808458Y1588850D01*
X808708Y1588683D01*
X808917Y1588433D01*
X809000Y1588142D01*
X808917Y1587808D01*
X808667Y1587517D01*
X808292Y1587350D01*
X807875Y1587308D01*
X807333Y1587392D01*
X807042Y1587517D01*
X806750Y1587725D01*
X806542Y1588017D01*
X806500Y1588308D01*
X806583Y1588600D01*
X806792Y1588808D01*
G01X809000Y1591200D02*
X806500D01*
X807000Y1590700D01*
G01X809000D02*
Y1591700D01*
G01X823000Y1591200D02*
X819000D01*
Y1583800D01*
G01X809500Y1576600D02*
X816500D01*
G01X837000Y1676417D02*
X834500D01*
Y1677417D01*
X834625Y1677750D01*
X834917Y1678000D01*
X835250Y1678083D01*
X835583Y1678000D01*
X835833Y1677792D01*
X835958Y1677417D01*
Y1676417D01*
G01X834708Y1681267D02*
X834583Y1681017D01*
X834500Y1680725D01*
Y1680392D01*
X834625Y1680017D01*
X834833Y1679725D01*
X835083Y1679517D01*
X835500Y1679350D01*
X835875Y1679308D01*
X836250Y1679392D01*
X836500Y1679517D01*
X836750Y1679767D01*
X836917Y1680058D01*
X837000Y1680350D01*
Y1680642D01*
X836917Y1680933D01*
X836792Y1681183D01*
X836625Y1681392D01*
G01X837000Y1683450D02*
X834500D01*
X835000Y1682950D01*
G01X837000D02*
Y1683950D01*
G01X834917Y1685758D02*
X834667Y1686008D01*
X834542Y1686300D01*
X834500Y1686633D01*
X834583Y1687050D01*
X834792Y1687342D01*
X835042Y1687425D01*
X835292Y1687383D01*
X835500Y1687217D01*
X835917Y1686383D01*
X836208Y1686008D01*
X836625Y1685758D01*
X837000Y1685675D01*
Y1687425D01*
G01Y1689650D02*
X836958Y1689942D01*
X836833Y1690275D01*
X836625Y1690483D01*
X836333Y1690567D01*
X836042Y1690483D01*
X835792Y1690233D01*
X835667Y1689858D01*
Y1689442D01*
X835583Y1689192D01*
X835375Y1688983D01*
X835083Y1688900D01*
X834792Y1689025D01*
X834583Y1689317D01*
X834500Y1689650D01*
X834583Y1689983D01*
X834792Y1690275D01*
X835083Y1690400D01*
X835375Y1690317D01*
X835583Y1690108D01*
X835667Y1689858D01*
Y1689442D01*
X835792Y1689067D01*
X836042Y1688817D01*
X836333Y1688733D01*
X836625Y1688817D01*
X836833Y1689025D01*
X836958Y1689358D01*
X837000Y1689650D01*
G01X834500Y1692750D02*
X834583Y1692417D01*
X834792Y1692167D01*
X835042Y1692000D01*
X835375Y1691875D01*
X835750Y1691833D01*
X836125Y1691875D01*
X836458Y1692000D01*
X836708Y1692167D01*
X836917Y1692417D01*
X837000Y1692750D01*
X836917Y1693083D01*
X836708Y1693333D01*
X836458Y1693500D01*
X836125Y1693625D01*
X835750Y1693667D01*
X835375Y1693625D01*
X835042Y1693500D01*
X834792Y1693333D01*
X834583Y1693083D01*
X834500Y1692750D01*
G01X785687Y1721161D02*
Y1723661D01*
X786687D01*
X787020Y1723536D01*
X787270Y1723244D01*
X787353Y1722911D01*
X787270Y1722578D01*
X787062Y1722328D01*
X786687Y1722203D01*
X785687D01*
G01X788787Y1721161D02*
Y1723661D01*
X789828D01*
X790162Y1723536D01*
X790370Y1723369D01*
X790453Y1723036D01*
X790370Y1722703D01*
X790120Y1722494D01*
X789828Y1722369D01*
X788787D01*
G01X789828D02*
X790453Y1721161D01*
G01X792012Y1721453D02*
X792303Y1721244D01*
X792637Y1721161D01*
X792970Y1721244D01*
X793262Y1721494D01*
X793470Y1721869D01*
X793553Y1722244D01*
Y1722703D01*
X793470Y1723078D01*
X793262Y1723411D01*
X793012Y1723578D01*
X792720Y1723661D01*
X792387Y1723578D01*
X792137Y1723411D01*
X791970Y1723161D01*
X791887Y1722828D01*
X791970Y1722536D01*
X792178Y1722244D01*
X792428Y1722078D01*
X792720Y1722036D01*
X793053Y1722119D01*
X793303Y1722328D01*
X793553Y1722703D01*
G01X795820Y1723661D02*
X795487Y1723578D01*
X795237Y1723369D01*
X795070Y1723119D01*
X794945Y1722786D01*
X794903Y1722411D01*
X794945Y1722036D01*
X795070Y1721703D01*
X795237Y1721453D01*
X795487Y1721244D01*
X795820Y1721161D01*
X796153Y1721244D01*
X796403Y1721453D01*
X796570Y1721703D01*
X796695Y1722036D01*
X796737Y1722411D01*
X796695Y1722786D01*
X796570Y1723119D01*
X796403Y1723369D01*
X796153Y1723578D01*
X795820Y1723661D01*
G01X798920Y1721161D02*
X799212Y1721203D01*
X799545Y1721328D01*
X799753Y1721536D01*
X799837Y1721828D01*
X799753Y1722119D01*
X799503Y1722369D01*
X799128Y1722494D01*
X798712D01*
X798462Y1722578D01*
X798253Y1722786D01*
X798170Y1723078D01*
X798295Y1723369D01*
X798587Y1723578D01*
X798920Y1723661D01*
X799253Y1723578D01*
X799545Y1723369D01*
X799670Y1723078D01*
X799587Y1722786D01*
X799378Y1722578D01*
X799128Y1722494D01*
X798712D01*
X798337Y1722369D01*
X798087Y1722119D01*
X798003Y1721828D01*
X798087Y1721536D01*
X798295Y1721328D01*
X798628Y1721203D01*
X798920Y1721161D01*
G01X801937D02*
X802020Y1721703D01*
X802145Y1722161D01*
X802312Y1722578D01*
X802520Y1723036D01*
X802853Y1723661D01*
X801187D01*
G01X805700Y1719500D02*
Y1727500D01*
X823300D01*
Y1719500D01*
X805700D01*
G01X785687Y1712161D02*
Y1714661D01*
X786687D01*
X787020Y1714536D01*
X787270Y1714244D01*
X787353Y1713911D01*
X787270Y1713578D01*
X787062Y1713328D01*
X786687Y1713203D01*
X785687D01*
G01X788787Y1712161D02*
Y1714661D01*
X789828D01*
X790162Y1714536D01*
X790370Y1714369D01*
X790453Y1714036D01*
X790370Y1713703D01*
X790120Y1713494D01*
X789828Y1713369D01*
X788787D01*
G01X789828D02*
X790453Y1712161D01*
G01X792012Y1712453D02*
X792303Y1712244D01*
X792637Y1712161D01*
X792970Y1712244D01*
X793262Y1712494D01*
X793470Y1712869D01*
X793553Y1713244D01*
Y1713703D01*
X793470Y1714078D01*
X793262Y1714411D01*
X793012Y1714578D01*
X792720Y1714661D01*
X792387Y1714578D01*
X792137Y1714411D01*
X791970Y1714161D01*
X791887Y1713828D01*
X791970Y1713536D01*
X792178Y1713244D01*
X792428Y1713078D01*
X792720Y1713036D01*
X793053Y1713119D01*
X793303Y1713328D01*
X793553Y1713703D01*
G01X795820Y1714661D02*
X795487Y1714578D01*
X795237Y1714369D01*
X795070Y1714119D01*
X794945Y1713786D01*
X794903Y1713411D01*
X794945Y1713036D01*
X795070Y1712703D01*
X795237Y1712453D01*
X795487Y1712244D01*
X795820Y1712161D01*
X796153Y1712244D01*
X796403Y1712453D01*
X796570Y1712703D01*
X796695Y1713036D01*
X796737Y1713411D01*
X796695Y1713786D01*
X796570Y1714119D01*
X796403Y1714369D01*
X796153Y1714578D01*
X795820Y1714661D01*
G01X798920Y1712161D02*
X799212Y1712203D01*
X799545Y1712328D01*
X799753Y1712536D01*
X799837Y1712828D01*
X799753Y1713119D01*
X799503Y1713369D01*
X799128Y1713494D01*
X798712D01*
X798462Y1713578D01*
X798253Y1713786D01*
X798170Y1714078D01*
X798295Y1714369D01*
X798587Y1714578D01*
X798920Y1714661D01*
X799253Y1714578D01*
X799545Y1714369D01*
X799670Y1714078D01*
X799587Y1713786D01*
X799378Y1713578D01*
X799128Y1713494D01*
X798712D01*
X798337Y1713369D01*
X798087Y1713119D01*
X798003Y1712828D01*
X798087Y1712536D01*
X798295Y1712328D01*
X798628Y1712203D01*
X798920Y1712161D01*
G01X802020D02*
X802312Y1712203D01*
X802645Y1712328D01*
X802853Y1712536D01*
X802937Y1712828D01*
X802853Y1713119D01*
X802603Y1713369D01*
X802228Y1713494D01*
X801812D01*
X801562Y1713578D01*
X801353Y1713786D01*
X801270Y1714078D01*
X801395Y1714369D01*
X801687Y1714578D01*
X802020Y1714661D01*
X802353Y1714578D01*
X802645Y1714369D01*
X802770Y1714078D01*
X802687Y1713786D01*
X802478Y1713578D01*
X802228Y1713494D01*
X801812D01*
X801437Y1713369D01*
X801187Y1713119D01*
X801103Y1712828D01*
X801187Y1712536D01*
X801395Y1712328D01*
X801728Y1712203D01*
X802020Y1712161D01*
G01X805700Y1710500D02*
Y1718500D01*
X823300D01*
Y1710500D01*
X805700D01*
G01X832500Y1676417D02*
X830000D01*
Y1677417D01*
X830125Y1677750D01*
X830417Y1678000D01*
X830750Y1678083D01*
X831083Y1678000D01*
X831333Y1677792D01*
X831458Y1677417D01*
Y1676417D01*
G01X830208Y1681267D02*
X830083Y1681017D01*
X830000Y1680725D01*
Y1680392D01*
X830125Y1680017D01*
X830333Y1679725D01*
X830583Y1679517D01*
X831000Y1679350D01*
X831375Y1679308D01*
X831750Y1679392D01*
X832000Y1679517D01*
X832250Y1679767D01*
X832417Y1680058D01*
X832500Y1680350D01*
Y1680642D01*
X832417Y1680933D01*
X832292Y1681183D01*
X832125Y1681392D01*
G01X832500Y1683450D02*
X830000D01*
X830500Y1682950D01*
G01X832500D02*
Y1683950D01*
G01X830417Y1685758D02*
X830167Y1686008D01*
X830042Y1686300D01*
X830000Y1686633D01*
X830083Y1687050D01*
X830292Y1687342D01*
X830542Y1687425D01*
X830792Y1687383D01*
X831000Y1687217D01*
X831417Y1686383D01*
X831708Y1686008D01*
X832125Y1685758D01*
X832500Y1685675D01*
Y1687425D01*
G01Y1689650D02*
X832458Y1689942D01*
X832333Y1690275D01*
X832125Y1690483D01*
X831833Y1690567D01*
X831542Y1690483D01*
X831292Y1690233D01*
X831167Y1689858D01*
Y1689442D01*
X831083Y1689192D01*
X830875Y1688983D01*
X830583Y1688900D01*
X830292Y1689025D01*
X830083Y1689317D01*
X830000Y1689650D01*
X830083Y1689983D01*
X830292Y1690275D01*
X830583Y1690400D01*
X830875Y1690317D01*
X831083Y1690108D01*
X831167Y1689858D01*
Y1689442D01*
X831292Y1689067D01*
X831542Y1688817D01*
X831833Y1688733D01*
X832125Y1688817D01*
X832333Y1689025D01*
X832458Y1689358D01*
X832500Y1689650D01*
G01X831458Y1691958D02*
X831167Y1692250D01*
X831000Y1692500D01*
X830917Y1692833D01*
X831000Y1693125D01*
X831167Y1693333D01*
X831417Y1693500D01*
X831708Y1693542D01*
X831958Y1693500D01*
X832208Y1693333D01*
X832417Y1693083D01*
X832500Y1692792D01*
X832417Y1692458D01*
X832167Y1692167D01*
X831792Y1692000D01*
X831375Y1691958D01*
X830833Y1692042D01*
X830542Y1692167D01*
X830250Y1692375D01*
X830042Y1692667D01*
X830000Y1692958D01*
X830083Y1693250D01*
X830292Y1693458D01*
G01X827333Y1675417D02*
X824833D01*
Y1676417D01*
X824958Y1676750D01*
X825250Y1677000D01*
X825583Y1677083D01*
X825916Y1677000D01*
X826166Y1676792D01*
X826291Y1676417D01*
Y1675417D01*
G01X825041Y1680267D02*
X824916Y1680017D01*
X824833Y1679725D01*
Y1679392D01*
X824958Y1679017D01*
X825166Y1678725D01*
X825416Y1678517D01*
X825833Y1678350D01*
X826208Y1678308D01*
X826583Y1678392D01*
X826833Y1678517D01*
X827083Y1678767D01*
X827250Y1679058D01*
X827333Y1679350D01*
Y1679642D01*
X827250Y1679933D01*
X827125Y1680183D01*
X826958Y1680392D01*
G01X827333Y1682450D02*
X824833D01*
X825333Y1681950D01*
G01X827333D02*
Y1682950D01*
G01X825250Y1684758D02*
X825000Y1685008D01*
X824875Y1685300D01*
X824833Y1685633D01*
X824916Y1686050D01*
X825125Y1686342D01*
X825375Y1686425D01*
X825625Y1686383D01*
X825833Y1686217D01*
X826250Y1685383D01*
X826541Y1685008D01*
X826958Y1684758D01*
X827333Y1684675D01*
Y1686425D01*
G01Y1688650D02*
X827291Y1688942D01*
X827166Y1689275D01*
X826958Y1689483D01*
X826666Y1689567D01*
X826375Y1689483D01*
X826125Y1689233D01*
X826000Y1688858D01*
Y1688442D01*
X825916Y1688192D01*
X825708Y1687983D01*
X825416Y1687900D01*
X825125Y1688025D01*
X824916Y1688317D01*
X824833Y1688650D01*
X824916Y1688983D01*
X825125Y1689275D01*
X825416Y1689400D01*
X825708Y1689317D01*
X825916Y1689108D01*
X826000Y1688858D01*
Y1688442D01*
X826125Y1688067D01*
X826375Y1687817D01*
X826666Y1687733D01*
X826958Y1687817D01*
X827166Y1688025D01*
X827291Y1688358D01*
X827333Y1688650D01*
G01X826958Y1690833D02*
X827166Y1691083D01*
X827291Y1691375D01*
X827333Y1691750D01*
X827250Y1692125D01*
X827083Y1692417D01*
X826791Y1692625D01*
X826458Y1692667D01*
X826125Y1692583D01*
X825916Y1692375D01*
X825750Y1692083D01*
X825708Y1691792D01*
X825750Y1691500D01*
X825916Y1691125D01*
X824833Y1691250D01*
Y1692375D01*
G01X807439Y1782507D02*
X804939D01*
Y1783548D01*
X805064Y1783882D01*
X805231Y1784090D01*
X805564Y1784173D01*
X805897Y1784090D01*
X806106Y1783840D01*
X806231Y1783548D01*
Y1782507D01*
G01Y1783548D02*
X807439Y1784173D01*
G01X806939Y1785523D02*
X807231Y1785773D01*
X807397Y1786107D01*
X807439Y1786482D01*
X807397Y1786815D01*
X807189Y1787148D01*
X806939Y1787357D01*
X806689Y1787398D01*
X806397Y1787315D01*
X806189Y1787023D01*
X806106Y1786732D01*
Y1786357D01*
G01Y1786732D02*
X805981Y1786982D01*
X805772Y1787190D01*
X805522Y1787273D01*
X805272Y1787190D01*
X805064Y1786982D01*
X804939Y1786607D01*
X804981Y1786232D01*
X805147Y1785857D01*
G01X807439Y1789540D02*
X804939D01*
X805439Y1789040D01*
G01X807439D02*
Y1790040D01*
G01X806397Y1791848D02*
X806106Y1792140D01*
X805939Y1792390D01*
X805856Y1792723D01*
X805939Y1793015D01*
X806106Y1793223D01*
X806356Y1793390D01*
X806647Y1793432D01*
X806897Y1793390D01*
X807147Y1793223D01*
X807356Y1792973D01*
X807439Y1792682D01*
X807356Y1792348D01*
X807106Y1792057D01*
X806731Y1791890D01*
X806314Y1791848D01*
X805772Y1791932D01*
X805481Y1792057D01*
X805189Y1792265D01*
X804981Y1792557D01*
X804939Y1792848D01*
X805022Y1793140D01*
X805231Y1793348D01*
G01X823500Y1786300D02*
X827500D01*
Y1793700D01*
G01X839500D02*
X835500D01*
Y1786300D01*
G01X811439Y1782507D02*
X808939D01*
Y1783548D01*
X809064Y1783882D01*
X809231Y1784090D01*
X809564Y1784173D01*
X809897Y1784090D01*
X810106Y1783840D01*
X810231Y1783548D01*
Y1782507D01*
G01Y1783548D02*
X811439Y1784173D01*
G01X810939Y1785523D02*
X811231Y1785773D01*
X811397Y1786107D01*
X811439Y1786482D01*
X811397Y1786815D01*
X811189Y1787148D01*
X810939Y1787357D01*
X810689Y1787398D01*
X810397Y1787315D01*
X810189Y1787023D01*
X810106Y1786732D01*
Y1786357D01*
G01Y1786732D02*
X809981Y1786982D01*
X809772Y1787190D01*
X809522Y1787273D01*
X809272Y1787190D01*
X809064Y1786982D01*
X808939Y1786607D01*
X808981Y1786232D01*
X809147Y1785857D01*
G01X809356Y1788748D02*
X809106Y1788998D01*
X808981Y1789290D01*
X808939Y1789623D01*
X809022Y1790040D01*
X809231Y1790332D01*
X809481Y1790415D01*
X809731Y1790373D01*
X809939Y1790207D01*
X810356Y1789373D01*
X810647Y1788998D01*
X811064Y1788748D01*
X811439Y1788665D01*
Y1790415D01*
G01Y1793140D02*
X808939D01*
X810731Y1791598D01*
Y1793682D01*
G01X831500Y1793700D02*
X827500D01*
Y1786300D01*
G01X796939Y1782507D02*
X794439D01*
Y1783548D01*
X794564Y1783882D01*
X794731Y1784090D01*
X795064Y1784173D01*
X795397Y1784090D01*
X795606Y1783840D01*
X795731Y1783548D01*
Y1782507D01*
G01Y1783548D02*
X796939Y1784173D01*
G01X796439Y1785523D02*
X796731Y1785773D01*
X796897Y1786107D01*
X796939Y1786482D01*
X796897Y1786815D01*
X796689Y1787148D01*
X796439Y1787357D01*
X796189Y1787398D01*
X795897Y1787315D01*
X795689Y1787023D01*
X795606Y1786732D01*
Y1786357D01*
G01Y1786732D02*
X795481Y1786982D01*
X795272Y1787190D01*
X795022Y1787273D01*
X794772Y1787190D01*
X794564Y1786982D01*
X794439Y1786607D01*
X794481Y1786232D01*
X794647Y1785857D01*
G01X796939Y1789540D02*
X794439D01*
X794939Y1789040D01*
G01X796939D02*
Y1790040D01*
G01Y1792557D02*
X796397Y1792640D01*
X795939Y1792765D01*
X795522Y1792932D01*
X795064Y1793140D01*
X794439Y1793473D01*
Y1791807D01*
G01X813000Y1786300D02*
X817000D01*
Y1793700D01*
G01X800939Y1782507D02*
X798439D01*
Y1783548D01*
X798564Y1783882D01*
X798731Y1784090D01*
X799064Y1784173D01*
X799397Y1784090D01*
X799606Y1783840D01*
X799731Y1783548D01*
Y1782507D01*
G01Y1783548D02*
X800939Y1784173D01*
G01X800439Y1785523D02*
X800731Y1785773D01*
X800897Y1786107D01*
X800939Y1786482D01*
X800897Y1786815D01*
X800689Y1787148D01*
X800439Y1787357D01*
X800189Y1787398D01*
X799897Y1787315D01*
X799689Y1787023D01*
X799606Y1786732D01*
Y1786357D01*
G01Y1786732D02*
X799481Y1786982D01*
X799272Y1787190D01*
X799022Y1787273D01*
X798772Y1787190D01*
X798564Y1786982D01*
X798439Y1786607D01*
X798481Y1786232D01*
X798647Y1785857D01*
G01X798856Y1788748D02*
X798606Y1788998D01*
X798481Y1789290D01*
X798439Y1789623D01*
X798522Y1790040D01*
X798731Y1790332D01*
X798981Y1790415D01*
X799231Y1790373D01*
X799439Y1790207D01*
X799856Y1789373D01*
X800147Y1788998D01*
X800564Y1788748D01*
X800939Y1788665D01*
Y1790415D01*
G01X800564Y1791723D02*
X800772Y1791973D01*
X800897Y1792265D01*
X800939Y1792640D01*
X800856Y1793015D01*
X800689Y1793307D01*
X800397Y1793515D01*
X800064Y1793557D01*
X799731Y1793473D01*
X799522Y1793265D01*
X799356Y1792973D01*
X799314Y1792682D01*
X799356Y1792390D01*
X799522Y1792015D01*
X798439Y1792140D01*
Y1793265D01*
G01X821000Y1793700D02*
X817000D01*
Y1786300D01*
G01X811977Y1730520D02*
Y1733020D01*
X812977D01*
X813310Y1732895D01*
X813560Y1732603D01*
X813643Y1732270D01*
X813560Y1731937D01*
X813352Y1731687D01*
X812977Y1731562D01*
X811977D01*
G01X816160Y1731770D02*
X816993D01*
Y1731020D01*
X816743Y1730770D01*
X816452Y1730603D01*
X816035Y1730520D01*
X815618Y1730603D01*
X815327Y1730770D01*
X815077Y1731020D01*
X814910Y1731312D01*
X814827Y1731645D01*
Y1731937D01*
X814910Y1732187D01*
X815077Y1732478D01*
X815327Y1732728D01*
X815577Y1732895D01*
X815910Y1733020D01*
X816202D01*
X816535Y1732937D01*
X816785Y1732770D01*
G01X819510Y1730520D02*
Y1733020D01*
X817968Y1731228D01*
X820052D01*
G01X836769Y1741387D02*
X834269D01*
Y1742387D01*
X834394Y1742720D01*
X834686Y1742970D01*
X835019Y1743053D01*
X835352Y1742970D01*
X835602Y1742762D01*
X835727Y1742387D01*
Y1741387D01*
G01X834477Y1746237D02*
X834352Y1745987D01*
X834269Y1745695D01*
Y1745362D01*
X834394Y1744987D01*
X834602Y1744695D01*
X834852Y1744487D01*
X835269Y1744320D01*
X835644Y1744278D01*
X836019Y1744362D01*
X836269Y1744487D01*
X836519Y1744737D01*
X836686Y1745028D01*
X836769Y1745320D01*
Y1745612D01*
X836686Y1745903D01*
X836561Y1746153D01*
X836394Y1746362D01*
G01X836769Y1748420D02*
X834269D01*
X834769Y1747920D01*
G01X836769D02*
Y1748920D01*
G01X834686Y1750728D02*
X834436Y1750978D01*
X834311Y1751270D01*
X834269Y1751603D01*
X834352Y1752020D01*
X834561Y1752312D01*
X834811Y1752395D01*
X835061Y1752353D01*
X835269Y1752187D01*
X835686Y1751353D01*
X835977Y1750978D01*
X836394Y1750728D01*
X836769Y1750645D01*
Y1752395D01*
G01Y1754537D02*
X836227Y1754620D01*
X835769Y1754745D01*
X835352Y1754912D01*
X834894Y1755120D01*
X834269Y1755453D01*
Y1753787D01*
G01X834686Y1756928D02*
X834436Y1757178D01*
X834311Y1757470D01*
X834269Y1757803D01*
X834352Y1758220D01*
X834561Y1758512D01*
X834811Y1758595D01*
X835061Y1758553D01*
X835269Y1758387D01*
X835686Y1757553D01*
X835977Y1757178D01*
X836394Y1756928D01*
X836769Y1756845D01*
Y1758595D01*
G01X828834Y1741917D02*
X826334D01*
Y1742917D01*
X826459Y1743250D01*
X826751Y1743500D01*
X827084Y1743583D01*
X827417Y1743500D01*
X827667Y1743292D01*
X827792Y1742917D01*
Y1741917D01*
G01X826542Y1746767D02*
X826417Y1746517D01*
X826334Y1746225D01*
Y1745892D01*
X826459Y1745517D01*
X826667Y1745225D01*
X826917Y1745017D01*
X827334Y1744850D01*
X827709Y1744808D01*
X828084Y1744892D01*
X828334Y1745017D01*
X828584Y1745267D01*
X828751Y1745558D01*
X828834Y1745850D01*
Y1746142D01*
X828751Y1746433D01*
X828626Y1746683D01*
X828459Y1746892D01*
G01X828834Y1748950D02*
X826334D01*
X826834Y1748450D01*
G01X828834D02*
Y1749450D01*
G01X826751Y1751258D02*
X826501Y1751508D01*
X826376Y1751800D01*
X826334Y1752133D01*
X826417Y1752550D01*
X826626Y1752842D01*
X826876Y1752925D01*
X827126Y1752883D01*
X827334Y1752717D01*
X827751Y1751883D01*
X828042Y1751508D01*
X828459Y1751258D01*
X828834Y1751175D01*
Y1752925D01*
G01Y1755150D02*
X828792Y1755442D01*
X828667Y1755775D01*
X828459Y1755983D01*
X828167Y1756067D01*
X827876Y1755983D01*
X827626Y1755733D01*
X827501Y1755358D01*
Y1754942D01*
X827417Y1754692D01*
X827209Y1754483D01*
X826917Y1754400D01*
X826626Y1754525D01*
X826417Y1754817D01*
X826334Y1755150D01*
X826417Y1755483D01*
X826626Y1755775D01*
X826917Y1755900D01*
X827209Y1755817D01*
X827417Y1755608D01*
X827501Y1755358D01*
Y1754942D01*
X827626Y1754567D01*
X827876Y1754317D01*
X828167Y1754233D01*
X828459Y1754317D01*
X828667Y1754525D01*
X828792Y1754858D01*
X828834Y1755150D01*
G01X826751Y1757458D02*
X826501Y1757708D01*
X826376Y1758000D01*
X826334Y1758333D01*
X826417Y1758750D01*
X826626Y1759042D01*
X826876Y1759125D01*
X827126Y1759083D01*
X827334Y1758917D01*
X827751Y1758083D01*
X828042Y1757708D01*
X828459Y1757458D01*
X828834Y1757375D01*
Y1759125D01*
G01X824267Y1822292D02*
X824017Y1822417D01*
X823725Y1822500D01*
X823392D01*
X823017Y1822375D01*
X822725Y1822167D01*
X822517Y1821917D01*
X822350Y1821500D01*
X822308Y1821125D01*
X822392Y1820750D01*
X822517Y1820500D01*
X822767Y1820250D01*
X823058Y1820083D01*
X823350Y1820000D01*
X823642D01*
X823933Y1820083D01*
X824183Y1820208D01*
X824392Y1820375D01*
G01X825533Y1820500D02*
X825783Y1820208D01*
X826117Y1820042D01*
X826492Y1820000D01*
X826825Y1820042D01*
X827158Y1820250D01*
X827367Y1820500D01*
X827408Y1820750D01*
X827325Y1821042D01*
X827033Y1821250D01*
X826742Y1821333D01*
X826367D01*
G01X826742D02*
X826992Y1821458D01*
X827200Y1821667D01*
X827283Y1821917D01*
X827200Y1822167D01*
X826992Y1822375D01*
X826617Y1822500D01*
X826242Y1822458D01*
X825867Y1822292D01*
G01X830050Y1820000D02*
Y1822500D01*
X828508Y1820708D01*
X830592D01*
G01X832650Y1820000D02*
Y1822500D01*
X832150Y1822000D01*
G01Y1820000D02*
X833150D01*
G01X784167Y1811561D02*
Y1814061D01*
X785208D01*
X785542Y1813936D01*
X785750Y1813769D01*
X785833Y1813436D01*
X785750Y1813103D01*
X785500Y1812894D01*
X785208Y1812769D01*
X784167D01*
G01X785208D02*
X785833Y1811561D01*
G01X787183Y1812061D02*
X787433Y1811769D01*
X787767Y1811603D01*
X788142Y1811561D01*
X788475Y1811603D01*
X788808Y1811811D01*
X789017Y1812061D01*
X789058Y1812311D01*
X788975Y1812603D01*
X788683Y1812811D01*
X788392Y1812894D01*
X788017D01*
G01X788392D02*
X788642Y1813019D01*
X788850Y1813228D01*
X788933Y1813478D01*
X788850Y1813728D01*
X788642Y1813936D01*
X788267Y1814061D01*
X787892Y1814019D01*
X787517Y1813853D01*
G01X791200Y1811561D02*
Y1814061D01*
X790700Y1813561D01*
G01Y1811561D02*
X791700D01*
G01X794800D02*
Y1814061D01*
X793258Y1812269D01*
X795342D01*
G01X797300Y1814000D02*
Y1810000D01*
X804700D01*
G01X784167Y1804561D02*
Y1807061D01*
X785208D01*
X785542Y1806936D01*
X785750Y1806769D01*
X785833Y1806436D01*
X785750Y1806103D01*
X785500Y1805894D01*
X785208Y1805769D01*
X784167D01*
G01X785208D02*
X785833Y1804561D01*
G01X787183Y1805061D02*
X787433Y1804769D01*
X787767Y1804603D01*
X788142Y1804561D01*
X788475Y1804603D01*
X788808Y1804811D01*
X789017Y1805061D01*
X789058Y1805311D01*
X788975Y1805603D01*
X788683Y1805811D01*
X788392Y1805894D01*
X788017D01*
G01X788392D02*
X788642Y1806019D01*
X788850Y1806228D01*
X788933Y1806478D01*
X788850Y1806728D01*
X788642Y1806936D01*
X788267Y1807061D01*
X787892Y1807019D01*
X787517Y1806853D01*
G01X791200Y1804561D02*
Y1807061D01*
X790700Y1806561D01*
G01Y1804561D02*
X791700D01*
G01X793592Y1804853D02*
X793883Y1804644D01*
X794217Y1804561D01*
X794550Y1804644D01*
X794842Y1804894D01*
X795050Y1805269D01*
X795133Y1805644D01*
Y1806103D01*
X795050Y1806478D01*
X794842Y1806811D01*
X794592Y1806978D01*
X794300Y1807061D01*
X793967Y1806978D01*
X793717Y1806811D01*
X793550Y1806561D01*
X793467Y1806228D01*
X793550Y1805936D01*
X793758Y1805644D01*
X794008Y1805478D01*
X794300Y1805436D01*
X794633Y1805519D01*
X794883Y1805728D01*
X795133Y1806103D01*
G01X797300Y1809000D02*
Y1805000D01*
X804700D01*
G01X799400Y1797500D02*
Y1795000D01*
G01X798442Y1797500D02*
X800358D01*
G01X801667Y1795000D02*
Y1797500D01*
X802667D01*
X803000Y1797375D01*
X803250Y1797083D01*
X803333Y1796750D01*
X803250Y1796417D01*
X803042Y1796167D01*
X802667Y1796042D01*
X801667D01*
G01X806100Y1795000D02*
Y1797500D01*
X804558Y1795708D01*
X806642D01*
G01X824740Y1802837D02*
X832740D01*
Y1814787D01*
X824740D01*
Y1802837D01*
G01X830890Y1814787D02*
X828890Y1812787D01*
X826890Y1814787D01*
G01X790726Y1910784D02*
X790601Y1910534D01*
X790518Y1910242D01*
Y1909909D01*
X790643Y1909534D01*
X790851Y1909242D01*
X791101Y1909034D01*
X791518Y1908867D01*
X791893Y1908825D01*
X792268Y1908909D01*
X792518Y1909034D01*
X792768Y1909284D01*
X792935Y1909575D01*
X793018Y1909867D01*
Y1910159D01*
X792935Y1910450D01*
X792810Y1910700D01*
X792643Y1910909D01*
G01X792518Y1912050D02*
X792810Y1912300D01*
X792976Y1912634D01*
X793018Y1913009D01*
X792976Y1913342D01*
X792768Y1913675D01*
X792518Y1913884D01*
X792268Y1913925D01*
X791976Y1913842D01*
X791768Y1913550D01*
X791685Y1913259D01*
Y1912884D01*
G01Y1913259D02*
X791560Y1913509D01*
X791351Y1913717D01*
X791101Y1913800D01*
X790851Y1913717D01*
X790643Y1913509D01*
X790518Y1913134D01*
X790560Y1912759D01*
X790726Y1912384D01*
G01X793018Y1916067D02*
X792976Y1916359D01*
X792851Y1916692D01*
X792643Y1916900D01*
X792351Y1916984D01*
X792060Y1916900D01*
X791810Y1916650D01*
X791685Y1916275D01*
Y1915859D01*
X791601Y1915609D01*
X791393Y1915400D01*
X791101Y1915317D01*
X790810Y1915442D01*
X790601Y1915734D01*
X790518Y1916067D01*
X790601Y1916400D01*
X790810Y1916692D01*
X791101Y1916817D01*
X791393Y1916734D01*
X791601Y1916525D01*
X791685Y1916275D01*
Y1915859D01*
X791810Y1915484D01*
X792060Y1915234D01*
X792351Y1915150D01*
X792643Y1915234D01*
X792851Y1915442D01*
X792976Y1915775D01*
X793018Y1916067D01*
G01X790935Y1918375D02*
X790685Y1918625D01*
X790560Y1918917D01*
X790518Y1919250D01*
X790601Y1919667D01*
X790810Y1919959D01*
X791060Y1920042D01*
X791310Y1920000D01*
X791518Y1919834D01*
X791935Y1919000D01*
X792226Y1918625D01*
X792643Y1918375D01*
X793018Y1918292D01*
Y1920042D01*
G01X786289Y1925507D02*
X785956Y1925549D01*
X785664Y1925715D01*
X785414Y1925965D01*
X785247Y1926257D01*
X785164Y1926590D01*
Y1926924D01*
X785247Y1927257D01*
X785414Y1927549D01*
X785664Y1927799D01*
X785956Y1927965D01*
X786289Y1928007D01*
X786622Y1927965D01*
X786914Y1927799D01*
X787164Y1927549D01*
X787331Y1927257D01*
X787414Y1926924D01*
Y1926590D01*
X787331Y1926257D01*
X787164Y1925965D01*
X786914Y1925715D01*
X786622Y1925549D01*
X786289Y1925507D01*
G01X786622Y1926174D02*
X787122Y1925507D01*
G01X789389D02*
X789681Y1925549D01*
X790014Y1925674D01*
X790222Y1925882D01*
X790306Y1926174D01*
X790222Y1926465D01*
X789972Y1926715D01*
X789597Y1926840D01*
X789181D01*
X788931Y1926924D01*
X788722Y1927132D01*
X788639Y1927424D01*
X788764Y1927715D01*
X789056Y1927924D01*
X789389Y1928007D01*
X789722Y1927924D01*
X790014Y1927715D01*
X790139Y1927424D01*
X790056Y1927132D01*
X789847Y1926924D01*
X789597Y1926840D01*
X789181D01*
X788806Y1926715D01*
X788556Y1926465D01*
X788472Y1926174D01*
X788556Y1925882D01*
X788764Y1925674D01*
X789097Y1925549D01*
X789389Y1925507D01*
G01X782246Y1921738D02*
Y1924238D01*
X783287D01*
X783621Y1924113D01*
X783829Y1923946D01*
X783912Y1923613D01*
X783829Y1923280D01*
X783579Y1923071D01*
X783287Y1922946D01*
X782246D01*
G01X783287D02*
X783912Y1921738D01*
G01X786179D02*
Y1924238D01*
X785679Y1923738D01*
G01Y1921738D02*
X786679D01*
G01X788362Y1922238D02*
X788612Y1921946D01*
X788946Y1921780D01*
X789321Y1921738D01*
X789654Y1921780D01*
X789987Y1921988D01*
X790196Y1922238D01*
X790237Y1922488D01*
X790154Y1922780D01*
X789862Y1922988D01*
X789571Y1923071D01*
X789196D01*
G01X789571D02*
X789821Y1923196D01*
X790029Y1923405D01*
X790112Y1923655D01*
X790029Y1923905D01*
X789821Y1924113D01*
X789446Y1924238D01*
X789071Y1924196D01*
X788696Y1924030D01*
G01X792296Y1921738D02*
X792379Y1922280D01*
X792504Y1922738D01*
X792671Y1923155D01*
X792879Y1923613D01*
X793212Y1924238D01*
X791546D01*
G01X794539Y1937507D02*
Y1941507D01*
X787139D01*
G01X784518Y1909034D02*
X782018D01*
Y1910075D01*
X782143Y1910409D01*
X782310Y1910617D01*
X782643Y1910700D01*
X782976Y1910617D01*
X783185Y1910367D01*
X783310Y1910075D01*
Y1909034D01*
G01Y1910075D02*
X784518Y1910700D01*
G01X784143Y1912050D02*
X784351Y1912300D01*
X784476Y1912592D01*
X784518Y1912967D01*
X784435Y1913342D01*
X784268Y1913634D01*
X783976Y1913842D01*
X783643Y1913884D01*
X783310Y1913800D01*
X783101Y1913592D01*
X782935Y1913300D01*
X782893Y1913009D01*
X782935Y1912717D01*
X783101Y1912342D01*
X782018Y1912467D01*
Y1913592D01*
G01X784143Y1915150D02*
X784351Y1915400D01*
X784476Y1915692D01*
X784518Y1916067D01*
X784435Y1916442D01*
X784268Y1916734D01*
X783976Y1916942D01*
X783643Y1916984D01*
X783310Y1916900D01*
X783101Y1916692D01*
X782935Y1916400D01*
X782893Y1916109D01*
X782935Y1915817D01*
X783101Y1915442D01*
X782018Y1915567D01*
Y1916692D01*
G01X784518Y1919167D02*
X782018D01*
X782518Y1918667D01*
G01X784518D02*
Y1919667D01*
G01X786339Y1937207D02*
X782339D01*
Y1929807D01*
G01X789018Y1909034D02*
X786518D01*
Y1910075D01*
X786643Y1910409D01*
X786810Y1910617D01*
X787143Y1910700D01*
X787476Y1910617D01*
X787685Y1910367D01*
X787810Y1910075D01*
Y1909034D01*
G01Y1910075D02*
X789018Y1910700D01*
G01X788643Y1912050D02*
X788851Y1912300D01*
X788976Y1912592D01*
X789018Y1912967D01*
X788935Y1913342D01*
X788768Y1913634D01*
X788476Y1913842D01*
X788143Y1913884D01*
X787810Y1913800D01*
X787601Y1913592D01*
X787435Y1913300D01*
X787393Y1913009D01*
X787435Y1912717D01*
X787601Y1912342D01*
X786518Y1912467D01*
Y1913592D01*
G01X787976Y1915275D02*
X787685Y1915567D01*
X787518Y1915817D01*
X787435Y1916150D01*
X787518Y1916442D01*
X787685Y1916650D01*
X787935Y1916817D01*
X788226Y1916859D01*
X788476Y1916817D01*
X788726Y1916650D01*
X788935Y1916400D01*
X789018Y1916109D01*
X788935Y1915775D01*
X788685Y1915484D01*
X788310Y1915317D01*
X787893Y1915275D01*
X787351Y1915359D01*
X787060Y1915484D01*
X786768Y1915692D01*
X786560Y1915984D01*
X786518Y1916275D01*
X786601Y1916567D01*
X786810Y1916775D01*
G01X787976Y1918375D02*
X787685Y1918667D01*
X787518Y1918917D01*
X787435Y1919250D01*
X787518Y1919542D01*
X787685Y1919750D01*
X787935Y1919917D01*
X788226Y1919959D01*
X788476Y1919917D01*
X788726Y1919750D01*
X788935Y1919500D01*
X789018Y1919209D01*
X788935Y1918875D01*
X788685Y1918584D01*
X788310Y1918417D01*
X787893Y1918375D01*
X787351Y1918459D01*
X787060Y1918584D01*
X786768Y1918792D01*
X786560Y1919084D01*
X786518Y1919375D01*
X786601Y1919667D01*
X786810Y1919875D01*
G01X786839Y1929807D02*
X790839D01*
Y1937207D01*
G01X809472Y1928207D02*
Y1926415D01*
X809639Y1926040D01*
X809972Y1925790D01*
X810389Y1925707D01*
X810806Y1925790D01*
X811139Y1926040D01*
X811306Y1926415D01*
Y1928207D01*
G01X812781Y1925999D02*
X813072Y1925790D01*
X813406Y1925707D01*
X813739Y1925790D01*
X814031Y1926040D01*
X814239Y1926415D01*
X814322Y1926790D01*
Y1927249D01*
X814239Y1927624D01*
X814031Y1927957D01*
X813781Y1928124D01*
X813489Y1928207D01*
X813156Y1928124D01*
X812906Y1927957D01*
X812739Y1927707D01*
X812656Y1927374D01*
X812739Y1927082D01*
X812947Y1926790D01*
X813197Y1926624D01*
X813489Y1926582D01*
X813822Y1926665D01*
X814072Y1926874D01*
X814322Y1927249D01*
G01X806839Y1952407D02*
Y1933207D01*
X818039D01*
Y1952407D01*
X806839D01*
G01X771333Y1937483D02*
X768833D01*
Y1938317D01*
X768958Y1938650D01*
X769125Y1938900D01*
X769375Y1939108D01*
X769666Y1939275D01*
X770083Y1939317D01*
X770500Y1939275D01*
X770791Y1939108D01*
X771041Y1938900D01*
X771208Y1938650D01*
X771333Y1938317D01*
Y1937483D01*
G01Y1941500D02*
X768833D01*
X769333Y1941000D01*
G01X771333D02*
Y1942000D01*
G01Y1944600D02*
X771291Y1944892D01*
X771166Y1945225D01*
X770958Y1945433D01*
X770666Y1945517D01*
X770375Y1945433D01*
X770125Y1945183D01*
X770000Y1944808D01*
Y1944392D01*
X769916Y1944142D01*
X769708Y1943933D01*
X769416Y1943850D01*
X769125Y1943975D01*
X768916Y1944267D01*
X768833Y1944600D01*
X768916Y1944933D01*
X769125Y1945225D01*
X769416Y1945350D01*
X769708Y1945267D01*
X769916Y1945058D01*
X770000Y1944808D01*
Y1944392D01*
X770125Y1944017D01*
X770375Y1943767D01*
X770666Y1943683D01*
X770958Y1943767D01*
X771166Y1943975D01*
X771291Y1944308D01*
X771333Y1944600D01*
G01X774339Y1934507D02*
Y1950607D01*
G01X781339Y1934507D02*
X774339D01*
G01X781339Y1950607D02*
Y1934507D01*
G01X770139Y1973007D02*
X769806Y1973049D01*
X769514Y1973215D01*
X769264Y1973465D01*
X769097Y1973757D01*
X769014Y1974090D01*
Y1974424D01*
X769097Y1974757D01*
X769264Y1975049D01*
X769514Y1975299D01*
X769806Y1975465D01*
X770139Y1975507D01*
X770472Y1975465D01*
X770764Y1975299D01*
X771014Y1975049D01*
X771181Y1974757D01*
X771264Y1974424D01*
Y1974090D01*
X771181Y1973757D01*
X771014Y1973465D01*
X770764Y1973215D01*
X770472Y1973049D01*
X770139Y1973007D01*
G01X770472Y1973674D02*
X770972Y1973007D01*
G01X772447Y1975090D02*
X772697Y1975340D01*
X772989Y1975465D01*
X773322Y1975507D01*
X773739Y1975424D01*
X774031Y1975215D01*
X774114Y1974965D01*
X774072Y1974715D01*
X773906Y1974507D01*
X773072Y1974090D01*
X772697Y1973799D01*
X772447Y1973382D01*
X772364Y1973007D01*
X774114D01*
G01X775422Y1973507D02*
X775672Y1973215D01*
X776006Y1973049D01*
X776381Y1973007D01*
X776714Y1973049D01*
X777047Y1973257D01*
X777256Y1973507D01*
X777297Y1973757D01*
X777214Y1974049D01*
X776922Y1974257D01*
X776631Y1974340D01*
X776256D01*
G01X776631D02*
X776881Y1974465D01*
X777089Y1974674D01*
X777172Y1974924D01*
X777089Y1975174D01*
X776881Y1975382D01*
X776506Y1975507D01*
X776131Y1975465D01*
X775756Y1975299D01*
G01X771739Y1970907D02*
Y1957907D01*
G01D02*
X785739D01*
G01D02*
Y1970907D01*
G01D02*
X771739D01*
G01X798139Y1973007D02*
X797806Y1973049D01*
X797514Y1973215D01*
X797264Y1973465D01*
X797097Y1973757D01*
X797014Y1974090D01*
Y1974424D01*
X797097Y1974757D01*
X797264Y1975049D01*
X797514Y1975299D01*
X797806Y1975465D01*
X798139Y1975507D01*
X798472Y1975465D01*
X798764Y1975299D01*
X799014Y1975049D01*
X799181Y1974757D01*
X799264Y1974424D01*
Y1974090D01*
X799181Y1973757D01*
X799014Y1973465D01*
X798764Y1973215D01*
X798472Y1973049D01*
X798139Y1973007D01*
G01X798472Y1973674D02*
X798972Y1973007D01*
G01X800447Y1975090D02*
X800697Y1975340D01*
X800989Y1975465D01*
X801322Y1975507D01*
X801739Y1975424D01*
X802031Y1975215D01*
X802114Y1974965D01*
X802072Y1974715D01*
X801906Y1974507D01*
X801072Y1974090D01*
X800697Y1973799D01*
X800447Y1973382D01*
X800364Y1973007D01*
X802114D01*
G01X804839D02*
Y1975507D01*
X803297Y1973715D01*
X805381D01*
G01X791239Y1970907D02*
Y1957907D01*
G01D02*
X805239D01*
G01D02*
Y1970907D01*
G01D02*
X791239D01*
G01X795339Y1956507D02*
X782339D01*
G01D02*
Y1942507D01*
G01D02*
X795339D01*
G01D02*
Y1956507D01*
G01X780706Y1973007D02*
Y1975507D01*
X781747D01*
X782081Y1975382D01*
X782289Y1975215D01*
X782372Y1974882D01*
X782289Y1974549D01*
X782039Y1974340D01*
X781747Y1974215D01*
X780706D01*
G01X781747D02*
X782372Y1973007D01*
G01X783931Y1973299D02*
X784222Y1973090D01*
X784556Y1973007D01*
X784889Y1973090D01*
X785181Y1973340D01*
X785389Y1973715D01*
X785472Y1974090D01*
Y1974549D01*
X785389Y1974924D01*
X785181Y1975257D01*
X784931Y1975424D01*
X784639Y1975507D01*
X784306Y1975424D01*
X784056Y1975257D01*
X783889Y1975007D01*
X783806Y1974674D01*
X783889Y1974382D01*
X784097Y1974090D01*
X784347Y1973924D01*
X784639Y1973882D01*
X784972Y1973965D01*
X785222Y1974174D01*
X785472Y1974549D01*
G01X787656Y1973007D02*
X787739Y1973549D01*
X787864Y1974007D01*
X788031Y1974424D01*
X788239Y1974882D01*
X788572Y1975507D01*
X786906D01*
G01X790756Y1973007D02*
X790839Y1973549D01*
X790964Y1974007D01*
X791131Y1974424D01*
X791339Y1974882D01*
X791672Y1975507D01*
X790006D01*
G01X793856Y1973007D02*
X793939Y1973549D01*
X794064Y1974007D01*
X794231Y1974424D01*
X794439Y1974882D01*
X794772Y1975507D01*
X793106D01*
G01X786389Y1958957D02*
X790389D01*
Y1966357D01*
G01X771239Y1965207D02*
X767239D01*
Y1957807D01*
G01X807267Y1973000D02*
Y1975500D01*
X808308D01*
X808642Y1975375D01*
X808850Y1975208D01*
X808933Y1974875D01*
X808850Y1974542D01*
X808600Y1974333D01*
X808308Y1974208D01*
X807267D01*
G01X808308D02*
X808933Y1973000D01*
G01X810492Y1973292D02*
X810783Y1973083D01*
X811117Y1973000D01*
X811450Y1973083D01*
X811742Y1973333D01*
X811950Y1973708D01*
X812033Y1974083D01*
Y1974542D01*
X811950Y1974917D01*
X811742Y1975250D01*
X811492Y1975417D01*
X811200Y1975500D01*
X810867Y1975417D01*
X810617Y1975250D01*
X810450Y1975000D01*
X810367Y1974667D01*
X810450Y1974375D01*
X810658Y1974083D01*
X810908Y1973917D01*
X811200Y1973875D01*
X811533Y1973958D01*
X811783Y1974167D01*
X812033Y1974542D01*
G01X814217Y1973000D02*
X814300Y1973542D01*
X814425Y1974000D01*
X814592Y1974417D01*
X814800Y1974875D01*
X815133Y1975500D01*
X813467D01*
G01X817317Y1973000D02*
X817400Y1973542D01*
X817525Y1974000D01*
X817692Y1974417D01*
X817900Y1974875D01*
X818233Y1975500D01*
X816567D01*
G01X819583Y1973375D02*
X819833Y1973167D01*
X820125Y1973042D01*
X820500Y1973000D01*
X820875Y1973083D01*
X821167Y1973250D01*
X821375Y1973542D01*
X821417Y1973875D01*
X821333Y1974208D01*
X821125Y1974417D01*
X820833Y1974583D01*
X820542Y1974625D01*
X820250Y1974583D01*
X819875Y1974417D01*
X820000Y1975500D01*
X821125D01*
G01X818839Y1969907D02*
Y1964707D01*
G01X811839Y1969907D02*
Y1962107D01*
G01X818839Y1969907D02*
X811839D01*
G01X818839Y1956507D02*
Y1965207D01*
G01X811839Y1956507D02*
X818839D01*
G01X811839Y1962907D02*
Y1956507D01*
G01X814439Y1952407D02*
X812439Y1950407D01*
X810439Y1952407D01*
G01X831367Y1979500D02*
Y1982000D01*
X832367D01*
X832700Y1981875D01*
X832950Y1981583D01*
X833033Y1981250D01*
X832950Y1980917D01*
X832742Y1980667D01*
X832367Y1980542D01*
X831367D01*
G01X836217Y1981792D02*
X835967Y1981917D01*
X835675Y1982000D01*
X835342D01*
X834967Y1981875D01*
X834675Y1981667D01*
X834467Y1981417D01*
X834300Y1981000D01*
X834258Y1980625D01*
X834342Y1980250D01*
X834467Y1980000D01*
X834717Y1979750D01*
X835008Y1979583D01*
X835300Y1979500D01*
X835592D01*
X835883Y1979583D01*
X836133Y1979708D01*
X836342Y1979875D01*
G01X838400Y1979500D02*
Y1982000D01*
X837900Y1981500D01*
G01Y1979500D02*
X838900D01*
G01X841500D02*
Y1982000D01*
X841000Y1981500D01*
G01Y1979500D02*
X842000D01*
G01X844600D02*
X844892Y1979542D01*
X845225Y1979667D01*
X845433Y1979875D01*
X845517Y1980167D01*
X845433Y1980458D01*
X845183Y1980708D01*
X844808Y1980833D01*
X844392D01*
X844142Y1980917D01*
X843933Y1981125D01*
X843850Y1981417D01*
X843975Y1981708D01*
X844267Y1981917D01*
X844600Y1982000D01*
X844933Y1981917D01*
X845225Y1981708D01*
X845350Y1981417D01*
X845267Y1981125D01*
X845058Y1980917D01*
X844808Y1980833D01*
X844392D01*
X844017Y1980708D01*
X843767Y1980458D01*
X843683Y1980167D01*
X843767Y1979875D01*
X843975Y1979667D01*
X844308Y1979542D01*
X844600Y1979500D01*
G01X846783Y1979875D02*
X847033Y1979667D01*
X847325Y1979542D01*
X847700Y1979500D01*
X848075Y1979583D01*
X848367Y1979750D01*
X848575Y1980042D01*
X848617Y1980375D01*
X848533Y1980708D01*
X848325Y1980917D01*
X848033Y1981083D01*
X847742Y1981125D01*
X847450Y1981083D01*
X847075Y1980917D01*
X847200Y1982000D01*
X848325D01*
G01X843150Y1971850D02*
Y1953150D01*
X832850D01*
Y1971850D01*
X843150D01*
G01X822567Y1975200D02*
Y1977700D01*
X823567D01*
X823900Y1977575D01*
X824150Y1977283D01*
X824233Y1976950D01*
X824150Y1976617D01*
X823942Y1976367D01*
X823567Y1976242D01*
X822567D01*
G01X827417Y1977492D02*
X827167Y1977617D01*
X826875Y1977700D01*
X826542D01*
X826167Y1977575D01*
X825875Y1977367D01*
X825667Y1977117D01*
X825500Y1976700D01*
X825458Y1976325D01*
X825542Y1975950D01*
X825667Y1975700D01*
X825917Y1975450D01*
X826208Y1975283D01*
X826500Y1975200D01*
X826792D01*
X827083Y1975283D01*
X827333Y1975408D01*
X827542Y1975575D01*
G01X829600Y1975200D02*
Y1977700D01*
X829100Y1977200D01*
G01Y1975200D02*
X830100D01*
G01X832700D02*
Y1977700D01*
X832200Y1977200D01*
G01Y1975200D02*
X833200D01*
G01X835800D02*
X836092Y1975242D01*
X836425Y1975367D01*
X836633Y1975575D01*
X836717Y1975867D01*
X836633Y1976158D01*
X836383Y1976408D01*
X836008Y1976533D01*
X835592D01*
X835342Y1976617D01*
X835133Y1976825D01*
X835050Y1977117D01*
X835175Y1977408D01*
X835467Y1977617D01*
X835800Y1977700D01*
X836133Y1977617D01*
X836425Y1977408D01*
X836550Y1977117D01*
X836467Y1976825D01*
X836258Y1976617D01*
X836008Y1976533D01*
X835592D01*
X835217Y1976408D01*
X834967Y1976158D01*
X834883Y1975867D01*
X834967Y1975575D01*
X835175Y1975367D01*
X835508Y1975242D01*
X835800Y1975200D01*
G01X838108Y1976242D02*
X838400Y1976533D01*
X838650Y1976700D01*
X838983Y1976783D01*
X839275Y1976700D01*
X839483Y1976533D01*
X839650Y1976283D01*
X839692Y1975992D01*
X839650Y1975742D01*
X839483Y1975492D01*
X839233Y1975283D01*
X838942Y1975200D01*
X838608Y1975283D01*
X838317Y1975533D01*
X838150Y1975908D01*
X838108Y1976325D01*
X838192Y1976867D01*
X838317Y1977158D01*
X838525Y1977450D01*
X838817Y1977658D01*
X839108Y1977700D01*
X839400Y1977617D01*
X839608Y1977408D01*
G01X830650Y1971850D02*
Y1953150D01*
X820350D01*
Y1971850D01*
X830650D01*
G01X774339Y1950607D02*
X781339D01*
G01X905217Y121792D02*
X904967Y121917D01*
X904675Y122000D01*
X904342D01*
X903967Y121875D01*
X903675Y121667D01*
X903467Y121417D01*
X903300Y121000D01*
X903258Y120625D01*
X903342Y120250D01*
X903467Y120000D01*
X903717Y119750D01*
X904008Y119583D01*
X904300Y119500D01*
X904592D01*
X904883Y119583D01*
X905133Y119708D01*
X905342Y119875D01*
G01X906692Y119792D02*
X906983Y119583D01*
X907317Y119500D01*
X907650Y119583D01*
X907942Y119833D01*
X908150Y120208D01*
X908233Y120583D01*
Y121042D01*
X908150Y121417D01*
X907942Y121750D01*
X907692Y121917D01*
X907400Y122000D01*
X907067Y121917D01*
X906817Y121750D01*
X906650Y121500D01*
X906567Y121167D01*
X906650Y120875D01*
X906858Y120583D01*
X907108Y120417D01*
X907400Y120375D01*
X907733Y120458D01*
X907983Y120667D01*
X908233Y121042D01*
G01X909583Y119875D02*
X909833Y119667D01*
X910125Y119542D01*
X910500Y119500D01*
X910875Y119583D01*
X911167Y119750D01*
X911375Y120042D01*
X911417Y120375D01*
X911333Y120708D01*
X911125Y120917D01*
X910833Y121083D01*
X910542Y121125D01*
X910250Y121083D01*
X909875Y120917D01*
X910000Y122000D01*
X911125D01*
G01X912808Y121583D02*
X913058Y121833D01*
X913350Y121958D01*
X913683Y122000D01*
X914100Y121917D01*
X914392Y121708D01*
X914475Y121458D01*
X914433Y121208D01*
X914267Y121000D01*
X913433Y120583D01*
X913058Y120292D01*
X912808Y119875D01*
X912725Y119500D01*
X914475D01*
G01X915908Y121583D02*
X916158Y121833D01*
X916450Y121958D01*
X916783Y122000D01*
X917200Y121917D01*
X917492Y121708D01*
X917575Y121458D01*
X917533Y121208D01*
X917367Y121000D01*
X916533Y120583D01*
X916158Y120292D01*
X915908Y119875D01*
X915825Y119500D01*
X917575D01*
G01X884233Y121300D02*
Y119508D01*
X884400Y119133D01*
X884733Y118883D01*
X885150Y118800D01*
X885567Y118883D01*
X885900Y119133D01*
X886067Y119508D01*
Y121300D01*
G01X887458Y120883D02*
X887708Y121133D01*
X888000Y121258D01*
X888333Y121300D01*
X888750Y121217D01*
X889042Y121008D01*
X889125Y120758D01*
X889083Y120508D01*
X888917Y120300D01*
X888083Y119883D01*
X887708Y119592D01*
X887458Y119175D01*
X887375Y118800D01*
X889125D01*
G01X891350Y121300D02*
X891017Y121217D01*
X890767Y121008D01*
X890600Y120758D01*
X890475Y120425D01*
X890433Y120050D01*
X890475Y119675D01*
X890600Y119342D01*
X890767Y119092D01*
X891017Y118883D01*
X891350Y118800D01*
X891683Y118883D01*
X891933Y119092D01*
X892100Y119342D01*
X892225Y119675D01*
X892267Y120050D01*
X892225Y120425D01*
X892100Y120758D01*
X891933Y121008D01*
X891683Y121217D01*
X891350Y121300D01*
G01X894450Y118800D02*
Y121300D01*
X893950Y120800D01*
G01Y118800D02*
X894950D01*
G01X895767Y168167D02*
Y170667D01*
X896767D01*
X897100Y170542D01*
X897350Y170250D01*
X897433Y169917D01*
X897350Y169584D01*
X897142Y169334D01*
X896767Y169209D01*
X895767D01*
G01X900533Y168167D02*
X898867D01*
Y170667D01*
X900533D01*
G01X899867Y169459D02*
X898867D01*
G01X903133Y169500D02*
X903300Y169625D01*
X903425Y169834D01*
X903508Y170125D01*
X903425Y170375D01*
X903258Y170542D01*
X902967Y170667D01*
X901842D01*
Y168167D01*
X903217D01*
X903508Y168334D01*
X903675Y168584D01*
X903758Y168875D01*
X903675Y169167D01*
X903425Y169417D01*
X903133Y169500D01*
X901842D01*
G01X907958Y168167D02*
X909000Y170667D01*
X910042Y168167D01*
G01X909667Y169042D02*
X908333D01*
G01X912100Y170667D02*
Y168167D01*
G01X911142Y170667D02*
X913058D01*
G01X915200D02*
Y168167D01*
G01X914242Y170667D02*
X916158D01*
G01X917342Y168167D02*
Y170667D01*
X919258Y168167D01*
Y170667D01*
G01X921900Y168167D02*
Y170667D01*
X920358Y168875D01*
X922442D01*
G01X937654Y185817D02*
X908754D01*
Y172917D01*
X890454D01*
Y185817D01*
X876954D01*
Y347017D01*
X890454D01*
Y359917D01*
X908754D01*
Y347017D01*
X937654D01*
Y336667D01*
X930954D01*
Y196167D01*
X937654D01*
Y185817D01*
G01X901817Y156567D02*
Y154067D01*
X903483D01*
G01X906583D02*
X904917D01*
Y156567D01*
X906583D01*
G01X905917Y155359D02*
X904917D01*
G01X907933Y154067D02*
Y156567D01*
X908767D01*
X909100Y156442D01*
X909350Y156275D01*
X909558Y156025D01*
X909725Y155734D01*
X909767Y155317D01*
X909725Y154900D01*
X909558Y154609D01*
X909350Y154359D01*
X909100Y154192D01*
X908767Y154067D01*
X907933D01*
G01X912450D02*
Y156567D01*
X910908Y154775D01*
X912992D01*
G01X893906Y158011D02*
Y165611D01*
X905306D01*
Y158011D01*
X893906D01*
G01X872400Y135000D02*
X872067Y135042D01*
X871775Y135208D01*
X871525Y135458D01*
X871358Y135750D01*
X871275Y136083D01*
Y136417D01*
X871358Y136750D01*
X871525Y137042D01*
X871775Y137292D01*
X872067Y137458D01*
X872400Y137500D01*
X872733Y137458D01*
X873025Y137292D01*
X873275Y137042D01*
X873442Y136750D01*
X873525Y136417D01*
Y136083D01*
X873442Y135750D01*
X873275Y135458D01*
X873025Y135208D01*
X872733Y135042D01*
X872400Y135000D01*
G01X872733Y135667D02*
X873233Y135000D01*
G01X876000D02*
Y137500D01*
X874458Y135708D01*
X876542D01*
G01X877892Y135292D02*
X878183Y135083D01*
X878517Y135000D01*
X878850Y135083D01*
X879142Y135333D01*
X879350Y135708D01*
X879433Y136083D01*
Y136542D01*
X879350Y136917D01*
X879142Y137250D01*
X878892Y137417D01*
X878600Y137500D01*
X878267Y137417D01*
X878017Y137250D01*
X877850Y137000D01*
X877767Y136667D01*
X877850Y136375D01*
X878058Y136083D01*
X878308Y135917D01*
X878600Y135875D01*
X878933Y135958D01*
X879183Y136167D01*
X879433Y136542D01*
G01X866000Y151500D02*
Y138500D01*
G01D02*
X880000D01*
G01D02*
Y151500D01*
G01D02*
X866000D01*
G01X862900Y155400D02*
X862858Y155067D01*
X862692Y154775D01*
X862442Y154525D01*
X862150Y154358D01*
X861817Y154275D01*
X861483D01*
X861150Y154358D01*
X860858Y154525D01*
X860608Y154775D01*
X860442Y155067D01*
X860400Y155400D01*
X860442Y155733D01*
X860608Y156025D01*
X860858Y156275D01*
X861150Y156442D01*
X861483Y156525D01*
X861817D01*
X862150Y156442D01*
X862442Y156275D01*
X862692Y156025D01*
X862858Y155733D01*
X862900Y155400D01*
G01X862233Y155733D02*
X862900Y156233D01*
G01X862525Y157583D02*
X862733Y157833D01*
X862858Y158125D01*
X862900Y158500D01*
X862817Y158875D01*
X862650Y159167D01*
X862358Y159375D01*
X862025Y159417D01*
X861692Y159333D01*
X861483Y159125D01*
X861317Y158833D01*
X861275Y158542D01*
X861317Y158250D01*
X861483Y157875D01*
X860400Y158000D01*
Y159125D01*
G01Y161600D02*
X860483Y161267D01*
X860692Y161017D01*
X860942Y160850D01*
X861275Y160725D01*
X861650Y160683D01*
X862025Y160725D01*
X862358Y160850D01*
X862608Y161017D01*
X862817Y161267D01*
X862900Y161600D01*
X862817Y161933D01*
X862608Y162183D01*
X862358Y162350D01*
X862025Y162475D01*
X861650Y162517D01*
X861275Y162475D01*
X860942Y162350D01*
X860692Y162183D01*
X860483Y161933D01*
X860400Y161600D01*
G01X869661Y152661D02*
X882661D01*
G01D02*
Y166661D01*
G01D02*
X869661D01*
G01D02*
Y152661D01*
G01X858567Y154375D02*
X858775Y154708D01*
X858900Y155083D01*
Y155417D01*
X858775Y155750D01*
X858567Y156000D01*
X858275Y156125D01*
X857983Y156042D01*
X857733Y155833D01*
X857567Y155458D01*
X857483Y154958D01*
X857317Y154667D01*
X857025Y154542D01*
X856733Y154625D01*
X856525Y154833D01*
X856400Y155125D01*
Y155417D01*
X856483Y155708D01*
X856692Y155958D01*
G01X858900Y157517D02*
X856400D01*
Y158558D01*
X856525Y158892D01*
X856692Y159100D01*
X857025Y159183D01*
X857358Y159100D01*
X857567Y158850D01*
X857692Y158558D01*
Y157517D01*
G01Y158558D02*
X858900Y159183D01*
G01Y161450D02*
X856400D01*
X856900Y160950D01*
G01X858900D02*
Y161950D01*
G01Y164550D02*
X856400D01*
X856900Y164050D01*
G01X858900D02*
Y165050D01*
G01X856817Y166858D02*
X856567Y167108D01*
X856442Y167400D01*
X856400Y167733D01*
X856483Y168150D01*
X856692Y168442D01*
X856942Y168525D01*
X857192Y168483D01*
X857400Y168317D01*
X857817Y167483D01*
X858108Y167108D01*
X858525Y166858D01*
X858900Y166775D01*
Y168525D01*
G01X858608Y170042D02*
X858817Y170333D01*
X858900Y170667D01*
X858817Y171000D01*
X858567Y171292D01*
X858192Y171500D01*
X857817Y171583D01*
X857358D01*
X856983Y171500D01*
X856650Y171292D01*
X856483Y171042D01*
X856400Y170750D01*
X856483Y170417D01*
X856650Y170167D01*
X856900Y170000D01*
X857233Y169917D01*
X857525Y170000D01*
X857817Y170208D01*
X857983Y170458D01*
X858025Y170750D01*
X857942Y171083D01*
X857733Y171333D01*
X857358Y171583D01*
G01X868961Y161361D02*
X864961D01*
Y153961D01*
G01X861667Y168400D02*
Y170900D01*
X862708D01*
X863042Y170775D01*
X863250Y170608D01*
X863333Y170275D01*
X863250Y169942D01*
X863000Y169733D01*
X862708Y169608D01*
X861667D01*
G01X862708D02*
X863333Y168400D01*
G01X864892Y168692D02*
X865183Y168483D01*
X865517Y168400D01*
X865850Y168483D01*
X866142Y168733D01*
X866350Y169108D01*
X866433Y169483D01*
Y169942D01*
X866350Y170317D01*
X866142Y170650D01*
X865892Y170817D01*
X865600Y170900D01*
X865267Y170817D01*
X865017Y170650D01*
X864850Y170400D01*
X864767Y170067D01*
X864850Y169775D01*
X865058Y169483D01*
X865308Y169317D01*
X865600Y169275D01*
X865933Y169358D01*
X866183Y169567D01*
X866433Y169942D01*
G01X868700Y168400D02*
X868992Y168442D01*
X869325Y168567D01*
X869533Y168775D01*
X869617Y169067D01*
X869533Y169358D01*
X869283Y169608D01*
X868908Y169733D01*
X868492D01*
X868242Y169817D01*
X868033Y170025D01*
X867950Y170317D01*
X868075Y170608D01*
X868367Y170817D01*
X868700Y170900D01*
X869033Y170817D01*
X869325Y170608D01*
X869450Y170317D01*
X869367Y170025D01*
X869158Y169817D01*
X868908Y169733D01*
X868492D01*
X868117Y169608D01*
X867867Y169358D01*
X867783Y169067D01*
X867867Y168775D01*
X868075Y168567D01*
X868408Y168442D01*
X868700Y168400D01*
G01X871800Y170900D02*
X871467Y170817D01*
X871217Y170608D01*
X871050Y170358D01*
X870925Y170025D01*
X870883Y169650D01*
X870925Y169275D01*
X871050Y168942D01*
X871217Y168692D01*
X871467Y168483D01*
X871800Y168400D01*
X872133Y168483D01*
X872383Y168692D01*
X872550Y168942D01*
X872675Y169275D01*
X872717Y169650D01*
X872675Y170025D01*
X872550Y170358D01*
X872383Y170608D01*
X872133Y170817D01*
X871800Y170900D01*
G01X874900Y168400D02*
X875192Y168442D01*
X875525Y168567D01*
X875733Y168775D01*
X875817Y169067D01*
X875733Y169358D01*
X875483Y169608D01*
X875108Y169733D01*
X874692D01*
X874442Y169817D01*
X874233Y170025D01*
X874150Y170317D01*
X874275Y170608D01*
X874567Y170817D01*
X874900Y170900D01*
X875233Y170817D01*
X875525Y170608D01*
X875650Y170317D01*
X875567Y170025D01*
X875358Y169817D01*
X875108Y169733D01*
X874692D01*
X874317Y169608D01*
X874067Y169358D01*
X873983Y169067D01*
X874067Y168775D01*
X874275Y168567D01*
X874608Y168442D01*
X874900Y168400D01*
G01X884300Y159000D02*
Y155000D01*
X891700D01*
G01X903467Y123500D02*
Y126000D01*
X904508D01*
X904842Y125875D01*
X905050Y125708D01*
X905133Y125375D01*
X905050Y125042D01*
X904800Y124833D01*
X904508Y124708D01*
X903467D01*
G01X904508D02*
X905133Y123500D01*
G01X906692Y123792D02*
X906983Y123583D01*
X907317Y123500D01*
X907650Y123583D01*
X907942Y123833D01*
X908150Y124208D01*
X908233Y124583D01*
Y125042D01*
X908150Y125417D01*
X907942Y125750D01*
X907692Y125917D01*
X907400Y126000D01*
X907067Y125917D01*
X906817Y125750D01*
X906650Y125500D01*
X906567Y125167D01*
X906650Y124875D01*
X906858Y124583D01*
X907108Y124417D01*
X907400Y124375D01*
X907733Y124458D01*
X907983Y124667D01*
X908233Y125042D01*
G01X910500Y123500D02*
X910792Y123542D01*
X911125Y123667D01*
X911333Y123875D01*
X911417Y124167D01*
X911333Y124458D01*
X911083Y124708D01*
X910708Y124833D01*
X910292D01*
X910042Y124917D01*
X909833Y125125D01*
X909750Y125417D01*
X909875Y125708D01*
X910167Y125917D01*
X910500Y126000D01*
X910833Y125917D01*
X911125Y125708D01*
X911250Y125417D01*
X911167Y125125D01*
X910958Y124917D01*
X910708Y124833D01*
X910292D01*
X909917Y124708D01*
X909667Y124458D01*
X909583Y124167D01*
X909667Y123875D01*
X909875Y123667D01*
X910208Y123542D01*
X910500Y123500D01*
G01X913600Y126000D02*
X913267Y125917D01*
X913017Y125708D01*
X912850Y125458D01*
X912725Y125125D01*
X912683Y124750D01*
X912725Y124375D01*
X912850Y124042D01*
X913017Y123792D01*
X913267Y123583D01*
X913600Y123500D01*
X913933Y123583D01*
X914183Y123792D01*
X914350Y124042D01*
X914475Y124375D01*
X914517Y124750D01*
X914475Y125125D01*
X914350Y125458D01*
X914183Y125708D01*
X913933Y125917D01*
X913600Y126000D01*
G01X915992Y123792D02*
X916283Y123583D01*
X916617Y123500D01*
X916950Y123583D01*
X917242Y123833D01*
X917450Y124208D01*
X917533Y124583D01*
Y125042D01*
X917450Y125417D01*
X917242Y125750D01*
X916992Y125917D01*
X916700Y126000D01*
X916367Y125917D01*
X916117Y125750D01*
X915950Y125500D01*
X915867Y125167D01*
X915950Y124875D01*
X916158Y124583D01*
X916408Y124417D01*
X916700Y124375D01*
X917033Y124458D01*
X917283Y124667D01*
X917533Y125042D01*
G01X912700Y144453D02*
Y148453D01*
X905300D01*
G01X884175Y123533D02*
X884508Y123325D01*
X884883Y123200D01*
X885217D01*
X885550Y123325D01*
X885800Y123533D01*
X885925Y123825D01*
X885842Y124117D01*
X885633Y124367D01*
X885258Y124533D01*
X884758Y124617D01*
X884467Y124783D01*
X884342Y125075D01*
X884425Y125367D01*
X884633Y125575D01*
X884925Y125700D01*
X885217D01*
X885508Y125617D01*
X885758Y125408D01*
G01X887317Y123200D02*
Y125700D01*
X888358D01*
X888692Y125575D01*
X888900Y125408D01*
X888983Y125075D01*
X888900Y124742D01*
X888650Y124533D01*
X888358Y124408D01*
X887317D01*
G01X888358D02*
X888983Y123200D01*
G01X891250D02*
Y125700D01*
X890750Y125200D01*
G01Y123200D02*
X891750D01*
G01X894350D02*
Y125700D01*
X893850Y125200D01*
G01Y123200D02*
X894850D01*
G01X896533Y123700D02*
X896783Y123408D01*
X897117Y123242D01*
X897492Y123200D01*
X897825Y123242D01*
X898158Y123450D01*
X898367Y123700D01*
X898408Y123950D01*
X898325Y124242D01*
X898033Y124450D01*
X897742Y124533D01*
X897367D01*
G01X897742D02*
X897992Y124658D01*
X898200Y124867D01*
X898283Y125117D01*
X898200Y125367D01*
X897992Y125575D01*
X897617Y125700D01*
X897242Y125658D01*
X896867Y125492D01*
G01X900550Y125700D02*
X900217Y125617D01*
X899967Y125408D01*
X899800Y125158D01*
X899675Y124825D01*
X899633Y124450D01*
X899675Y124075D01*
X899800Y123742D01*
X899967Y123492D01*
X900217Y123283D01*
X900550Y123200D01*
X900883Y123283D01*
X901133Y123492D01*
X901300Y123742D01*
X901425Y124075D01*
X901467Y124450D01*
X901425Y124825D01*
X901300Y125158D01*
X901133Y125408D01*
X900883Y125617D01*
X900550Y125700D01*
G01X897648Y145253D02*
X901648D01*
Y152653D01*
G01X861667Y172400D02*
Y174900D01*
X862708D01*
X863042Y174775D01*
X863250Y174608D01*
X863333Y174275D01*
X863250Y173942D01*
X863000Y173733D01*
X862708Y173608D01*
X861667D01*
G01X862708D02*
X863333Y172400D01*
G01X864892Y172692D02*
X865183Y172483D01*
X865517Y172400D01*
X865850Y172483D01*
X866142Y172733D01*
X866350Y173108D01*
X866433Y173483D01*
Y173942D01*
X866350Y174317D01*
X866142Y174650D01*
X865892Y174817D01*
X865600Y174900D01*
X865267Y174817D01*
X865017Y174650D01*
X864850Y174400D01*
X864767Y174067D01*
X864850Y173775D01*
X865058Y173483D01*
X865308Y173317D01*
X865600Y173275D01*
X865933Y173358D01*
X866183Y173567D01*
X866433Y173942D01*
G01X867992Y172692D02*
X868283Y172483D01*
X868617Y172400D01*
X868950Y172483D01*
X869242Y172733D01*
X869450Y173108D01*
X869533Y173483D01*
Y173942D01*
X869450Y174317D01*
X869242Y174650D01*
X868992Y174817D01*
X868700Y174900D01*
X868367Y174817D01*
X868117Y174650D01*
X867950Y174400D01*
X867867Y174067D01*
X867950Y173775D01*
X868158Y173483D01*
X868408Y173317D01*
X868700Y173275D01*
X869033Y173358D01*
X869283Y173567D01*
X869533Y173942D01*
G01X871800Y172400D02*
Y174900D01*
X871300Y174400D01*
G01Y172400D02*
X872300D01*
G01X874108Y173442D02*
X874400Y173733D01*
X874650Y173900D01*
X874983Y173983D01*
X875275Y173900D01*
X875483Y173733D01*
X875650Y173483D01*
X875692Y173192D01*
X875650Y172942D01*
X875483Y172692D01*
X875233Y172483D01*
X874942Y172400D01*
X874608Y172483D01*
X874317Y172733D01*
X874150Y173108D01*
X874108Y173525D01*
X874192Y174067D01*
X874317Y174358D01*
X874525Y174650D01*
X874817Y174858D01*
X875108Y174900D01*
X875400Y174817D01*
X875608Y174608D01*
G01X884300Y163000D02*
Y159000D01*
X891700D01*
G01X884767Y127767D02*
Y130267D01*
X885808D01*
X886142Y130142D01*
X886350Y129975D01*
X886433Y129642D01*
X886350Y129309D01*
X886100Y129100D01*
X885808Y128975D01*
X884767D01*
G01X885808D02*
X886433Y127767D01*
G01X887992Y128059D02*
X888283Y127850D01*
X888617Y127767D01*
X888950Y127850D01*
X889242Y128100D01*
X889450Y128475D01*
X889533Y128850D01*
Y129309D01*
X889450Y129684D01*
X889242Y130017D01*
X888992Y130184D01*
X888700Y130267D01*
X888367Y130184D01*
X888117Y130017D01*
X887950Y129767D01*
X887867Y129434D01*
X887950Y129142D01*
X888158Y128850D01*
X888408Y128684D01*
X888700Y128642D01*
X889033Y128725D01*
X889283Y128934D01*
X889533Y129309D01*
G01X891092Y128059D02*
X891383Y127850D01*
X891717Y127767D01*
X892050Y127850D01*
X892342Y128100D01*
X892550Y128475D01*
X892633Y128850D01*
Y129309D01*
X892550Y129684D01*
X892342Y130017D01*
X892092Y130184D01*
X891800Y130267D01*
X891467Y130184D01*
X891217Y130017D01*
X891050Y129767D01*
X890967Y129434D01*
X891050Y129142D01*
X891258Y128850D01*
X891508Y128684D01*
X891800Y128642D01*
X892133Y128725D01*
X892383Y128934D01*
X892633Y129309D01*
G01X893983Y128267D02*
X894233Y127975D01*
X894567Y127809D01*
X894942Y127767D01*
X895275Y127809D01*
X895608Y128017D01*
X895817Y128267D01*
X895858Y128517D01*
X895775Y128809D01*
X895483Y129017D01*
X895192Y129100D01*
X894817D01*
G01X895192D02*
X895442Y129225D01*
X895650Y129434D01*
X895733Y129684D01*
X895650Y129934D01*
X895442Y130142D01*
X895067Y130267D01*
X894692Y130225D01*
X894317Y130059D01*
G01X897208Y128809D02*
X897500Y129100D01*
X897750Y129267D01*
X898083Y129350D01*
X898375Y129267D01*
X898583Y129100D01*
X898750Y128850D01*
X898792Y128559D01*
X898750Y128309D01*
X898583Y128059D01*
X898333Y127850D01*
X898042Y127767D01*
X897708Y127850D01*
X897417Y128100D01*
X897250Y128475D01*
X897208Y128892D01*
X897292Y129434D01*
X897417Y129725D01*
X897625Y130017D01*
X897917Y130225D01*
X898208Y130267D01*
X898500Y130184D01*
X898708Y129975D01*
G01X893275Y156724D02*
Y152724D01*
X900675D01*
G01X873467Y176166D02*
Y178666D01*
X874508D01*
X874842Y178541D01*
X875050Y178374D01*
X875133Y178041D01*
X875050Y177708D01*
X874800Y177499D01*
X874508Y177374D01*
X873467D01*
G01X874508D02*
X875133Y176166D01*
G01X876692Y176458D02*
X876983Y176249D01*
X877317Y176166D01*
X877650Y176249D01*
X877942Y176499D01*
X878150Y176874D01*
X878233Y177249D01*
Y177708D01*
X878150Y178083D01*
X877942Y178416D01*
X877692Y178583D01*
X877400Y178666D01*
X877067Y178583D01*
X876817Y178416D01*
X876650Y178166D01*
X876567Y177833D01*
X876650Y177541D01*
X876858Y177249D01*
X877108Y177083D01*
X877400Y177041D01*
X877733Y177124D01*
X877983Y177333D01*
X878233Y177708D01*
G01X879792Y176458D02*
X880083Y176249D01*
X880417Y176166D01*
X880750Y176249D01*
X881042Y176499D01*
X881250Y176874D01*
X881333Y177249D01*
Y177708D01*
X881250Y178083D01*
X881042Y178416D01*
X880792Y178583D01*
X880500Y178666D01*
X880167Y178583D01*
X879917Y178416D01*
X879750Y178166D01*
X879667Y177833D01*
X879750Y177541D01*
X879958Y177249D01*
X880208Y177083D01*
X880500Y177041D01*
X880833Y177124D01*
X881083Y177333D01*
X881333Y177708D01*
G01X882683Y176666D02*
X882933Y176374D01*
X883267Y176208D01*
X883642Y176166D01*
X883975Y176208D01*
X884308Y176416D01*
X884517Y176666D01*
X884558Y176916D01*
X884475Y177208D01*
X884183Y177416D01*
X883892Y177499D01*
X883517D01*
G01X883892D02*
X884142Y177624D01*
X884350Y177833D01*
X884433Y178083D01*
X884350Y178333D01*
X884142Y178541D01*
X883767Y178666D01*
X883392Y178624D01*
X883017Y178458D01*
G01X885783Y176541D02*
X886033Y176333D01*
X886325Y176208D01*
X886700Y176166D01*
X887075Y176249D01*
X887367Y176416D01*
X887575Y176708D01*
X887617Y177041D01*
X887533Y177374D01*
X887325Y177583D01*
X887033Y177749D01*
X886742Y177791D01*
X886450Y177749D01*
X886075Y177583D01*
X886200Y178666D01*
X887325D01*
G01X885116Y170354D02*
Y166354D01*
X892516D01*
G01X888800Y132453D02*
Y142453D01*
G01D02*
X902200D01*
G01D02*
Y132453D01*
G01D02*
X888800D01*
G01X851529Y288467D02*
X850696Y287134D01*
X850196Y285634D01*
Y284300D01*
X850696Y282967D01*
X851529Y281967D01*
X852696Y281467D01*
X853862Y281800D01*
X854863Y282634D01*
X855529Y284134D01*
X855863Y286134D01*
X856529Y287300D01*
X857696Y287800D01*
X858863Y287467D01*
X859696Y286634D01*
X860196Y285467D01*
Y284300D01*
X859863Y283134D01*
X859029Y282134D01*
G01X851529Y277867D02*
X850696Y276534D01*
X850196Y275034D01*
Y273700D01*
X850696Y272367D01*
X851529Y271367D01*
X852696Y270867D01*
X853862Y271200D01*
X854863Y272034D01*
X855529Y273534D01*
X855863Y275534D01*
X856529Y276700D01*
X857696Y277200D01*
X858863Y276867D01*
X859696Y276034D01*
X860196Y274867D01*
Y273700D01*
X859863Y272534D01*
X859029Y271534D01*
G01X850196Y267434D02*
X860196D01*
Y264100D01*
X859696Y262767D01*
X859029Y261767D01*
X858029Y260934D01*
X856862Y260267D01*
X855196Y260100D01*
X853529Y260267D01*
X852363Y260934D01*
X851362Y261767D01*
X850696Y262767D01*
X850196Y264100D01*
Y267434D01*
G01Y251167D02*
X860196D01*
X853029Y257334D01*
Y249000D01*
G01X867280Y238487D02*
X864780D01*
Y239487D01*
X864905Y239820D01*
X865197Y240070D01*
X865530Y240153D01*
X865863Y240070D01*
X866113Y239862D01*
X866238Y239487D01*
Y238487D01*
G01X864988Y243337D02*
X864863Y243087D01*
X864780Y242795D01*
Y242462D01*
X864905Y242087D01*
X865113Y241795D01*
X865363Y241587D01*
X865780Y241420D01*
X866155Y241378D01*
X866530Y241462D01*
X866780Y241587D01*
X867030Y241837D01*
X867197Y242128D01*
X867280Y242420D01*
Y242712D01*
X867197Y243003D01*
X867072Y243253D01*
X866905Y243462D01*
G01X867280Y245520D02*
X864780D01*
X865280Y245020D01*
G01X867280D02*
Y246020D01*
G01X865197Y247828D02*
X864947Y248078D01*
X864822Y248370D01*
X864780Y248703D01*
X864863Y249120D01*
X865072Y249412D01*
X865322Y249495D01*
X865572Y249453D01*
X865780Y249287D01*
X866197Y248453D01*
X866488Y248078D01*
X866905Y247828D01*
X867280Y247745D01*
Y249495D01*
G01X864780Y251720D02*
X864863Y251387D01*
X865072Y251137D01*
X865322Y250970D01*
X865655Y250845D01*
X866030Y250803D01*
X866405Y250845D01*
X866738Y250970D01*
X866988Y251137D01*
X867197Y251387D01*
X867280Y251720D01*
X867197Y252053D01*
X866988Y252303D01*
X866738Y252470D01*
X866405Y252595D01*
X866030Y252637D01*
X865655Y252595D01*
X865322Y252470D01*
X865072Y252303D01*
X864863Y252053D01*
X864780Y251720D01*
G01X867280Y255320D02*
X864780D01*
X866572Y253778D01*
Y255862D01*
G01X869650Y274177D02*
X869900Y274385D01*
X870067Y274635D01*
X870150Y274927D01*
X870067Y275260D01*
X869900Y275510D01*
X869650Y275760D01*
X869317Y275843D01*
X867650D01*
G01X870150Y278610D02*
X867650D01*
X869442Y277068D01*
Y279152D01*
G01X868700Y312817D02*
X866200D01*
Y313817D01*
X866325Y314150D01*
X866617Y314400D01*
X866950Y314483D01*
X867283Y314400D01*
X867533Y314192D01*
X867658Y313817D01*
Y312817D01*
G01X866408Y317667D02*
X866283Y317417D01*
X866200Y317125D01*
Y316792D01*
X866325Y316417D01*
X866533Y316125D01*
X866783Y315917D01*
X867200Y315750D01*
X867575Y315708D01*
X867950Y315792D01*
X868200Y315917D01*
X868450Y316167D01*
X868617Y316458D01*
X868700Y316750D01*
Y317042D01*
X868617Y317333D01*
X868492Y317583D01*
X868325Y317792D01*
G01X868700Y319850D02*
X866200D01*
X866700Y319350D01*
G01X868700D02*
Y320350D01*
G01X866617Y322158D02*
X866367Y322408D01*
X866242Y322700D01*
X866200Y323033D01*
X866283Y323450D01*
X866492Y323742D01*
X866742Y323825D01*
X866992Y323783D01*
X867200Y323617D01*
X867617Y322783D01*
X867908Y322408D01*
X868325Y322158D01*
X868700Y322075D01*
Y323825D01*
G01X866200Y326050D02*
X866283Y325717D01*
X866492Y325467D01*
X866742Y325300D01*
X867075Y325175D01*
X867450Y325133D01*
X867825Y325175D01*
X868158Y325300D01*
X868408Y325467D01*
X868617Y325717D01*
X868700Y326050D01*
X868617Y326383D01*
X868408Y326633D01*
X868158Y326800D01*
X867825Y326925D01*
X867450Y326967D01*
X867075Y326925D01*
X866742Y326800D01*
X866492Y326633D01*
X866283Y326383D01*
X866200Y326050D01*
G01X868200Y328233D02*
X868492Y328483D01*
X868658Y328817D01*
X868700Y329192D01*
X868658Y329525D01*
X868450Y329858D01*
X868200Y330067D01*
X867950Y330108D01*
X867658Y330025D01*
X867450Y329733D01*
X867367Y329442D01*
Y329067D01*
G01Y329442D02*
X867242Y329692D01*
X867033Y329900D01*
X866783Y329983D01*
X866533Y329900D01*
X866325Y329692D01*
X866200Y329317D01*
X866242Y328942D01*
X866408Y328567D01*
G01X846187Y309521D02*
Y312021D01*
X847228D01*
X847562Y311896D01*
X847770Y311729D01*
X847853Y311396D01*
X847770Y311063D01*
X847520Y310854D01*
X847228Y310729D01*
X846187D01*
G01X847228D02*
X847853Y309521D01*
G01X849203Y310021D02*
X849453Y309729D01*
X849787Y309563D01*
X850162Y309521D01*
X850495Y309563D01*
X850828Y309771D01*
X851037Y310021D01*
X851078Y310271D01*
X850995Y310563D01*
X850703Y310771D01*
X850412Y310854D01*
X850037D01*
G01X850412D02*
X850662Y310979D01*
X850870Y311188D01*
X850953Y311438D01*
X850870Y311688D01*
X850662Y311896D01*
X850287Y312021D01*
X849912Y311979D01*
X849537Y311813D01*
G01X852512Y309813D02*
X852803Y309604D01*
X853137Y309521D01*
X853470Y309604D01*
X853762Y309854D01*
X853970Y310229D01*
X854053Y310604D01*
Y311063D01*
X853970Y311438D01*
X853762Y311771D01*
X853512Y311938D01*
X853220Y312021D01*
X852887Y311938D01*
X852637Y311771D01*
X852470Y311521D01*
X852387Y311188D01*
X852470Y310896D01*
X852678Y310604D01*
X852928Y310438D01*
X853220Y310396D01*
X853553Y310479D01*
X853803Y310688D01*
X854053Y311063D01*
G01X855403Y309896D02*
X855653Y309688D01*
X855945Y309563D01*
X856320Y309521D01*
X856695Y309604D01*
X856987Y309771D01*
X857195Y310063D01*
X857237Y310396D01*
X857153Y310729D01*
X856945Y310938D01*
X856653Y311104D01*
X856362Y311146D01*
X856070Y311104D01*
X855695Y310938D01*
X855820Y312021D01*
X856945D01*
G01X858200Y319000D02*
Y323000D01*
X850800D01*
G01X846187Y314521D02*
Y317021D01*
X847228D01*
X847562Y316896D01*
X847770Y316729D01*
X847853Y316396D01*
X847770Y316063D01*
X847520Y315854D01*
X847228Y315729D01*
X846187D01*
G01X847228D02*
X847853Y314521D01*
G01X849203Y315021D02*
X849453Y314729D01*
X849787Y314563D01*
X850162Y314521D01*
X850495Y314563D01*
X850828Y314771D01*
X851037Y315021D01*
X851078Y315271D01*
X850995Y315563D01*
X850703Y315771D01*
X850412Y315854D01*
X850037D01*
G01X850412D02*
X850662Y315979D01*
X850870Y316188D01*
X850953Y316438D01*
X850870Y316688D01*
X850662Y316896D01*
X850287Y317021D01*
X849912Y316979D01*
X849537Y316813D01*
G01X852512Y314813D02*
X852803Y314604D01*
X853137Y314521D01*
X853470Y314604D01*
X853762Y314854D01*
X853970Y315229D01*
X854053Y315604D01*
Y316063D01*
X853970Y316438D01*
X853762Y316771D01*
X853512Y316938D01*
X853220Y317021D01*
X852887Y316938D01*
X852637Y316771D01*
X852470Y316521D01*
X852387Y316188D01*
X852470Y315896D01*
X852678Y315604D01*
X852928Y315438D01*
X853220Y315396D01*
X853553Y315479D01*
X853803Y315688D01*
X854053Y316063D01*
G01X855528Y315563D02*
X855820Y315854D01*
X856070Y316021D01*
X856403Y316104D01*
X856695Y316021D01*
X856903Y315854D01*
X857070Y315604D01*
X857112Y315313D01*
X857070Y315063D01*
X856903Y314813D01*
X856653Y314604D01*
X856362Y314521D01*
X856028Y314604D01*
X855737Y314854D01*
X855570Y315229D01*
X855528Y315646D01*
X855612Y316188D01*
X855737Y316479D01*
X855945Y316771D01*
X856237Y316979D01*
X856528Y317021D01*
X856820Y316938D01*
X857028Y316729D01*
G01X858200Y324000D02*
Y328000D01*
X850800D01*
G01X846050Y336200D02*
X842050D01*
Y328800D01*
G01X854200D02*
X858200D01*
Y336200D01*
G01X861700Y313517D02*
X859200D01*
Y314517D01*
X859325Y314850D01*
X859617Y315100D01*
X859950Y315183D01*
X860283Y315100D01*
X860533Y314892D01*
X860658Y314517D01*
Y313517D01*
G01X859408Y318367D02*
X859283Y318117D01*
X859200Y317825D01*
Y317492D01*
X859325Y317117D01*
X859533Y316825D01*
X859783Y316617D01*
X860200Y316450D01*
X860575Y316408D01*
X860950Y316492D01*
X861200Y316617D01*
X861450Y316867D01*
X861617Y317158D01*
X861700Y317450D01*
Y317742D01*
X861617Y318033D01*
X861492Y318283D01*
X861325Y318492D01*
G01X861700Y320550D02*
X859200D01*
X859700Y320050D01*
G01X861700D02*
Y321050D01*
G01X859617Y322858D02*
X859367Y323108D01*
X859242Y323400D01*
X859200Y323733D01*
X859283Y324150D01*
X859492Y324442D01*
X859742Y324525D01*
X859992Y324483D01*
X860200Y324317D01*
X860617Y323483D01*
X860908Y323108D01*
X861325Y322858D01*
X861700Y322775D01*
Y324525D01*
G01X859200Y326750D02*
X859283Y326417D01*
X859492Y326167D01*
X859742Y326000D01*
X860075Y325875D01*
X860450Y325833D01*
X860825Y325875D01*
X861158Y326000D01*
X861408Y326167D01*
X861617Y326417D01*
X861700Y326750D01*
X861617Y327083D01*
X861408Y327333D01*
X861158Y327500D01*
X860825Y327625D01*
X860450Y327667D01*
X860075Y327625D01*
X859742Y327500D01*
X859492Y327333D01*
X859283Y327083D01*
X859200Y326750D01*
G01X861700Y329850D02*
X859200D01*
X859700Y329350D01*
G01X861700D02*
Y330350D01*
G01X861150Y331150D02*
Y349850D01*
X871450D01*
Y331150D01*
X861150D01*
G01X881200Y370717D02*
X878700D01*
Y371717D01*
X878825Y372050D01*
X879117Y372300D01*
X879450Y372383D01*
X879783Y372300D01*
X880033Y372092D01*
X880158Y371717D01*
Y370717D01*
G01X878908Y375567D02*
X878783Y375317D01*
X878700Y375025D01*
Y374692D01*
X878825Y374317D01*
X879033Y374025D01*
X879283Y373817D01*
X879700Y373650D01*
X880075Y373608D01*
X880450Y373692D01*
X880700Y373817D01*
X880950Y374067D01*
X881117Y374358D01*
X881200Y374650D01*
Y374942D01*
X881117Y375233D01*
X880992Y375483D01*
X880825Y375692D01*
G01X881200Y377750D02*
X878700D01*
X879200Y377250D01*
G01X881200D02*
Y378250D01*
G01X879117Y380058D02*
X878867Y380308D01*
X878742Y380600D01*
X878700Y380933D01*
X878783Y381350D01*
X878992Y381642D01*
X879242Y381725D01*
X879492Y381683D01*
X879700Y381517D01*
X880117Y380683D01*
X880408Y380308D01*
X880825Y380058D01*
X881200Y379975D01*
Y381725D01*
G01X878700Y383950D02*
X878783Y383617D01*
X878992Y383367D01*
X879242Y383200D01*
X879575Y383075D01*
X879950Y383033D01*
X880325Y383075D01*
X880658Y383200D01*
X880908Y383367D01*
X881117Y383617D01*
X881200Y383950D01*
X881117Y384283D01*
X880908Y384533D01*
X880658Y384700D01*
X880325Y384825D01*
X879950Y384867D01*
X879575Y384825D01*
X879242Y384700D01*
X878992Y384533D01*
X878783Y384283D01*
X878700Y383950D01*
G01X879117Y386258D02*
X878867Y386508D01*
X878742Y386800D01*
X878700Y387133D01*
X878783Y387550D01*
X878992Y387842D01*
X879242Y387925D01*
X879492Y387883D01*
X879700Y387717D01*
X880117Y386883D01*
X880408Y386508D01*
X880825Y386258D01*
X881200Y386175D01*
Y387925D01*
G01X846400Y382000D02*
X846067Y382042D01*
X845775Y382208D01*
X845525Y382458D01*
X845358Y382750D01*
X845275Y383083D01*
Y383417D01*
X845358Y383750D01*
X845525Y384042D01*
X845775Y384292D01*
X846067Y384458D01*
X846400Y384500D01*
X846733Y384458D01*
X847025Y384292D01*
X847275Y384042D01*
X847442Y383750D01*
X847525Y383417D01*
Y383083D01*
X847442Y382750D01*
X847275Y382458D01*
X847025Y382208D01*
X846733Y382042D01*
X846400Y382000D01*
G01X846733Y382667D02*
X847233Y382000D01*
G01X850000D02*
Y384500D01*
X848458Y382708D01*
X850542D01*
G01X851808Y383042D02*
X852100Y383333D01*
X852350Y383500D01*
X852683Y383583D01*
X852975Y383500D01*
X853183Y383333D01*
X853350Y383083D01*
X853392Y382792D01*
X853350Y382542D01*
X853183Y382292D01*
X852933Y382083D01*
X852642Y382000D01*
X852308Y382083D01*
X852017Y382333D01*
X851850Y382708D01*
X851808Y383125D01*
X851892Y383667D01*
X852017Y383958D01*
X852225Y384250D01*
X852517Y384458D01*
X852808Y384500D01*
X853100Y384417D01*
X853308Y384208D01*
G01X843000Y380400D02*
Y367400D01*
G01D02*
X857000D01*
G01D02*
Y380400D01*
G01D02*
X843000D01*
G01X841500Y382967D02*
X839000D01*
Y384008D01*
X839125Y384342D01*
X839292Y384550D01*
X839625Y384633D01*
X839958Y384550D01*
X840167Y384300D01*
X840292Y384008D01*
Y382967D01*
G01Y384008D02*
X841500Y384633D01*
G01X841208Y386192D02*
X841417Y386483D01*
X841500Y386817D01*
X841417Y387150D01*
X841167Y387442D01*
X840792Y387650D01*
X840417Y387733D01*
X839958D01*
X839583Y387650D01*
X839250Y387442D01*
X839083Y387192D01*
X839000Y386900D01*
X839083Y386567D01*
X839250Y386317D01*
X839500Y386150D01*
X839833Y386067D01*
X840125Y386150D01*
X840417Y386358D01*
X840583Y386608D01*
X840625Y386900D01*
X840542Y387233D01*
X840333Y387483D01*
X839958Y387733D01*
G01X841500Y390000D02*
X841458Y390292D01*
X841333Y390625D01*
X841125Y390833D01*
X840833Y390917D01*
X840542Y390833D01*
X840292Y390583D01*
X840167Y390208D01*
Y389792D01*
X840083Y389542D01*
X839875Y389333D01*
X839583Y389250D01*
X839292Y389375D01*
X839083Y389667D01*
X839000Y390000D01*
X839083Y390333D01*
X839292Y390625D01*
X839583Y390750D01*
X839875Y390667D01*
X840083Y390458D01*
X840167Y390208D01*
Y389792D01*
X840292Y389417D01*
X840542Y389167D01*
X840833Y389083D01*
X841125Y389167D01*
X841333Y389375D01*
X841458Y389708D01*
X841500Y390000D01*
G01X839000Y393100D02*
X839083Y392767D01*
X839292Y392517D01*
X839542Y392350D01*
X839875Y392225D01*
X840250Y392183D01*
X840625Y392225D01*
X840958Y392350D01*
X841208Y392517D01*
X841417Y392767D01*
X841500Y393100D01*
X841417Y393433D01*
X841208Y393683D01*
X840958Y393850D01*
X840625Y393975D01*
X840250Y394017D01*
X839875Y393975D01*
X839542Y393850D01*
X839292Y393683D01*
X839083Y393433D01*
X839000Y393100D01*
G01X840458Y395408D02*
X840167Y395700D01*
X840000Y395950D01*
X839917Y396283D01*
X840000Y396575D01*
X840167Y396783D01*
X840417Y396950D01*
X840708Y396992D01*
X840958Y396950D01*
X841208Y396783D01*
X841417Y396533D01*
X841500Y396242D01*
X841417Y395908D01*
X841167Y395617D01*
X840792Y395450D01*
X840375Y395408D01*
X839833Y395492D01*
X839542Y395617D01*
X839250Y395825D01*
X839042Y396117D01*
X839000Y396408D01*
X839083Y396700D01*
X839292Y396908D01*
G01X863217Y386000D02*
Y388500D01*
X864258D01*
X864592Y388375D01*
X864800Y388208D01*
X864883Y387875D01*
X864800Y387542D01*
X864550Y387333D01*
X864258Y387208D01*
X863217D01*
G01X864258D02*
X864883Y386000D01*
G01X866442Y386292D02*
X866733Y386083D01*
X867067Y386000D01*
X867400Y386083D01*
X867692Y386333D01*
X867900Y386708D01*
X867983Y387083D01*
Y387542D01*
X867900Y387917D01*
X867692Y388250D01*
X867442Y388417D01*
X867150Y388500D01*
X866817Y388417D01*
X866567Y388250D01*
X866400Y388000D01*
X866317Y387667D01*
X866400Y387375D01*
X866608Y387083D01*
X866858Y386917D01*
X867150Y386875D01*
X867483Y386958D01*
X867733Y387167D01*
X867983Y387542D01*
G01X870250Y386000D02*
X870542Y386042D01*
X870875Y386167D01*
X871083Y386375D01*
X871167Y386667D01*
X871083Y386958D01*
X870833Y387208D01*
X870458Y387333D01*
X870042D01*
X869792Y387417D01*
X869583Y387625D01*
X869500Y387917D01*
X869625Y388208D01*
X869917Y388417D01*
X870250Y388500D01*
X870583Y388417D01*
X870875Y388208D01*
X871000Y387917D01*
X870917Y387625D01*
X870708Y387417D01*
X870458Y387333D01*
X870042D01*
X869667Y387208D01*
X869417Y386958D01*
X869333Y386667D01*
X869417Y386375D01*
X869625Y386167D01*
X869958Y386042D01*
X870250Y386000D01*
G01X873350Y388500D02*
X873017Y388417D01*
X872767Y388208D01*
X872600Y387958D01*
X872475Y387625D01*
X872433Y387250D01*
X872475Y386875D01*
X872600Y386542D01*
X872767Y386292D01*
X873017Y386083D01*
X873350Y386000D01*
X873683Y386083D01*
X873933Y386292D01*
X874100Y386542D01*
X874225Y386875D01*
X874267Y387250D01*
X874225Y387625D01*
X874100Y387958D01*
X873933Y388208D01*
X873683Y388417D01*
X873350Y388500D01*
G01X876950Y386000D02*
Y388500D01*
X875408Y386708D01*
X877492D01*
G01X877300Y372900D02*
X872100D01*
G01X877300Y379900D02*
X869500D01*
G01X877300Y372900D02*
Y379900D01*
G01X863900Y372900D02*
X872600D01*
G01X863900Y379900D02*
Y372900D01*
G01X870300Y379900D02*
X863900D01*
G01X847983Y365500D02*
Y363708D01*
X848150Y363333D01*
X848483Y363083D01*
X848900Y363000D01*
X849317Y363083D01*
X849650Y363333D01*
X849817Y363708D01*
Y365500D01*
G01X852000Y363000D02*
Y365500D01*
X851500Y365000D01*
G01Y363000D02*
X852500D01*
G01X854183Y363500D02*
X854433Y363208D01*
X854767Y363042D01*
X855142Y363000D01*
X855475Y363042D01*
X855808Y363250D01*
X856017Y363500D01*
X856058Y363750D01*
X855975Y364042D01*
X855683Y364250D01*
X855392Y364333D01*
X855017D01*
G01X855392D02*
X855642Y364458D01*
X855850Y364667D01*
X855933Y364917D01*
X855850Y365167D01*
X855642Y365375D01*
X855267Y365500D01*
X854892Y365458D01*
X854517Y365292D01*
G01X839900Y360800D02*
Y341600D01*
X851100D01*
Y360800D01*
X839900D01*
G01X847500D02*
X845500Y358800D01*
X843500Y360800D01*
G01X898467Y376300D02*
Y378800D01*
X899508D01*
X899842Y378675D01*
X900050Y378508D01*
X900133Y378175D01*
X900050Y377842D01*
X899800Y377633D01*
X899508Y377508D01*
X898467D01*
G01X899508D02*
X900133Y376300D01*
G01X901692Y376592D02*
X901983Y376383D01*
X902317Y376300D01*
X902650Y376383D01*
X902942Y376633D01*
X903150Y377008D01*
X903233Y377383D01*
Y377842D01*
X903150Y378217D01*
X902942Y378550D01*
X902692Y378717D01*
X902400Y378800D01*
X902067Y378717D01*
X901817Y378550D01*
X901650Y378300D01*
X901567Y377967D01*
X901650Y377675D01*
X901858Y377383D01*
X902108Y377217D01*
X902400Y377175D01*
X902733Y377258D01*
X902983Y377467D01*
X903233Y377842D01*
G01X904708Y378383D02*
X904958Y378633D01*
X905250Y378758D01*
X905583Y378800D01*
X906000Y378717D01*
X906292Y378508D01*
X906375Y378258D01*
X906333Y378008D01*
X906167Y377800D01*
X905333Y377383D01*
X904958Y377092D01*
X904708Y376675D01*
X904625Y376300D01*
X906375D01*
G01X909100D02*
Y378800D01*
X907558Y377008D01*
X909642D01*
G01X912200Y376300D02*
Y378800D01*
X910658Y377008D01*
X912742D01*
G01X886000Y362100D02*
X912000D01*
G01X886000Y375100D02*
Y362100D01*
G01X912000Y375100D02*
X886000D01*
G01X885200Y370717D02*
X882700D01*
Y371717D01*
X882825Y372050D01*
X883117Y372300D01*
X883450Y372383D01*
X883783Y372300D01*
X884033Y372092D01*
X884158Y371717D01*
Y370717D01*
G01X882908Y375567D02*
X882783Y375317D01*
X882700Y375025D01*
Y374692D01*
X882825Y374317D01*
X883033Y374025D01*
X883283Y373817D01*
X883700Y373650D01*
X884075Y373608D01*
X884450Y373692D01*
X884700Y373817D01*
X884950Y374067D01*
X885117Y374358D01*
X885200Y374650D01*
Y374942D01*
X885117Y375233D01*
X884992Y375483D01*
X884825Y375692D01*
G01X885200Y377750D02*
X882700D01*
X883200Y377250D01*
G01X885200D02*
Y378250D01*
G01X883117Y380058D02*
X882867Y380308D01*
X882742Y380600D01*
X882700Y380933D01*
X882783Y381350D01*
X882992Y381642D01*
X883242Y381725D01*
X883492Y381683D01*
X883700Y381517D01*
X884117Y380683D01*
X884408Y380308D01*
X884825Y380058D01*
X885200Y379975D01*
Y381725D01*
G01X882700Y383950D02*
X882783Y383617D01*
X882992Y383367D01*
X883242Y383200D01*
X883575Y383075D01*
X883950Y383033D01*
X884325Y383075D01*
X884658Y383200D01*
X884908Y383367D01*
X885117Y383617D01*
X885200Y383950D01*
X885117Y384283D01*
X884908Y384533D01*
X884658Y384700D01*
X884325Y384825D01*
X883950Y384867D01*
X883575Y384825D01*
X883242Y384700D01*
X882992Y384533D01*
X882783Y384283D01*
X882700Y383950D01*
G01Y387050D02*
X882783Y386717D01*
X882992Y386467D01*
X883242Y386300D01*
X883575Y386175D01*
X883950Y386133D01*
X884325Y386175D01*
X884658Y386300D01*
X884908Y386467D01*
X885117Y386717D01*
X885200Y387050D01*
X885117Y387383D01*
X884908Y387633D01*
X884658Y387800D01*
X884325Y387925D01*
X883950Y387967D01*
X883575Y387925D01*
X883242Y387800D01*
X882992Y387633D01*
X882783Y387383D01*
X882700Y387050D01*
G01X879150Y369350D02*
Y350650D01*
X868850D01*
Y369350D01*
X879150D01*
G01X903717Y529292D02*
X903467Y529417D01*
X903175Y529500D01*
X902842D01*
X902467Y529375D01*
X902175Y529167D01*
X901967Y528917D01*
X901800Y528500D01*
X901758Y528125D01*
X901842Y527750D01*
X901967Y527500D01*
X902217Y527250D01*
X902508Y527083D01*
X902800Y527000D01*
X903092D01*
X903383Y527083D01*
X903633Y527208D01*
X903842Y527375D01*
G01X905192Y527292D02*
X905483Y527083D01*
X905817Y527000D01*
X906150Y527083D01*
X906442Y527333D01*
X906650Y527708D01*
X906733Y528083D01*
Y528542D01*
X906650Y528917D01*
X906442Y529250D01*
X906192Y529417D01*
X905900Y529500D01*
X905567Y529417D01*
X905317Y529250D01*
X905150Y529000D01*
X905067Y528667D01*
X905150Y528375D01*
X905358Y528083D01*
X905608Y527917D01*
X905900Y527875D01*
X906233Y527958D01*
X906483Y528167D01*
X906733Y528542D01*
G01X908083Y527375D02*
X908333Y527167D01*
X908625Y527042D01*
X909000Y527000D01*
X909375Y527083D01*
X909667Y527250D01*
X909875Y527542D01*
X909917Y527875D01*
X909833Y528208D01*
X909625Y528417D01*
X909333Y528583D01*
X909042Y528625D01*
X908750Y528583D01*
X908375Y528417D01*
X908500Y529500D01*
X909625D01*
G01X911308Y529083D02*
X911558Y529333D01*
X911850Y529458D01*
X912183Y529500D01*
X912600Y529417D01*
X912892Y529208D01*
X912975Y528958D01*
X912933Y528708D01*
X912767Y528500D01*
X911933Y528083D01*
X911558Y527792D01*
X911308Y527375D01*
X911225Y527000D01*
X912975D01*
G01X915200D02*
Y529500D01*
X914700Y529000D01*
G01Y527000D02*
X915700D01*
G01X861000Y537900D02*
X860958Y537567D01*
X860792Y537275D01*
X860542Y537025D01*
X860250Y536858D01*
X859917Y536775D01*
X859583D01*
X859250Y536858D01*
X858958Y537025D01*
X858708Y537275D01*
X858542Y537567D01*
X858500Y537900D01*
X858542Y538233D01*
X858708Y538525D01*
X858958Y538775D01*
X859250Y538942D01*
X859583Y539025D01*
X859917D01*
X860250Y538942D01*
X860542Y538775D01*
X860792Y538525D01*
X860958Y538233D01*
X861000Y537900D01*
G01X860333Y538233D02*
X861000Y538733D01*
G01Y541500D02*
X858500D01*
X860292Y539958D01*
Y542042D01*
G01X861000Y544600D02*
X858500D01*
X860292Y543058D01*
Y545142D01*
G01X862500Y536465D02*
X875500D01*
G01D02*
Y550465D01*
G01D02*
X862500D01*
G01D02*
Y536465D01*
G01X868000Y552465D02*
X881000D01*
G01D02*
Y566465D01*
G01X868000D02*
Y552465D01*
G01X855167Y548375D02*
X855375Y548708D01*
X855500Y549083D01*
Y549417D01*
X855375Y549750D01*
X855167Y550000D01*
X854875Y550125D01*
X854583Y550042D01*
X854333Y549833D01*
X854167Y549458D01*
X854083Y548958D01*
X853917Y548667D01*
X853625Y548542D01*
X853333Y548625D01*
X853125Y548833D01*
X853000Y549125D01*
Y549417D01*
X853083Y549708D01*
X853292Y549958D01*
G01X855500Y551517D02*
X853000D01*
Y552558D01*
X853125Y552892D01*
X853292Y553100D01*
X853625Y553183D01*
X853958Y553100D01*
X854167Y552850D01*
X854292Y552558D01*
Y551517D01*
G01Y552558D02*
X855500Y553183D01*
G01Y555450D02*
X853000D01*
X853500Y554950D01*
G01X855500D02*
Y555950D01*
G01Y558550D02*
X853000D01*
X853500Y558050D01*
G01X855500D02*
Y559050D01*
G01X853417Y560858D02*
X853167Y561108D01*
X853042Y561400D01*
X853000Y561733D01*
X853083Y562150D01*
X853292Y562442D01*
X853542Y562525D01*
X853792Y562483D01*
X854000Y562317D01*
X854417Y561483D01*
X854708Y561108D01*
X855125Y560858D01*
X855500Y560775D01*
Y562525D01*
G01Y564667D02*
X854958Y564750D01*
X854500Y564875D01*
X854083Y565042D01*
X853625Y565250D01*
X853000Y565583D01*
Y563917D01*
G01X859800Y555465D02*
Y551465D01*
X867200D01*
G01X882550Y558715D02*
Y554715D01*
X889950D01*
G01X901967Y531500D02*
Y534000D01*
X903008D01*
X903342Y533875D01*
X903550Y533708D01*
X903633Y533375D01*
X903550Y533042D01*
X903300Y532833D01*
X903008Y532708D01*
X901967D01*
G01X903008D02*
X903633Y531500D01*
G01X905192Y531792D02*
X905483Y531583D01*
X905817Y531500D01*
X906150Y531583D01*
X906442Y531833D01*
X906650Y532208D01*
X906733Y532583D01*
Y533042D01*
X906650Y533417D01*
X906442Y533750D01*
X906192Y533917D01*
X905900Y534000D01*
X905567Y533917D01*
X905317Y533750D01*
X905150Y533500D01*
X905067Y533167D01*
X905150Y532875D01*
X905358Y532583D01*
X905608Y532417D01*
X905900Y532375D01*
X906233Y532458D01*
X906483Y532667D01*
X906733Y533042D01*
G01X909000Y531500D02*
X909292Y531542D01*
X909625Y531667D01*
X909833Y531875D01*
X909917Y532167D01*
X909833Y532458D01*
X909583Y532708D01*
X909208Y532833D01*
X908792D01*
X908542Y532917D01*
X908333Y533125D01*
X908250Y533417D01*
X908375Y533708D01*
X908667Y533917D01*
X909000Y534000D01*
X909333Y533917D01*
X909625Y533708D01*
X909750Y533417D01*
X909667Y533125D01*
X909458Y532917D01*
X909208Y532833D01*
X908792D01*
X908417Y532708D01*
X908167Y532458D01*
X908083Y532167D01*
X908167Y531875D01*
X908375Y531667D01*
X908708Y531542D01*
X909000Y531500D01*
G01X912100Y534000D02*
X911767Y533917D01*
X911517Y533708D01*
X911350Y533458D01*
X911225Y533125D01*
X911183Y532750D01*
X911225Y532375D01*
X911350Y532042D01*
X911517Y531792D01*
X911767Y531583D01*
X912100Y531500D01*
X912433Y531583D01*
X912683Y531792D01*
X912850Y532042D01*
X912975Y532375D01*
X913017Y532750D01*
X912975Y533125D01*
X912850Y533458D01*
X912683Y533708D01*
X912433Y533917D01*
X912100Y534000D01*
G01X914283Y532000D02*
X914533Y531708D01*
X914867Y531542D01*
X915242Y531500D01*
X915575Y531542D01*
X915908Y531750D01*
X916117Y532000D01*
X916158Y532250D01*
X916075Y532542D01*
X915783Y532750D01*
X915492Y532833D01*
X915117D01*
G01X915492D02*
X915742Y532958D01*
X915950Y533167D01*
X916033Y533417D01*
X915950Y533667D01*
X915742Y533875D01*
X915367Y534000D01*
X914992Y533958D01*
X914617Y533792D01*
G01X911700Y549965D02*
Y553965D01*
X904300D01*
G01X881875Y531833D02*
X882208Y531625D01*
X882583Y531500D01*
X882917D01*
X883250Y531625D01*
X883500Y531833D01*
X883625Y532125D01*
X883542Y532417D01*
X883333Y532667D01*
X882958Y532833D01*
X882458Y532917D01*
X882167Y533083D01*
X882042Y533375D01*
X882125Y533667D01*
X882333Y533875D01*
X882625Y534000D01*
X882917D01*
X883208Y533917D01*
X883458Y533708D01*
G01X885017Y531500D02*
Y534000D01*
X886058D01*
X886392Y533875D01*
X886600Y533708D01*
X886683Y533375D01*
X886600Y533042D01*
X886350Y532833D01*
X886058Y532708D01*
X885017D01*
G01X886058D02*
X886683Y531500D01*
G01X888950D02*
Y534000D01*
X888450Y533500D01*
G01Y531500D02*
X889450D01*
G01X892050D02*
Y534000D01*
X891550Y533500D01*
G01Y531500D02*
X892550D01*
G01X894358Y533583D02*
X894608Y533833D01*
X894900Y533958D01*
X895233Y534000D01*
X895650Y533917D01*
X895942Y533708D01*
X896025Y533458D01*
X895983Y533208D01*
X895817Y533000D01*
X894983Y532583D01*
X894608Y532292D01*
X894358Y531875D01*
X894275Y531500D01*
X896025D01*
G01X898250D02*
X898542Y531542D01*
X898875Y531667D01*
X899083Y531875D01*
X899167Y532167D01*
X899083Y532458D01*
X898833Y532708D01*
X898458Y532833D01*
X898042D01*
X897792Y532917D01*
X897583Y533125D01*
X897500Y533417D01*
X897625Y533708D01*
X897917Y533917D01*
X898250Y534000D01*
X898583Y533917D01*
X898875Y533708D01*
X899000Y533417D01*
X898917Y533125D01*
X898708Y532917D01*
X898458Y532833D01*
X898042D01*
X897667Y532708D01*
X897417Y532458D01*
X897333Y532167D01*
X897417Y531875D01*
X897625Y531667D01*
X897958Y531542D01*
X898250Y531500D01*
G01X896754Y550765D02*
X900754D01*
Y558165D01*
G01X887933Y529500D02*
Y527708D01*
X888100Y527333D01*
X888433Y527083D01*
X888850Y527000D01*
X889267Y527083D01*
X889600Y527333D01*
X889767Y527708D01*
Y529500D01*
G01X891158Y529083D02*
X891408Y529333D01*
X891700Y529458D01*
X892033Y529500D01*
X892450Y529417D01*
X892742Y529208D01*
X892825Y528958D01*
X892783Y528708D01*
X892617Y528500D01*
X891783Y528083D01*
X891408Y527792D01*
X891158Y527375D01*
X891075Y527000D01*
X892825D01*
G01X895050Y529500D02*
X894717Y529417D01*
X894467Y529208D01*
X894300Y528958D01*
X894175Y528625D01*
X894133Y528250D01*
X894175Y527875D01*
X894300Y527542D01*
X894467Y527292D01*
X894717Y527083D01*
X895050Y527000D01*
X895383Y527083D01*
X895633Y527292D01*
X895800Y527542D01*
X895925Y527875D01*
X895967Y528250D01*
X895925Y528625D01*
X895800Y528958D01*
X895633Y529208D01*
X895383Y529417D01*
X895050Y529500D01*
G01X898150D02*
X897817Y529417D01*
X897567Y529208D01*
X897400Y528958D01*
X897275Y528625D01*
X897233Y528250D01*
X897275Y527875D01*
X897400Y527542D01*
X897567Y527292D01*
X897817Y527083D01*
X898150Y527000D01*
X898483Y527083D01*
X898733Y527292D01*
X898900Y527542D01*
X899025Y527875D01*
X899067Y528250D01*
X899025Y528625D01*
X898900Y528958D01*
X898733Y529208D01*
X898483Y529417D01*
X898150Y529500D01*
G01X887800Y537965D02*
Y547965D01*
G01D02*
X901200D01*
G01D02*
Y537965D01*
G01D02*
X887800D01*
G01X904267Y573667D02*
Y576167D01*
X905267D01*
X905600Y576042D01*
X905850Y575750D01*
X905933Y575417D01*
X905850Y575084D01*
X905642Y574834D01*
X905267Y574709D01*
X904267D01*
G01X909033Y573667D02*
X907367D01*
Y576167D01*
X909033D01*
G01X908367Y574959D02*
X907367D01*
G01X911633Y575000D02*
X911800Y575125D01*
X911925Y575334D01*
X912008Y575625D01*
X911925Y575875D01*
X911758Y576042D01*
X911467Y576167D01*
X910342D01*
Y573667D01*
X911717D01*
X912008Y573834D01*
X912175Y574084D01*
X912258Y574375D01*
X912175Y574667D01*
X911925Y574917D01*
X911633Y575000D01*
X910342D01*
G01X916458Y573667D02*
X917500Y576167D01*
X918542Y573667D01*
G01X918167Y574542D02*
X916833D01*
G01X920600Y576167D02*
Y573667D01*
G01X919642Y576167D02*
X921558D01*
G01X923700D02*
Y573667D01*
G01X922742Y576167D02*
X924658D01*
G01X925842Y573667D02*
Y576167D01*
X927758Y573667D01*
Y576167D01*
G01X928983Y574167D02*
X929233Y573875D01*
X929567Y573709D01*
X929942Y573667D01*
X930275Y573709D01*
X930608Y573917D01*
X930817Y574167D01*
X930858Y574417D01*
X930775Y574709D01*
X930483Y574917D01*
X930192Y575000D01*
X929817D01*
G01X930192D02*
X930442Y575125D01*
X930650Y575334D01*
X930733Y575584D01*
X930650Y575834D01*
X930442Y576042D01*
X930067Y576167D01*
X929692Y576125D01*
X929317Y575959D01*
G01X937654Y591329D02*
X908754D01*
Y578429D01*
X890454D01*
Y591329D01*
X876954D01*
Y752529D01*
X890454D01*
Y765429D01*
X908754D01*
Y752529D01*
X937654D01*
Y742179D01*
X930954D01*
Y601679D01*
X937654D01*
Y591329D01*
G01X889000Y564017D02*
X891500D01*
Y565683D01*
G01Y568783D02*
Y567117D01*
X889000D01*
Y568783D01*
G01X890208Y568117D02*
Y567117D01*
G01X891500Y570133D02*
X889000D01*
Y570967D01*
X889125Y571300D01*
X889292Y571550D01*
X889542Y571758D01*
X889833Y571925D01*
X890250Y571967D01*
X890667Y571925D01*
X890958Y571758D01*
X891208Y571550D01*
X891375Y571300D01*
X891500Y570967D01*
Y570133D01*
G01X891000Y573233D02*
X891292Y573483D01*
X891458Y573817D01*
X891500Y574192D01*
X891458Y574525D01*
X891250Y574858D01*
X891000Y575067D01*
X890750Y575108D01*
X890458Y575025D01*
X890250Y574733D01*
X890167Y574442D01*
Y574067D01*
G01Y574442D02*
X890042Y574692D01*
X889833Y574900D01*
X889583Y574983D01*
X889333Y574900D01*
X889125Y574692D01*
X889000Y574317D01*
X889042Y573942D01*
X889208Y573567D01*
G01X893906Y563523D02*
Y571123D01*
X905306D01*
Y563523D01*
X893906D01*
G01X859300Y562200D02*
X858967Y562242D01*
X858675Y562408D01*
X858425Y562658D01*
X858258Y562950D01*
X858175Y563283D01*
Y563617D01*
X858258Y563950D01*
X858425Y564242D01*
X858675Y564492D01*
X858967Y564658D01*
X859300Y564700D01*
X859633Y564658D01*
X859925Y564492D01*
X860175Y564242D01*
X860342Y563950D01*
X860425Y563617D01*
Y563283D01*
X860342Y562950D01*
X860175Y562658D01*
X859925Y562408D01*
X859633Y562242D01*
X859300Y562200D01*
G01X859633Y562867D02*
X860133Y562200D01*
G01X862900D02*
Y564700D01*
X861358Y562908D01*
X863442D01*
G01X864583Y562575D02*
X864833Y562367D01*
X865125Y562242D01*
X865500Y562200D01*
X865875Y562283D01*
X866167Y562450D01*
X866375Y562742D01*
X866417Y563075D01*
X866333Y563408D01*
X866125Y563617D01*
X865833Y563783D01*
X865542Y563825D01*
X865250Y563783D01*
X864875Y563617D01*
X865000Y564700D01*
X866125D01*
G01X881000Y566465D02*
X868000D01*
G01X867567Y567900D02*
Y570400D01*
X868608D01*
X868942Y570275D01*
X869150Y570108D01*
X869233Y569775D01*
X869150Y569442D01*
X868900Y569233D01*
X868608Y569108D01*
X867567D01*
G01X868608D02*
X869233Y567900D01*
G01X870792Y568192D02*
X871083Y567983D01*
X871417Y567900D01*
X871750Y567983D01*
X872042Y568233D01*
X872250Y568608D01*
X872333Y568983D01*
Y569442D01*
X872250Y569817D01*
X872042Y570150D01*
X871792Y570317D01*
X871500Y570400D01*
X871167Y570317D01*
X870917Y570150D01*
X870750Y569900D01*
X870667Y569567D01*
X870750Y569275D01*
X870958Y568983D01*
X871208Y568817D01*
X871500Y568775D01*
X871833Y568858D01*
X872083Y569067D01*
X872333Y569442D01*
G01X874600Y567900D02*
X874892Y567942D01*
X875225Y568067D01*
X875433Y568275D01*
X875517Y568567D01*
X875433Y568858D01*
X875183Y569108D01*
X874808Y569233D01*
X874392D01*
X874142Y569317D01*
X873933Y569525D01*
X873850Y569817D01*
X873975Y570108D01*
X874267Y570317D01*
X874600Y570400D01*
X874933Y570317D01*
X875225Y570108D01*
X875350Y569817D01*
X875267Y569525D01*
X875058Y569317D01*
X874808Y569233D01*
X874392D01*
X874017Y569108D01*
X873767Y568858D01*
X873683Y568567D01*
X873767Y568275D01*
X873975Y568067D01*
X874308Y567942D01*
X874600Y567900D01*
G01X877700Y570400D02*
X877367Y570317D01*
X877117Y570108D01*
X876950Y569858D01*
X876825Y569525D01*
X876783Y569150D01*
X876825Y568775D01*
X876950Y568442D01*
X877117Y568192D01*
X877367Y567983D01*
X877700Y567900D01*
X878033Y567983D01*
X878283Y568192D01*
X878450Y568442D01*
X878575Y568775D01*
X878617Y569150D01*
X878575Y569525D01*
X878450Y569858D01*
X878283Y570108D01*
X878033Y570317D01*
X877700Y570400D01*
G01X880008Y569983D02*
X880258Y570233D01*
X880550Y570358D01*
X880883Y570400D01*
X881300Y570317D01*
X881592Y570108D01*
X881675Y569858D01*
X881633Y569608D01*
X881467Y569400D01*
X880633Y568983D01*
X880258Y568692D01*
X880008Y568275D01*
X879925Y567900D01*
X881675D01*
G01X867567Y571900D02*
Y574400D01*
X868608D01*
X868942Y574275D01*
X869150Y574108D01*
X869233Y573775D01*
X869150Y573442D01*
X868900Y573233D01*
X868608Y573108D01*
X867567D01*
G01X868608D02*
X869233Y571900D01*
G01X870792Y572192D02*
X871083Y571983D01*
X871417Y571900D01*
X871750Y571983D01*
X872042Y572233D01*
X872250Y572608D01*
X872333Y572983D01*
Y573442D01*
X872250Y573817D01*
X872042Y574150D01*
X871792Y574317D01*
X871500Y574400D01*
X871167Y574317D01*
X870917Y574150D01*
X870750Y573900D01*
X870667Y573567D01*
X870750Y573275D01*
X870958Y572983D01*
X871208Y572817D01*
X871500Y572775D01*
X871833Y572858D01*
X872083Y573067D01*
X872333Y573442D01*
G01X873892Y572192D02*
X874183Y571983D01*
X874517Y571900D01*
X874850Y571983D01*
X875142Y572233D01*
X875350Y572608D01*
X875433Y572983D01*
Y573442D01*
X875350Y573817D01*
X875142Y574150D01*
X874892Y574317D01*
X874600Y574400D01*
X874267Y574317D01*
X874017Y574150D01*
X873850Y573900D01*
X873767Y573567D01*
X873850Y573275D01*
X874058Y572983D01*
X874308Y572817D01*
X874600Y572775D01*
X874933Y572858D01*
X875183Y573067D01*
X875433Y573442D01*
G01X877700Y571900D02*
Y574400D01*
X877200Y573900D01*
G01Y571900D02*
X878200D01*
G01X879883Y572275D02*
X880133Y572067D01*
X880425Y571942D01*
X880800Y571900D01*
X881175Y571983D01*
X881467Y572150D01*
X881675Y572442D01*
X881717Y572775D01*
X881633Y573108D01*
X881425Y573317D01*
X881133Y573483D01*
X880842Y573525D01*
X880550Y573483D01*
X880175Y573317D01*
X880300Y574400D01*
X881425D01*
G01X882550Y562715D02*
Y558715D01*
X889950D01*
G01X901467Y559166D02*
Y561666D01*
X902508D01*
X902842Y561541D01*
X903050Y561374D01*
X903133Y561041D01*
X903050Y560708D01*
X902800Y560499D01*
X902508Y560374D01*
X901467D01*
G01X902508D02*
X903133Y559166D01*
G01X904692Y559458D02*
X904983Y559249D01*
X905317Y559166D01*
X905650Y559249D01*
X905942Y559499D01*
X906150Y559874D01*
X906233Y560249D01*
Y560708D01*
X906150Y561083D01*
X905942Y561416D01*
X905692Y561583D01*
X905400Y561666D01*
X905067Y561583D01*
X904817Y561416D01*
X904650Y561166D01*
X904567Y560833D01*
X904650Y560541D01*
X904858Y560249D01*
X905108Y560083D01*
X905400Y560041D01*
X905733Y560124D01*
X905983Y560333D01*
X906233Y560708D01*
G01X907792Y559458D02*
X908083Y559249D01*
X908417Y559166D01*
X908750Y559249D01*
X909042Y559499D01*
X909250Y559874D01*
X909333Y560249D01*
Y560708D01*
X909250Y561083D01*
X909042Y561416D01*
X908792Y561583D01*
X908500Y561666D01*
X908167Y561583D01*
X907917Y561416D01*
X907750Y561166D01*
X907667Y560833D01*
X907750Y560541D01*
X907958Y560249D01*
X908208Y560083D01*
X908500Y560041D01*
X908833Y560124D01*
X909083Y560333D01*
X909333Y560708D01*
G01X910683Y559666D02*
X910933Y559374D01*
X911267Y559208D01*
X911642Y559166D01*
X911975Y559208D01*
X912308Y559416D01*
X912517Y559666D01*
X912558Y559916D01*
X912475Y560208D01*
X912183Y560416D01*
X911892Y560499D01*
X911517D01*
G01X911892D02*
X912142Y560624D01*
X912350Y560833D01*
X912433Y561083D01*
X912350Y561333D01*
X912142Y561541D01*
X911767Y561666D01*
X911392Y561624D01*
X911017Y561458D01*
G01X915200Y559166D02*
Y561666D01*
X913658Y559874D01*
X915742D01*
G01X891541Y562408D02*
Y558408D01*
X898941D01*
G01X874467Y576167D02*
Y578667D01*
X875508D01*
X875842Y578542D01*
X876050Y578375D01*
X876133Y578042D01*
X876050Y577709D01*
X875800Y577500D01*
X875508Y577375D01*
X874467D01*
G01X875508D02*
X876133Y576167D01*
G01X877692Y576459D02*
X877983Y576250D01*
X878317Y576167D01*
X878650Y576250D01*
X878942Y576500D01*
X879150Y576875D01*
X879233Y577250D01*
Y577709D01*
X879150Y578084D01*
X878942Y578417D01*
X878692Y578584D01*
X878400Y578667D01*
X878067Y578584D01*
X877817Y578417D01*
X877650Y578167D01*
X877567Y577834D01*
X877650Y577542D01*
X877858Y577250D01*
X878108Y577084D01*
X878400Y577042D01*
X878733Y577125D01*
X878983Y577334D01*
X879233Y577709D01*
G01X880792Y576459D02*
X881083Y576250D01*
X881417Y576167D01*
X881750Y576250D01*
X882042Y576500D01*
X882250Y576875D01*
X882333Y577250D01*
Y577709D01*
X882250Y578084D01*
X882042Y578417D01*
X881792Y578584D01*
X881500Y578667D01*
X881167Y578584D01*
X880917Y578417D01*
X880750Y578167D01*
X880667Y577834D01*
X880750Y577542D01*
X880958Y577250D01*
X881208Y577084D01*
X881500Y577042D01*
X881833Y577125D01*
X882083Y577334D01*
X882333Y577709D01*
G01X883683Y576667D02*
X883933Y576375D01*
X884267Y576209D01*
X884642Y576167D01*
X884975Y576209D01*
X885308Y576417D01*
X885517Y576667D01*
X885558Y576917D01*
X885475Y577209D01*
X885183Y577417D01*
X884892Y577500D01*
X884517D01*
G01X884892D02*
X885142Y577625D01*
X885350Y577834D01*
X885433Y578084D01*
X885350Y578334D01*
X885142Y578542D01*
X884767Y578667D01*
X884392Y578625D01*
X884017Y578459D01*
G01X886783Y576667D02*
X887033Y576375D01*
X887367Y576209D01*
X887742Y576167D01*
X888075Y576209D01*
X888408Y576417D01*
X888617Y576667D01*
X888658Y576917D01*
X888575Y577209D01*
X888283Y577417D01*
X887992Y577500D01*
X887617D01*
G01X887992D02*
X888242Y577625D01*
X888450Y577834D01*
X888533Y578084D01*
X888450Y578334D01*
X888242Y578542D01*
X887867Y578667D01*
X887492Y578625D01*
X887117Y578459D01*
G01X901376Y572422D02*
Y576422D01*
X893976D01*
G01X848665Y701800D02*
X847832Y700467D01*
X847332Y698967D01*
Y697633D01*
X847832Y696300D01*
X848665Y695300D01*
X849832Y694800D01*
X850998Y695133D01*
X851999Y695967D01*
X852665Y697467D01*
X852999Y699467D01*
X853665Y700633D01*
X854832Y701133D01*
X855999Y700800D01*
X856832Y699967D01*
X857332Y698800D01*
Y697633D01*
X856999Y696467D01*
X856165Y695467D01*
G01X848665Y691200D02*
X847832Y689867D01*
X847332Y688367D01*
Y687033D01*
X847832Y685700D01*
X848665Y684700D01*
X849832Y684200D01*
X850998Y684533D01*
X851999Y685367D01*
X852665Y686867D01*
X852999Y688867D01*
X853665Y690033D01*
X854832Y690533D01*
X855999Y690200D01*
X856832Y689367D01*
X857332Y688200D01*
Y687033D01*
X856999Y685867D01*
X856165Y684867D01*
G01X847332Y680767D02*
X857332D01*
Y677433D01*
X856832Y676100D01*
X856165Y675100D01*
X855165Y674267D01*
X853998Y673600D01*
X852332Y673433D01*
X850665Y673600D01*
X849499Y674267D01*
X848498Y675100D01*
X847832Y676100D01*
X847332Y677433D01*
Y680767D01*
G01X849332Y670167D02*
X848165Y669167D01*
X847499Y667834D01*
X847332Y666333D01*
X847499Y665000D01*
X848332Y663667D01*
X849332Y662833D01*
X850332Y662667D01*
X851498Y663000D01*
X852332Y664167D01*
X852665Y665333D01*
Y666833D01*
G01Y665333D02*
X853165Y664333D01*
X853998Y663500D01*
X854999Y663167D01*
X855999Y663500D01*
X856832Y664333D01*
X857332Y665833D01*
X857165Y667333D01*
X856499Y668833D01*
G01X869720Y679347D02*
X869970Y679555D01*
X870137Y679805D01*
X870220Y680097D01*
X870137Y680430D01*
X869970Y680680D01*
X869720Y680930D01*
X869387Y681013D01*
X867720D01*
G01X869720Y682363D02*
X870012Y682613D01*
X870178Y682947D01*
X870220Y683322D01*
X870178Y683655D01*
X869970Y683988D01*
X869720Y684197D01*
X869470Y684238D01*
X869178Y684155D01*
X868970Y683863D01*
X868887Y683572D01*
Y683197D01*
G01Y683572D02*
X868762Y683822D01*
X868553Y684030D01*
X868303Y684113D01*
X868053Y684030D01*
X867845Y683822D01*
X867720Y683447D01*
X867762Y683072D01*
X867928Y682697D01*
G01X866000Y632917D02*
X863500D01*
Y633917D01*
X863625Y634250D01*
X863917Y634500D01*
X864250Y634583D01*
X864583Y634500D01*
X864833Y634292D01*
X864958Y633917D01*
Y632917D01*
G01X863708Y637767D02*
X863583Y637517D01*
X863500Y637225D01*
Y636892D01*
X863625Y636517D01*
X863833Y636225D01*
X864083Y636017D01*
X864500Y635850D01*
X864875Y635808D01*
X865250Y635892D01*
X865500Y636017D01*
X865750Y636267D01*
X865917Y636558D01*
X866000Y636850D01*
Y637142D01*
X865917Y637433D01*
X865792Y637683D01*
X865625Y637892D01*
G01X866000Y639950D02*
X863500D01*
X864000Y639450D01*
G01X866000D02*
Y640450D01*
G01X863917Y642258D02*
X863667Y642508D01*
X863542Y642800D01*
X863500Y643133D01*
X863583Y643550D01*
X863792Y643842D01*
X864042Y643925D01*
X864292Y643883D01*
X864500Y643717D01*
X864917Y642883D01*
X865208Y642508D01*
X865625Y642258D01*
X866000Y642175D01*
Y643925D01*
G01X863917Y645358D02*
X863667Y645608D01*
X863542Y645900D01*
X863500Y646233D01*
X863583Y646650D01*
X863792Y646942D01*
X864042Y647025D01*
X864292Y646983D01*
X864500Y646817D01*
X864917Y645983D01*
X865208Y645608D01*
X865625Y645358D01*
X866000Y645275D01*
Y647025D01*
G01X865708Y648542D02*
X865917Y648833D01*
X866000Y649167D01*
X865917Y649500D01*
X865667Y649792D01*
X865292Y650000D01*
X864917Y650083D01*
X864458D01*
X864083Y650000D01*
X863750Y649792D01*
X863583Y649542D01*
X863500Y649250D01*
X863583Y648917D01*
X863750Y648667D01*
X864000Y648500D01*
X864333Y648417D01*
X864625Y648500D01*
X864917Y648708D01*
X865083Y648958D01*
X865125Y649250D01*
X865042Y649583D01*
X864833Y649833D01*
X864458Y650083D01*
G01X868900Y718317D02*
X866400D01*
Y719317D01*
X866525Y719650D01*
X866817Y719900D01*
X867150Y719983D01*
X867483Y719900D01*
X867733Y719692D01*
X867858Y719317D01*
Y718317D01*
G01X866608Y723167D02*
X866483Y722917D01*
X866400Y722625D01*
Y722292D01*
X866525Y721917D01*
X866733Y721625D01*
X866983Y721417D01*
X867400Y721250D01*
X867775Y721208D01*
X868150Y721292D01*
X868400Y721417D01*
X868650Y721667D01*
X868817Y721958D01*
X868900Y722250D01*
Y722542D01*
X868817Y722833D01*
X868692Y723083D01*
X868525Y723292D01*
G01X868900Y725350D02*
X866400D01*
X866900Y724850D01*
G01X868900D02*
Y725850D01*
G01X866817Y727658D02*
X866567Y727908D01*
X866442Y728200D01*
X866400Y728533D01*
X866483Y728950D01*
X866692Y729242D01*
X866942Y729325D01*
X867192Y729283D01*
X867400Y729117D01*
X867817Y728283D01*
X868108Y727908D01*
X868525Y727658D01*
X868900Y727575D01*
Y729325D01*
G01X866817Y730758D02*
X866567Y731008D01*
X866442Y731300D01*
X866400Y731633D01*
X866483Y732050D01*
X866692Y732342D01*
X866942Y732425D01*
X867192Y732383D01*
X867400Y732217D01*
X867817Y731383D01*
X868108Y731008D01*
X868525Y730758D01*
X868900Y730675D01*
Y732425D01*
G01Y734650D02*
X868858Y734942D01*
X868733Y735275D01*
X868525Y735483D01*
X868233Y735567D01*
X867942Y735483D01*
X867692Y735233D01*
X867567Y734858D01*
Y734442D01*
X867483Y734192D01*
X867275Y733983D01*
X866983Y733900D01*
X866692Y734025D01*
X866483Y734317D01*
X866400Y734650D01*
X866483Y734983D01*
X866692Y735275D01*
X866983Y735400D01*
X867275Y735317D01*
X867483Y735108D01*
X867567Y734858D01*
Y734442D01*
X867692Y734067D01*
X867942Y733817D01*
X868233Y733733D01*
X868525Y733817D01*
X868733Y734025D01*
X868858Y734358D01*
X868900Y734650D01*
G01X861900Y767517D02*
X859400D01*
Y768517D01*
X859525Y768850D01*
X859817Y769100D01*
X860150Y769183D01*
X860483Y769100D01*
X860733Y768892D01*
X860858Y768517D01*
Y767517D01*
G01X859608Y772367D02*
X859483Y772117D01*
X859400Y771825D01*
Y771492D01*
X859525Y771117D01*
X859733Y770825D01*
X859983Y770617D01*
X860400Y770450D01*
X860775Y770408D01*
X861150Y770492D01*
X861400Y770617D01*
X861650Y770867D01*
X861817Y771158D01*
X861900Y771450D01*
Y771742D01*
X861817Y772033D01*
X861692Y772283D01*
X861525Y772492D01*
G01X861900Y774550D02*
X859400D01*
X859900Y774050D01*
G01X861900D02*
Y775050D01*
G01X859817Y776858D02*
X859567Y777108D01*
X859442Y777400D01*
X859400Y777733D01*
X859483Y778150D01*
X859692Y778442D01*
X859942Y778525D01*
X860192Y778483D01*
X860400Y778317D01*
X860817Y777483D01*
X861108Y777108D01*
X861525Y776858D01*
X861900Y776775D01*
Y778525D01*
G01X859817Y779958D02*
X859567Y780208D01*
X859442Y780500D01*
X859400Y780833D01*
X859483Y781250D01*
X859692Y781542D01*
X859942Y781625D01*
X860192Y781583D01*
X860400Y781417D01*
X860817Y780583D01*
X861108Y780208D01*
X861525Y779958D01*
X861900Y779875D01*
Y781625D01*
G01Y783767D02*
X861358Y783850D01*
X860900Y783975D01*
X860483Y784142D01*
X860025Y784350D01*
X859400Y784683D01*
Y783017D01*
G01X843000Y785900D02*
Y772900D01*
G01D02*
X857000D01*
G01D02*
Y785900D01*
G01X846417Y716000D02*
Y718500D01*
X847458D01*
X847792Y718375D01*
X848000Y718208D01*
X848083Y717875D01*
X848000Y717542D01*
X847750Y717333D01*
X847458Y717208D01*
X846417D01*
G01X847458D02*
X848083Y716000D01*
G01X849433Y716500D02*
X849683Y716208D01*
X850017Y716042D01*
X850392Y716000D01*
X850725Y716042D01*
X851058Y716250D01*
X851267Y716500D01*
X851308Y716750D01*
X851225Y717042D01*
X850933Y717250D01*
X850642Y717333D01*
X850267D01*
G01X850642D02*
X850892Y717458D01*
X851100Y717667D01*
X851183Y717917D01*
X851100Y718167D01*
X850892Y718375D01*
X850517Y718500D01*
X850142Y718458D01*
X849767Y718292D01*
G01X852742Y716292D02*
X853033Y716083D01*
X853367Y716000D01*
X853700Y716083D01*
X853992Y716333D01*
X854200Y716708D01*
X854283Y717083D01*
Y717542D01*
X854200Y717917D01*
X853992Y718250D01*
X853742Y718417D01*
X853450Y718500D01*
X853117Y718417D01*
X852867Y718250D01*
X852700Y718000D01*
X852617Y717667D01*
X852700Y717375D01*
X852908Y717083D01*
X853158Y716917D01*
X853450Y716875D01*
X853783Y716958D01*
X854033Y717167D01*
X854283Y717542D01*
G01X855633Y716500D02*
X855883Y716208D01*
X856217Y716042D01*
X856592Y716000D01*
X856925Y716042D01*
X857258Y716250D01*
X857467Y716500D01*
X857508Y716750D01*
X857425Y717042D01*
X857133Y717250D01*
X856842Y717333D01*
X856467D01*
G01X856842D02*
X857092Y717458D01*
X857300Y717667D01*
X857383Y717917D01*
X857300Y718167D01*
X857092Y718375D01*
X856717Y718500D01*
X856342Y718458D01*
X855967Y718292D01*
G01X858200Y724500D02*
Y728500D01*
X850800D01*
G01X846417Y720500D02*
Y723000D01*
X847458D01*
X847792Y722875D01*
X848000Y722708D01*
X848083Y722375D01*
X848000Y722042D01*
X847750Y721833D01*
X847458Y721708D01*
X846417D01*
G01X847458D02*
X848083Y720500D01*
G01X849433Y721000D02*
X849683Y720708D01*
X850017Y720542D01*
X850392Y720500D01*
X850725Y720542D01*
X851058Y720750D01*
X851267Y721000D01*
X851308Y721250D01*
X851225Y721542D01*
X850933Y721750D01*
X850642Y721833D01*
X850267D01*
G01X850642D02*
X850892Y721958D01*
X851100Y722167D01*
X851183Y722417D01*
X851100Y722667D01*
X850892Y722875D01*
X850517Y723000D01*
X850142Y722958D01*
X849767Y722792D01*
G01X852742Y720792D02*
X853033Y720583D01*
X853367Y720500D01*
X853700Y720583D01*
X853992Y720833D01*
X854200Y721208D01*
X854283Y721583D01*
Y722042D01*
X854200Y722417D01*
X853992Y722750D01*
X853742Y722917D01*
X853450Y723000D01*
X853117Y722917D01*
X852867Y722750D01*
X852700Y722500D01*
X852617Y722167D01*
X852700Y721875D01*
X852908Y721583D01*
X853158Y721417D01*
X853450Y721375D01*
X853783Y721458D01*
X854033Y721667D01*
X854283Y722042D01*
G01X857050Y720500D02*
Y723000D01*
X855508Y721208D01*
X857592D01*
G01X858200Y729500D02*
Y733500D01*
X850800D01*
G01X848200Y742200D02*
X844200D01*
Y734800D01*
G01X842167Y724875D02*
X842375Y725208D01*
X842500Y725583D01*
Y725917D01*
X842375Y726250D01*
X842167Y726500D01*
X841875Y726625D01*
X841583Y726542D01*
X841333Y726333D01*
X841167Y725958D01*
X841083Y725458D01*
X840917Y725167D01*
X840625Y725042D01*
X840333Y725125D01*
X840125Y725333D01*
X840000Y725625D01*
Y725917D01*
X840083Y726208D01*
X840292Y726458D01*
G01X842500Y728017D02*
X840000D01*
Y729058D01*
X840125Y729392D01*
X840292Y729600D01*
X840625Y729683D01*
X840958Y729600D01*
X841167Y729350D01*
X841292Y729058D01*
Y728017D01*
G01Y729058D02*
X842500Y729683D01*
G01Y731950D02*
X840000D01*
X840500Y731450D01*
G01X842500D02*
Y732450D01*
G01X840000Y735050D02*
X840083Y734717D01*
X840292Y734467D01*
X840542Y734300D01*
X840875Y734175D01*
X841250Y734133D01*
X841625Y734175D01*
X841958Y734300D01*
X842208Y734467D01*
X842417Y734717D01*
X842500Y735050D01*
X842417Y735383D01*
X842208Y735633D01*
X841958Y735800D01*
X841625Y735925D01*
X841250Y735967D01*
X840875Y735925D01*
X840542Y735800D01*
X840292Y735633D01*
X840083Y735383D01*
X840000Y735050D01*
G01X842208Y737442D02*
X842417Y737733D01*
X842500Y738067D01*
X842417Y738400D01*
X842167Y738692D01*
X841792Y738900D01*
X841417Y738983D01*
X840958D01*
X840583Y738900D01*
X840250Y738692D01*
X840083Y738442D01*
X840000Y738150D01*
X840083Y737817D01*
X840250Y737567D01*
X840500Y737400D01*
X840833Y737317D01*
X841125Y737400D01*
X841417Y737608D01*
X841583Y737858D01*
X841625Y738150D01*
X841542Y738483D01*
X841333Y738733D01*
X840958Y738983D01*
G01X842500Y741250D02*
X842458Y741542D01*
X842333Y741875D01*
X842125Y742083D01*
X841833Y742167D01*
X841542Y742083D01*
X841292Y741833D01*
X841167Y741458D01*
Y741042D01*
X841083Y740792D01*
X840875Y740583D01*
X840583Y740500D01*
X840292Y740625D01*
X840083Y740917D01*
X840000Y741250D01*
X840083Y741583D01*
X840292Y741875D01*
X840583Y742000D01*
X840875Y741917D01*
X841083Y741708D01*
X841167Y741458D01*
Y741042D01*
X841292Y740667D01*
X841542Y740417D01*
X841833Y740333D01*
X842125Y740417D01*
X842333Y740625D01*
X842458Y740958D01*
X842500Y741250D01*
G01X854100Y734800D02*
X858100D01*
Y742200D01*
G01X846983Y771000D02*
Y769208D01*
X847150Y768833D01*
X847483Y768583D01*
X847900Y768500D01*
X848317Y768583D01*
X848650Y768833D01*
X848817Y769208D01*
Y771000D01*
G01X851000Y768500D02*
Y771000D01*
X850500Y770500D01*
G01Y768500D02*
X851500D01*
G01X853308Y770583D02*
X853558Y770833D01*
X853850Y770958D01*
X854183Y771000D01*
X854600Y770917D01*
X854892Y770708D01*
X854975Y770458D01*
X854933Y770208D01*
X854767Y770000D01*
X853933Y769583D01*
X853558Y769292D01*
X853308Y768875D01*
X853225Y768500D01*
X854975D01*
G01X839900Y766300D02*
Y747100D01*
X851100D01*
Y766300D01*
X839900D01*
G01X847500D02*
X845500Y764300D01*
X843500Y766300D01*
G01X911700Y768100D02*
Y781100D01*
G01X885700Y768100D02*
X911700D01*
G01X885700Y781100D02*
Y768100D01*
G01X884800Y754017D02*
X882300D01*
Y755017D01*
X882425Y755350D01*
X882717Y755600D01*
X883050Y755683D01*
X883383Y755600D01*
X883633Y755392D01*
X883758Y755017D01*
Y754017D01*
G01X882508Y758867D02*
X882383Y758617D01*
X882300Y758325D01*
Y757992D01*
X882425Y757617D01*
X882633Y757325D01*
X882883Y757117D01*
X883300Y756950D01*
X883675Y756908D01*
X884050Y756992D01*
X884300Y757117D01*
X884550Y757367D01*
X884717Y757658D01*
X884800Y757950D01*
Y758242D01*
X884717Y758533D01*
X884592Y758783D01*
X884425Y758992D01*
G01X884800Y761050D02*
X882300D01*
X882800Y760550D01*
G01X884800D02*
Y761550D01*
G01X882717Y763358D02*
X882467Y763608D01*
X882342Y763900D01*
X882300Y764233D01*
X882383Y764650D01*
X882592Y764942D01*
X882842Y765025D01*
X883092Y764983D01*
X883300Y764817D01*
X883717Y763983D01*
X884008Y763608D01*
X884425Y763358D01*
X884800Y763275D01*
Y765025D01*
G01X882717Y766458D02*
X882467Y766708D01*
X882342Y767000D01*
X882300Y767333D01*
X882383Y767750D01*
X882592Y768042D01*
X882842Y768125D01*
X883092Y768083D01*
X883300Y767917D01*
X883717Y767083D01*
X884008Y766708D01*
X884425Y766458D01*
X884800Y766375D01*
Y768125D01*
G01X884425Y769433D02*
X884633Y769683D01*
X884758Y769975D01*
X884800Y770350D01*
X884717Y770725D01*
X884550Y771017D01*
X884258Y771225D01*
X883925Y771267D01*
X883592Y771183D01*
X883383Y770975D01*
X883217Y770683D01*
X883175Y770392D01*
X883217Y770100D01*
X883383Y769725D01*
X882300Y769850D01*
Y770975D01*
G01X879150Y774850D02*
Y756150D01*
X868850D01*
Y774850D01*
X879150D01*
G01X861800Y718217D02*
X859300D01*
Y719217D01*
X859425Y719550D01*
X859717Y719800D01*
X860050Y719883D01*
X860383Y719800D01*
X860633Y719592D01*
X860758Y719217D01*
Y718217D01*
G01X859508Y723067D02*
X859383Y722817D01*
X859300Y722525D01*
Y722192D01*
X859425Y721817D01*
X859633Y721525D01*
X859883Y721317D01*
X860300Y721150D01*
X860675Y721108D01*
X861050Y721192D01*
X861300Y721317D01*
X861550Y721567D01*
X861717Y721858D01*
X861800Y722150D01*
Y722442D01*
X861717Y722733D01*
X861592Y722983D01*
X861425Y723192D01*
G01X861800Y725250D02*
X859300D01*
X859800Y724750D01*
G01X861800D02*
Y725750D01*
G01X859717Y727558D02*
X859467Y727808D01*
X859342Y728100D01*
X859300Y728433D01*
X859383Y728850D01*
X859592Y729142D01*
X859842Y729225D01*
X860092Y729183D01*
X860300Y729017D01*
X860717Y728183D01*
X861008Y727808D01*
X861425Y727558D01*
X861800Y727475D01*
Y729225D01*
G01X859717Y730658D02*
X859467Y730908D01*
X859342Y731200D01*
X859300Y731533D01*
X859383Y731950D01*
X859592Y732242D01*
X859842Y732325D01*
X860092Y732283D01*
X860300Y732117D01*
X860717Y731283D01*
X861008Y730908D01*
X861425Y730658D01*
X861800Y730575D01*
Y732325D01*
G01X860758Y733758D02*
X860467Y734050D01*
X860300Y734300D01*
X860217Y734633D01*
X860300Y734925D01*
X860467Y735133D01*
X860717Y735300D01*
X861008Y735342D01*
X861258Y735300D01*
X861508Y735133D01*
X861717Y734883D01*
X861800Y734592D01*
X861717Y734258D01*
X861467Y733967D01*
X861092Y733800D01*
X860675Y733758D01*
X860133Y733842D01*
X859842Y733967D01*
X859550Y734175D01*
X859342Y734467D01*
X859300Y734758D01*
X859383Y735050D01*
X859592Y735258D01*
G01X860950Y736450D02*
Y755150D01*
X871250D01*
Y736450D01*
X860950D01*
G01X847900Y787500D02*
X847567Y787542D01*
X847275Y787708D01*
X847025Y787958D01*
X846858Y788250D01*
X846775Y788583D01*
Y788917D01*
X846858Y789250D01*
X847025Y789542D01*
X847275Y789792D01*
X847567Y789958D01*
X847900Y790000D01*
X848233Y789958D01*
X848525Y789792D01*
X848775Y789542D01*
X848942Y789250D01*
X849025Y788917D01*
Y788583D01*
X848942Y788250D01*
X848775Y787958D01*
X848525Y787708D01*
X848233Y787542D01*
X847900Y787500D01*
G01X848233Y788167D02*
X848733Y787500D01*
G01X851500D02*
Y790000D01*
X849958Y788208D01*
X852042D01*
G01X854100Y787500D02*
Y790000D01*
X853600Y789500D01*
G01Y787500D02*
X854600D01*
G01X857000Y785900D02*
X843000D01*
G01X842000Y789467D02*
X839500D01*
Y790508D01*
X839625Y790842D01*
X839792Y791050D01*
X840125Y791133D01*
X840458Y791050D01*
X840667Y790800D01*
X840792Y790508D01*
Y789467D01*
G01Y790508D02*
X842000Y791133D01*
G01X841708Y792692D02*
X841917Y792983D01*
X842000Y793317D01*
X841917Y793650D01*
X841667Y793942D01*
X841292Y794150D01*
X840917Y794233D01*
X840458D01*
X840083Y794150D01*
X839750Y793942D01*
X839583Y793692D01*
X839500Y793400D01*
X839583Y793067D01*
X839750Y792817D01*
X840000Y792650D01*
X840333Y792567D01*
X840625Y792650D01*
X840917Y792858D01*
X841083Y793108D01*
X841125Y793400D01*
X841042Y793733D01*
X840833Y793983D01*
X840458Y794233D01*
G01X842000Y796500D02*
X841958Y796792D01*
X841833Y797125D01*
X841625Y797333D01*
X841333Y797417D01*
X841042Y797333D01*
X840792Y797083D01*
X840667Y796708D01*
Y796292D01*
X840583Y796042D01*
X840375Y795833D01*
X840083Y795750D01*
X839792Y795875D01*
X839583Y796167D01*
X839500Y796500D01*
X839583Y796833D01*
X839792Y797125D01*
X840083Y797250D01*
X840375Y797167D01*
X840583Y796958D01*
X840667Y796708D01*
Y796292D01*
X840792Y795917D01*
X841042Y795667D01*
X841333Y795583D01*
X841625Y795667D01*
X841833Y795875D01*
X841958Y796208D01*
X842000Y796500D01*
G01X839500Y799600D02*
X839583Y799267D01*
X839792Y799017D01*
X840042Y798850D01*
X840375Y798725D01*
X840750Y798683D01*
X841125Y798725D01*
X841458Y798850D01*
X841708Y799017D01*
X841917Y799267D01*
X842000Y799600D01*
X841917Y799933D01*
X841708Y800183D01*
X841458Y800350D01*
X841125Y800475D01*
X840750Y800517D01*
X840375Y800475D01*
X840042Y800350D01*
X839792Y800183D01*
X839583Y799933D01*
X839500Y799600D01*
G01Y802700D02*
X839583Y802367D01*
X839792Y802117D01*
X840042Y801950D01*
X840375Y801825D01*
X840750Y801783D01*
X841125Y801825D01*
X841458Y801950D01*
X841708Y802117D01*
X841917Y802367D01*
X842000Y802700D01*
X841917Y803033D01*
X841708Y803283D01*
X841458Y803450D01*
X841125Y803575D01*
X840750Y803617D01*
X840375Y803575D01*
X840042Y803450D01*
X839792Y803283D01*
X839583Y803033D01*
X839500Y802700D01*
G01X863817Y787000D02*
Y789500D01*
X864858D01*
X865192Y789375D01*
X865400Y789208D01*
X865483Y788875D01*
X865400Y788542D01*
X865150Y788333D01*
X864858Y788208D01*
X863817D01*
G01X864858D02*
X865483Y787000D01*
G01X867042Y787292D02*
X867333Y787083D01*
X867667Y787000D01*
X868000Y787083D01*
X868292Y787333D01*
X868500Y787708D01*
X868583Y788083D01*
Y788542D01*
X868500Y788917D01*
X868292Y789250D01*
X868042Y789417D01*
X867750Y789500D01*
X867417Y789417D01*
X867167Y789250D01*
X867000Y789000D01*
X866917Y788667D01*
X867000Y788375D01*
X867208Y788083D01*
X867458Y787917D01*
X867750Y787875D01*
X868083Y787958D01*
X868333Y788167D01*
X868583Y788542D01*
G01X870767Y787000D02*
X870850Y787542D01*
X870975Y788000D01*
X871142Y788417D01*
X871350Y788875D01*
X871683Y789500D01*
X870017D01*
G01X873242Y787292D02*
X873533Y787083D01*
X873867Y787000D01*
X874200Y787083D01*
X874492Y787333D01*
X874700Y787708D01*
X874783Y788083D01*
Y788542D01*
X874700Y788917D01*
X874492Y789250D01*
X874242Y789417D01*
X873950Y789500D01*
X873617Y789417D01*
X873367Y789250D01*
X873200Y789000D01*
X873117Y788667D01*
X873200Y788375D01*
X873408Y788083D01*
X873658Y787917D01*
X873950Y787875D01*
X874283Y787958D01*
X874533Y788167D01*
X874783Y788542D01*
G01X877050Y787000D02*
X877342Y787042D01*
X877675Y787167D01*
X877883Y787375D01*
X877967Y787667D01*
X877883Y787958D01*
X877633Y788208D01*
X877258Y788333D01*
X876842D01*
X876592Y788417D01*
X876383Y788625D01*
X876300Y788917D01*
X876425Y789208D01*
X876717Y789417D01*
X877050Y789500D01*
X877383Y789417D01*
X877675Y789208D01*
X877800Y788917D01*
X877717Y788625D01*
X877508Y788417D01*
X877258Y788333D01*
X876842D01*
X876467Y788208D01*
X876217Y787958D01*
X876133Y787667D01*
X876217Y787375D01*
X876425Y787167D01*
X876758Y787042D01*
X877050Y787000D01*
G01X876800Y778400D02*
X871600D01*
G01X876800Y785400D02*
X869000D01*
G01X876800Y778400D02*
Y785400D01*
G01X863400Y778400D02*
X872100D01*
G01X863400Y785400D02*
Y778400D01*
G01X869800Y785400D02*
X863400D01*
G01X898367Y782400D02*
Y784900D01*
X899408D01*
X899742Y784775D01*
X899950Y784608D01*
X900033Y784275D01*
X899950Y783942D01*
X899700Y783733D01*
X899408Y783608D01*
X898367D01*
G01X899408D02*
X900033Y782400D01*
G01X901592Y782692D02*
X901883Y782483D01*
X902217Y782400D01*
X902550Y782483D01*
X902842Y782733D01*
X903050Y783108D01*
X903133Y783483D01*
Y783942D01*
X903050Y784317D01*
X902842Y784650D01*
X902592Y784817D01*
X902300Y784900D01*
X901967Y784817D01*
X901717Y784650D01*
X901550Y784400D01*
X901467Y784067D01*
X901550Y783775D01*
X901758Y783483D01*
X902008Y783317D01*
X902300Y783275D01*
X902633Y783358D01*
X902883Y783567D01*
X903133Y783942D01*
G01X904608Y784483D02*
X904858Y784733D01*
X905150Y784858D01*
X905483Y784900D01*
X905900Y784817D01*
X906192Y784608D01*
X906275Y784358D01*
X906233Y784108D01*
X906067Y783900D01*
X905233Y783483D01*
X904858Y783192D01*
X904608Y782775D01*
X904525Y782400D01*
X906275D01*
G01X907708Y783442D02*
X908000Y783733D01*
X908250Y783900D01*
X908583Y783983D01*
X908875Y783900D01*
X909083Y783733D01*
X909250Y783483D01*
X909292Y783192D01*
X909250Y782942D01*
X909083Y782692D01*
X908833Y782483D01*
X908542Y782400D01*
X908208Y782483D01*
X907917Y782733D01*
X907750Y783108D01*
X907708Y783525D01*
X907792Y784067D01*
X907917Y784358D01*
X908125Y784650D01*
X908417Y784858D01*
X908708Y784900D01*
X909000Y784817D01*
X909208Y784608D01*
G01X911600Y782400D02*
Y784900D01*
X911100Y784400D01*
G01Y782400D02*
X912100D01*
G01X911700Y781100D02*
X885700D01*
G01X893567Y979367D02*
Y981867D01*
X894567D01*
X894900Y981742D01*
X895150Y981450D01*
X895233Y981117D01*
X895150Y980784D01*
X894942Y980534D01*
X894567Y980409D01*
X893567D01*
G01X898333Y979367D02*
X896667D01*
Y981867D01*
X898333D01*
G01X897667Y980659D02*
X896667D01*
G01X900933Y980700D02*
X901100Y980825D01*
X901225Y981034D01*
X901308Y981325D01*
X901225Y981575D01*
X901058Y981742D01*
X900767Y981867D01*
X899642D01*
Y979367D01*
X901017D01*
X901308Y979534D01*
X901475Y979784D01*
X901558Y980075D01*
X901475Y980367D01*
X901225Y980617D01*
X900933Y980700D01*
X899642D01*
G01X905758Y979367D02*
X906800Y981867D01*
X907842Y979367D01*
G01X907467Y980242D02*
X906133D01*
G01X909900Y981867D02*
Y979367D01*
G01X908942Y981867D02*
X910858D01*
G01X913000D02*
Y979367D01*
G01X912042Y981867D02*
X913958D01*
G01X915142Y979367D02*
Y981867D01*
X917058Y979367D01*
Y981867D01*
G01X918408Y981450D02*
X918658Y981700D01*
X918950Y981825D01*
X919283Y981867D01*
X919700Y981784D01*
X919992Y981575D01*
X920075Y981325D01*
X920033Y981075D01*
X919867Y980867D01*
X919033Y980450D01*
X918658Y980159D01*
X918408Y979742D01*
X918325Y979367D01*
X920075D01*
G01X937654Y996841D02*
X908754D01*
Y983941D01*
X890454D01*
Y996841D01*
X876954D01*
Y1158041D01*
X890454D01*
Y1170941D01*
X908754D01*
Y1158041D01*
X937654D01*
Y1147691D01*
X930954D01*
Y1007191D01*
X937654D01*
Y996841D01*
G01X900317Y967667D02*
Y965167D01*
X901983D01*
G01X905083D02*
X903417D01*
Y967667D01*
X905083D01*
G01X904417Y966459D02*
X903417D01*
G01X906433Y965167D02*
Y967667D01*
X907267D01*
X907600Y967542D01*
X907850Y967375D01*
X908058Y967125D01*
X908225Y966834D01*
X908267Y966417D01*
X908225Y966000D01*
X908058Y965709D01*
X907850Y965459D01*
X907600Y965292D01*
X907267Y965167D01*
X906433D01*
G01X909658Y967250D02*
X909908Y967500D01*
X910200Y967625D01*
X910533Y967667D01*
X910950Y967584D01*
X911242Y967375D01*
X911325Y967125D01*
X911283Y966875D01*
X911117Y966667D01*
X910283Y966250D01*
X909908Y965959D01*
X909658Y965542D01*
X909575Y965167D01*
X911325D01*
G01X893906Y969035D02*
Y976635D01*
X905306D01*
Y969035D01*
X893906D01*
G01X903208Y931717D02*
X903083Y931467D01*
X903000Y931175D01*
Y930842D01*
X903125Y930467D01*
X903333Y930175D01*
X903583Y929967D01*
X904000Y929800D01*
X904375Y929758D01*
X904750Y929842D01*
X905000Y929967D01*
X905250Y930217D01*
X905417Y930508D01*
X905500Y930800D01*
Y931092D01*
X905417Y931383D01*
X905292Y931633D01*
X905125Y931842D01*
G01X905208Y933192D02*
X905417Y933483D01*
X905500Y933817D01*
X905417Y934150D01*
X905167Y934442D01*
X904792Y934650D01*
X904417Y934733D01*
X903958D01*
X903583Y934650D01*
X903250Y934442D01*
X903083Y934192D01*
X903000Y933900D01*
X903083Y933567D01*
X903250Y933317D01*
X903500Y933150D01*
X903833Y933067D01*
X904125Y933150D01*
X904417Y933358D01*
X904583Y933608D01*
X904625Y933900D01*
X904542Y934233D01*
X904333Y934483D01*
X903958Y934733D01*
G01X905125Y936083D02*
X905333Y936333D01*
X905458Y936625D01*
X905500Y937000D01*
X905417Y937375D01*
X905250Y937667D01*
X904958Y937875D01*
X904625Y937917D01*
X904292Y937833D01*
X904083Y937625D01*
X903917Y937333D01*
X903875Y937042D01*
X903917Y936750D01*
X904083Y936375D01*
X903000Y936500D01*
Y937625D01*
G01X903417Y939308D02*
X903167Y939558D01*
X903042Y939850D01*
X903000Y940183D01*
X903083Y940600D01*
X903292Y940892D01*
X903542Y940975D01*
X903792Y940933D01*
X904000Y940767D01*
X904417Y939933D01*
X904708Y939558D01*
X905125Y939308D01*
X905500Y939225D01*
Y940975D01*
G01X903000Y943200D02*
X903083Y942867D01*
X903292Y942617D01*
X903542Y942450D01*
X903875Y942325D01*
X904250Y942283D01*
X904625Y942325D01*
X904958Y942450D01*
X905208Y942617D01*
X905417Y942867D01*
X905500Y943200D01*
X905417Y943533D01*
X905208Y943783D01*
X904958Y943950D01*
X904625Y944075D01*
X904250Y944117D01*
X903875Y944075D01*
X903542Y943950D01*
X903292Y943783D01*
X903083Y943533D01*
X903000Y943200D01*
G01X862400Y937500D02*
X862067Y937542D01*
X861775Y937708D01*
X861525Y937958D01*
X861358Y938250D01*
X861275Y938583D01*
Y938917D01*
X861358Y939250D01*
X861525Y939542D01*
X861775Y939792D01*
X862067Y939958D01*
X862400Y940000D01*
X862733Y939958D01*
X863025Y939792D01*
X863275Y939542D01*
X863442Y939250D01*
X863525Y938917D01*
Y938583D01*
X863442Y938250D01*
X863275Y937958D01*
X863025Y937708D01*
X862733Y937542D01*
X862400Y937500D01*
G01X862733Y938167D02*
X863233Y937500D01*
G01X864583Y938000D02*
X864833Y937708D01*
X865167Y937542D01*
X865542Y937500D01*
X865875Y937542D01*
X866208Y937750D01*
X866417Y938000D01*
X866458Y938250D01*
X866375Y938542D01*
X866083Y938750D01*
X865792Y938833D01*
X865417D01*
G01X865792D02*
X866042Y938958D01*
X866250Y939167D01*
X866333Y939417D01*
X866250Y939667D01*
X866042Y939875D01*
X865667Y940000D01*
X865292Y939958D01*
X864917Y939792D01*
G01X867892Y937792D02*
X868183Y937583D01*
X868517Y937500D01*
X868850Y937583D01*
X869142Y937833D01*
X869350Y938208D01*
X869433Y938583D01*
Y939042D01*
X869350Y939417D01*
X869142Y939750D01*
X868892Y939917D01*
X868600Y940000D01*
X868267Y939917D01*
X868017Y939750D01*
X867850Y939500D01*
X867767Y939167D01*
X867850Y938875D01*
X868058Y938583D01*
X868308Y938417D01*
X868600Y938375D01*
X868933Y938458D01*
X869183Y938667D01*
X869433Y939042D01*
G01X862500Y941977D02*
X875500D01*
G01D02*
Y955977D01*
G01D02*
X862500D01*
G01D02*
Y941977D01*
G01X857800Y967600D02*
X857467Y967642D01*
X857175Y967808D01*
X856925Y968058D01*
X856758Y968350D01*
X856675Y968683D01*
Y969017D01*
X856758Y969350D01*
X856925Y969642D01*
X857175Y969892D01*
X857467Y970058D01*
X857800Y970100D01*
X858133Y970058D01*
X858425Y969892D01*
X858675Y969642D01*
X858842Y969350D01*
X858925Y969017D01*
Y968683D01*
X858842Y968350D01*
X858675Y968058D01*
X858425Y967808D01*
X858133Y967642D01*
X857800Y967600D01*
G01X858133Y968267D02*
X858633Y967600D01*
G01X861400D02*
Y970100D01*
X859858Y968308D01*
X861942D01*
G01X864000Y970100D02*
X863667Y970017D01*
X863417Y969808D01*
X863250Y969558D01*
X863125Y969225D01*
X863083Y968850D01*
X863125Y968475D01*
X863250Y968142D01*
X863417Y967892D01*
X863667Y967683D01*
X864000Y967600D01*
X864333Y967683D01*
X864583Y967892D01*
X864750Y968142D01*
X864875Y968475D01*
X864917Y968850D01*
X864875Y969225D01*
X864750Y969558D01*
X864583Y969808D01*
X864333Y970017D01*
X864000Y970100D01*
G01X868000Y957977D02*
X881000D01*
G01D02*
Y971977D01*
G01D02*
X868000D01*
G01D02*
Y957977D01*
G01X847375Y963333D02*
X847708Y963125D01*
X848083Y963000D01*
X848417D01*
X848750Y963125D01*
X849000Y963333D01*
X849125Y963625D01*
X849042Y963917D01*
X848833Y964167D01*
X848458Y964333D01*
X847958Y964417D01*
X847667Y964583D01*
X847542Y964875D01*
X847625Y965167D01*
X847833Y965375D01*
X848125Y965500D01*
X848417D01*
X848708Y965417D01*
X848958Y965208D01*
G01X850517Y963000D02*
Y965500D01*
X851558D01*
X851892Y965375D01*
X852100Y965208D01*
X852183Y964875D01*
X852100Y964542D01*
X851850Y964333D01*
X851558Y964208D01*
X850517D01*
G01X851558D02*
X852183Y963000D01*
G01X854450D02*
Y965500D01*
X853950Y965000D01*
G01Y963000D02*
X854950D01*
G01X857550D02*
Y965500D01*
X857050Y965000D01*
G01Y963000D02*
X858050D01*
G01X859858Y965083D02*
X860108Y965333D01*
X860400Y965458D01*
X860733Y965500D01*
X861150Y965417D01*
X861442Y965208D01*
X861525Y964958D01*
X861483Y964708D01*
X861317Y964500D01*
X860483Y964083D01*
X860108Y963792D01*
X859858Y963375D01*
X859775Y963000D01*
X861525D01*
G01X862833Y963375D02*
X863083Y963167D01*
X863375Y963042D01*
X863750Y963000D01*
X864125Y963083D01*
X864417Y963250D01*
X864625Y963542D01*
X864667Y963875D01*
X864583Y964208D01*
X864375Y964417D01*
X864083Y964583D01*
X863792Y964625D01*
X863500Y964583D01*
X863125Y964417D01*
X863250Y965500D01*
X864375D01*
G01X859800Y960977D02*
Y956977D01*
X867200D01*
G01X857267Y977200D02*
Y979700D01*
X858308D01*
X858642Y979575D01*
X858850Y979408D01*
X858933Y979075D01*
X858850Y978742D01*
X858600Y978533D01*
X858308Y978408D01*
X857267D01*
G01X858308D02*
X858933Y977200D01*
G01X860492Y977492D02*
X860783Y977283D01*
X861117Y977200D01*
X861450Y977283D01*
X861742Y977533D01*
X861950Y977908D01*
X862033Y978283D01*
Y978742D01*
X861950Y979117D01*
X861742Y979450D01*
X861492Y979617D01*
X861200Y979700D01*
X860867Y979617D01*
X860617Y979450D01*
X860450Y979200D01*
X860367Y978867D01*
X860450Y978575D01*
X860658Y978283D01*
X860908Y978117D01*
X861200Y978075D01*
X861533Y978158D01*
X861783Y978367D01*
X862033Y978742D01*
G01X864217Y977200D02*
X864300Y977742D01*
X864425Y978200D01*
X864592Y978617D01*
X864800Y979075D01*
X865133Y979700D01*
X863467D01*
G01X866692Y977492D02*
X866983Y977283D01*
X867317Y977200D01*
X867650Y977283D01*
X867942Y977533D01*
X868150Y977908D01*
X868233Y978283D01*
Y978742D01*
X868150Y979117D01*
X867942Y979450D01*
X867692Y979617D01*
X867400Y979700D01*
X867067Y979617D01*
X866817Y979450D01*
X866650Y979200D01*
X866567Y978867D01*
X866650Y978575D01*
X866858Y978283D01*
X867108Y978117D01*
X867400Y978075D01*
X867733Y978158D01*
X867983Y978367D01*
X868233Y978742D01*
G01X869708Y978242D02*
X870000Y978533D01*
X870250Y978700D01*
X870583Y978783D01*
X870875Y978700D01*
X871083Y978533D01*
X871250Y978283D01*
X871292Y977992D01*
X871250Y977742D01*
X871083Y977492D01*
X870833Y977283D01*
X870542Y977200D01*
X870208Y977283D01*
X869917Y977533D01*
X869750Y977908D01*
X869708Y978325D01*
X869792Y978867D01*
X869917Y979158D01*
X870125Y979450D01*
X870417Y979658D01*
X870708Y979700D01*
X871000Y979617D01*
X871208Y979408D01*
G01X882550Y964227D02*
Y960227D01*
X889950D01*
G01X912700Y936167D02*
X910200D01*
Y937208D01*
X910325Y937542D01*
X910492Y937750D01*
X910825Y937833D01*
X911158Y937750D01*
X911367Y937500D01*
X911492Y937208D01*
Y936167D01*
G01Y937208D02*
X912700Y937833D01*
G01X912408Y939392D02*
X912617Y939683D01*
X912700Y940017D01*
X912617Y940350D01*
X912367Y940642D01*
X911992Y940850D01*
X911617Y940933D01*
X911158D01*
X910783Y940850D01*
X910450Y940642D01*
X910283Y940392D01*
X910200Y940100D01*
X910283Y939767D01*
X910450Y939517D01*
X910700Y939350D01*
X911033Y939267D01*
X911325Y939350D01*
X911617Y939558D01*
X911783Y939808D01*
X911825Y940100D01*
X911742Y940433D01*
X911533Y940683D01*
X911158Y940933D01*
G01X912700Y943117D02*
X912158Y943200D01*
X911700Y943325D01*
X911283Y943492D01*
X910825Y943700D01*
X910200Y944033D01*
Y942367D01*
G01X912408Y945592D02*
X912617Y945883D01*
X912700Y946217D01*
X912617Y946550D01*
X912367Y946842D01*
X911992Y947050D01*
X911617Y947133D01*
X911158D01*
X910783Y947050D01*
X910450Y946842D01*
X910283Y946592D01*
X910200Y946300D01*
X910283Y945967D01*
X910450Y945717D01*
X910700Y945550D01*
X911033Y945467D01*
X911325Y945550D01*
X911617Y945758D01*
X911783Y946008D01*
X911825Y946300D01*
X911742Y946633D01*
X911533Y946883D01*
X911158Y947133D01*
G01X912700Y949317D02*
X912158Y949400D01*
X911700Y949525D01*
X911283Y949692D01*
X910825Y949900D01*
X910200Y950233D01*
Y948567D01*
G01X911700Y955477D02*
Y959477D01*
X904300D01*
G01X882875Y939333D02*
X883208Y939125D01*
X883583Y939000D01*
X883917D01*
X884250Y939125D01*
X884500Y939333D01*
X884625Y939625D01*
X884542Y939917D01*
X884333Y940167D01*
X883958Y940333D01*
X883458Y940417D01*
X883167Y940583D01*
X883042Y940875D01*
X883125Y941167D01*
X883333Y941375D01*
X883625Y941500D01*
X883917D01*
X884208Y941417D01*
X884458Y941208D01*
G01X886017Y939000D02*
Y941500D01*
X887058D01*
X887392Y941375D01*
X887600Y941208D01*
X887683Y940875D01*
X887600Y940542D01*
X887350Y940333D01*
X887058Y940208D01*
X886017D01*
G01X887058D02*
X887683Y939000D01*
G01X889950D02*
Y941500D01*
X889450Y941000D01*
G01Y939000D02*
X890450D01*
G01X893050D02*
Y941500D01*
X892550Y941000D01*
G01Y939000D02*
X893550D01*
G01X895358Y941083D02*
X895608Y941333D01*
X895900Y941458D01*
X896233Y941500D01*
X896650Y941417D01*
X896942Y941208D01*
X897025Y940958D01*
X896983Y940708D01*
X896817Y940500D01*
X895983Y940083D01*
X895608Y939792D01*
X895358Y939375D01*
X895275Y939000D01*
X897025D01*
G01X898458Y940042D02*
X898750Y940333D01*
X899000Y940500D01*
X899333Y940583D01*
X899625Y940500D01*
X899833Y940333D01*
X900000Y940083D01*
X900042Y939792D01*
X900000Y939542D01*
X899833Y939292D01*
X899583Y939083D01*
X899292Y939000D01*
X898958Y939083D01*
X898667Y939333D01*
X898500Y939708D01*
X898458Y940125D01*
X898542Y940667D01*
X898667Y940958D01*
X898875Y941250D01*
X899167Y941458D01*
X899458Y941500D01*
X899750Y941417D01*
X899958Y941208D01*
G01X896648Y956277D02*
X900648D01*
Y963677D01*
G01X857267Y981200D02*
Y983700D01*
X858308D01*
X858642Y983575D01*
X858850Y983408D01*
X858933Y983075D01*
X858850Y982742D01*
X858600Y982533D01*
X858308Y982408D01*
X857267D01*
G01X858308D02*
X858933Y981200D01*
G01X860492Y981492D02*
X860783Y981283D01*
X861117Y981200D01*
X861450Y981283D01*
X861742Y981533D01*
X861950Y981908D01*
X862033Y982283D01*
Y982742D01*
X861950Y983117D01*
X861742Y983450D01*
X861492Y983617D01*
X861200Y983700D01*
X860867Y983617D01*
X860617Y983450D01*
X860450Y983200D01*
X860367Y982867D01*
X860450Y982575D01*
X860658Y982283D01*
X860908Y982117D01*
X861200Y982075D01*
X861533Y982158D01*
X861783Y982367D01*
X862033Y982742D01*
G01X863592Y981492D02*
X863883Y981283D01*
X864217Y981200D01*
X864550Y981283D01*
X864842Y981533D01*
X865050Y981908D01*
X865133Y982283D01*
Y982742D01*
X865050Y983117D01*
X864842Y983450D01*
X864592Y983617D01*
X864300Y983700D01*
X863967Y983617D01*
X863717Y983450D01*
X863550Y983200D01*
X863467Y982867D01*
X863550Y982575D01*
X863758Y982283D01*
X864008Y982117D01*
X864300Y982075D01*
X864633Y982158D01*
X864883Y982367D01*
X865133Y982742D01*
G01X867400Y981200D02*
Y983700D01*
X866900Y983200D01*
G01Y981200D02*
X867900D01*
G01X871000D02*
Y983700D01*
X869458Y981908D01*
X871542D01*
G01X882550Y968227D02*
Y964227D01*
X889950D01*
G01X873867Y981267D02*
Y983767D01*
X874908D01*
X875242Y983642D01*
X875450Y983475D01*
X875533Y983142D01*
X875450Y982809D01*
X875200Y982600D01*
X874908Y982475D01*
X873867D01*
G01X874908D02*
X875533Y981267D01*
G01X877092Y981559D02*
X877383Y981350D01*
X877717Y981267D01*
X878050Y981350D01*
X878342Y981600D01*
X878550Y981975D01*
X878633Y982350D01*
Y982809D01*
X878550Y983184D01*
X878342Y983517D01*
X878092Y983684D01*
X877800Y983767D01*
X877467Y983684D01*
X877217Y983517D01*
X877050Y983267D01*
X876967Y982934D01*
X877050Y982642D01*
X877258Y982350D01*
X877508Y982184D01*
X877800Y982142D01*
X878133Y982225D01*
X878383Y982434D01*
X878633Y982809D01*
G01X880192Y981559D02*
X880483Y981350D01*
X880817Y981267D01*
X881150Y981350D01*
X881442Y981600D01*
X881650Y981975D01*
X881733Y982350D01*
Y982809D01*
X881650Y983184D01*
X881442Y983517D01*
X881192Y983684D01*
X880900Y983767D01*
X880567Y983684D01*
X880317Y983517D01*
X880150Y983267D01*
X880067Y982934D01*
X880150Y982642D01*
X880358Y982350D01*
X880608Y982184D01*
X880900Y982142D01*
X881233Y982225D01*
X881483Y982434D01*
X881733Y982809D01*
G01X883083Y981767D02*
X883333Y981475D01*
X883667Y981309D01*
X884042Y981267D01*
X884375Y981309D01*
X884708Y981517D01*
X884917Y981767D01*
X884958Y982017D01*
X884875Y982309D01*
X884583Y982517D01*
X884292Y982600D01*
X883917D01*
G01X884292D02*
X884542Y982725D01*
X884750Y982934D01*
X884833Y983184D01*
X884750Y983434D01*
X884542Y983642D01*
X884167Y983767D01*
X883792Y983725D01*
X883417Y983559D01*
G01X886308Y983350D02*
X886558Y983600D01*
X886850Y983725D01*
X887183Y983767D01*
X887600Y983684D01*
X887892Y983475D01*
X887975Y983225D01*
X887933Y982975D01*
X887767Y982767D01*
X886933Y982350D01*
X886558Y982059D01*
X886308Y981642D01*
X886225Y981267D01*
X887975D01*
G01X891774Y967913D02*
Y963913D01*
X899174D01*
G01X857667Y985566D02*
Y988066D01*
X858708D01*
X859042Y987941D01*
X859250Y987774D01*
X859333Y987441D01*
X859250Y987108D01*
X859000Y986899D01*
X858708Y986774D01*
X857667D01*
G01X858708D02*
X859333Y985566D01*
G01X860892Y985858D02*
X861183Y985649D01*
X861517Y985566D01*
X861850Y985649D01*
X862142Y985899D01*
X862350Y986274D01*
X862433Y986649D01*
Y987108D01*
X862350Y987483D01*
X862142Y987816D01*
X861892Y987983D01*
X861600Y988066D01*
X861267Y987983D01*
X861017Y987816D01*
X860850Y987566D01*
X860767Y987233D01*
X860850Y986941D01*
X861058Y986649D01*
X861308Y986483D01*
X861600Y986441D01*
X861933Y986524D01*
X862183Y986733D01*
X862433Y987108D01*
G01X863992Y985858D02*
X864283Y985649D01*
X864617Y985566D01*
X864950Y985649D01*
X865242Y985899D01*
X865450Y986274D01*
X865533Y986649D01*
Y987108D01*
X865450Y987483D01*
X865242Y987816D01*
X864992Y987983D01*
X864700Y988066D01*
X864367Y987983D01*
X864117Y987816D01*
X863950Y987566D01*
X863867Y987233D01*
X863950Y986941D01*
X864158Y986649D01*
X864408Y986483D01*
X864700Y986441D01*
X865033Y986524D01*
X865283Y986733D01*
X865533Y987108D01*
G01X866883Y986066D02*
X867133Y985774D01*
X867467Y985608D01*
X867842Y985566D01*
X868175Y985608D01*
X868508Y985816D01*
X868717Y986066D01*
X868758Y986316D01*
X868675Y986608D01*
X868383Y986816D01*
X868092Y986899D01*
X867717D01*
G01X868092D02*
X868342Y987024D01*
X868550Y987233D01*
X868633Y987483D01*
X868550Y987733D01*
X868342Y987941D01*
X867967Y988066D01*
X867592Y988024D01*
X867217Y987858D01*
G01X870900Y985566D02*
Y988066D01*
X870400Y987566D01*
G01Y985566D02*
X871400D01*
G01X887909Y971907D02*
X891909D01*
Y979307D01*
G01X888933Y937500D02*
Y935708D01*
X889100Y935333D01*
X889433Y935083D01*
X889850Y935000D01*
X890267Y935083D01*
X890600Y935333D01*
X890767Y935708D01*
Y937500D01*
G01X892950Y935000D02*
Y937500D01*
X892450Y937000D01*
G01Y935000D02*
X893450D01*
G01X895342Y935292D02*
X895633Y935083D01*
X895967Y935000D01*
X896300Y935083D01*
X896592Y935333D01*
X896800Y935708D01*
X896883Y936083D01*
Y936542D01*
X896800Y936917D01*
X896592Y937250D01*
X896342Y937417D01*
X896050Y937500D01*
X895717Y937417D01*
X895467Y937250D01*
X895300Y937000D01*
X895217Y936667D01*
X895300Y936375D01*
X895508Y936083D01*
X895758Y935917D01*
X896050Y935875D01*
X896383Y935958D01*
X896633Y936167D01*
X896883Y936542D01*
G01X898442Y935292D02*
X898733Y935083D01*
X899067Y935000D01*
X899400Y935083D01*
X899692Y935333D01*
X899900Y935708D01*
X899983Y936083D01*
Y936542D01*
X899900Y936917D01*
X899692Y937250D01*
X899442Y937417D01*
X899150Y937500D01*
X898817Y937417D01*
X898567Y937250D01*
X898400Y937000D01*
X898317Y936667D01*
X898400Y936375D01*
X898608Y936083D01*
X898858Y935917D01*
X899150Y935875D01*
X899483Y935958D01*
X899733Y936167D01*
X899983Y936542D01*
G01X887800Y943477D02*
Y953477D01*
G01D02*
X901200D01*
G01D02*
Y943477D01*
G01D02*
X887800D01*
G01X867000Y1038417D02*
X864500D01*
Y1039417D01*
X864625Y1039750D01*
X864917Y1040000D01*
X865250Y1040083D01*
X865583Y1040000D01*
X865833Y1039792D01*
X865958Y1039417D01*
Y1038417D01*
G01X864708Y1043267D02*
X864583Y1043017D01*
X864500Y1042725D01*
Y1042392D01*
X864625Y1042017D01*
X864833Y1041725D01*
X865083Y1041517D01*
X865500Y1041350D01*
X865875Y1041308D01*
X866250Y1041392D01*
X866500Y1041517D01*
X866750Y1041767D01*
X866917Y1042058D01*
X867000Y1042350D01*
Y1042642D01*
X866917Y1042933D01*
X866792Y1043183D01*
X866625Y1043392D01*
G01X867000Y1045450D02*
X864500D01*
X865000Y1044950D01*
G01X867000D02*
Y1045950D01*
G01Y1048550D02*
X864500D01*
X865000Y1048050D01*
G01X867000D02*
Y1049050D01*
G01X866708Y1050942D02*
X866917Y1051233D01*
X867000Y1051567D01*
X866917Y1051900D01*
X866667Y1052192D01*
X866292Y1052400D01*
X865917Y1052483D01*
X865458D01*
X865083Y1052400D01*
X864750Y1052192D01*
X864583Y1051942D01*
X864500Y1051650D01*
X864583Y1051317D01*
X864750Y1051067D01*
X865000Y1050900D01*
X865333Y1050817D01*
X865625Y1050900D01*
X865917Y1051108D01*
X866083Y1051358D01*
X866125Y1051650D01*
X866042Y1051983D01*
X865833Y1052233D01*
X865458Y1052483D01*
G01X867000Y1055250D02*
X864500D01*
X866292Y1053708D01*
Y1055792D01*
G01X853053Y1108828D02*
X852220Y1107495D01*
X851720Y1105995D01*
Y1104661D01*
X852220Y1103328D01*
X853053Y1102328D01*
X854220Y1101828D01*
X855386Y1102161D01*
X856387Y1102995D01*
X857053Y1104495D01*
X857387Y1106495D01*
X858053Y1107661D01*
X859220Y1108161D01*
X860387Y1107828D01*
X861220Y1106995D01*
X861720Y1105828D01*
Y1104661D01*
X861387Y1103495D01*
X860553Y1102495D01*
G01X853053Y1098228D02*
X852220Y1096895D01*
X851720Y1095395D01*
Y1094061D01*
X852220Y1092728D01*
X853053Y1091728D01*
X854220Y1091228D01*
X855386Y1091561D01*
X856387Y1092395D01*
X857053Y1093895D01*
X857387Y1095895D01*
X858053Y1097061D01*
X859220Y1097561D01*
X860387Y1097228D01*
X861220Y1096395D01*
X861720Y1095228D01*
Y1094061D01*
X861387Y1092895D01*
X860553Y1091895D01*
G01X851720Y1087795D02*
X861720D01*
Y1084461D01*
X861220Y1083128D01*
X860553Y1082128D01*
X859553Y1081295D01*
X858386Y1080628D01*
X856720Y1080461D01*
X855053Y1080628D01*
X853887Y1081295D01*
X852886Y1082128D01*
X852220Y1083128D01*
X851720Y1084461D01*
Y1087795D01*
G01X860053Y1076695D02*
X861053Y1075695D01*
X861553Y1074528D01*
X861720Y1073195D01*
X861387Y1071528D01*
X860553Y1070361D01*
X859553Y1070028D01*
X858553Y1070195D01*
X857720Y1070861D01*
X856053Y1074195D01*
X854887Y1075695D01*
X853220Y1076695D01*
X851720Y1077028D01*
Y1070028D01*
G01X869100Y1104217D02*
X869350Y1104425D01*
X869517Y1104675D01*
X869600Y1104967D01*
X869517Y1105300D01*
X869350Y1105550D01*
X869100Y1105800D01*
X868767Y1105883D01*
X867100D01*
G01X867517Y1107358D02*
X867267Y1107608D01*
X867142Y1107900D01*
X867100Y1108233D01*
X867183Y1108650D01*
X867392Y1108942D01*
X867642Y1109025D01*
X867892Y1108983D01*
X868100Y1108817D01*
X868517Y1107983D01*
X868808Y1107608D01*
X869225Y1107358D01*
X869600Y1107275D01*
Y1109025D01*
G01Y1123717D02*
X867100D01*
Y1124717D01*
X867225Y1125050D01*
X867517Y1125300D01*
X867850Y1125383D01*
X868183Y1125300D01*
X868433Y1125092D01*
X868558Y1124717D01*
Y1123717D01*
G01X867308Y1128567D02*
X867183Y1128317D01*
X867100Y1128025D01*
Y1127692D01*
X867225Y1127317D01*
X867433Y1127025D01*
X867683Y1126817D01*
X868100Y1126650D01*
X868475Y1126608D01*
X868850Y1126692D01*
X869100Y1126817D01*
X869350Y1127067D01*
X869517Y1127358D01*
X869600Y1127650D01*
Y1127942D01*
X869517Y1128233D01*
X869392Y1128483D01*
X869225Y1128692D01*
G01X869600Y1130750D02*
X867100D01*
X867600Y1130250D01*
G01X869600D02*
Y1131250D01*
G01Y1133850D02*
X867100D01*
X867600Y1133350D01*
G01X869600D02*
Y1134350D01*
G01X869308Y1136242D02*
X869517Y1136533D01*
X869600Y1136867D01*
X869517Y1137200D01*
X869267Y1137492D01*
X868892Y1137700D01*
X868517Y1137783D01*
X868058D01*
X867683Y1137700D01*
X867350Y1137492D01*
X867183Y1137242D01*
X867100Y1136950D01*
X867183Y1136617D01*
X867350Y1136367D01*
X867600Y1136200D01*
X867933Y1136117D01*
X868225Y1136200D01*
X868517Y1136408D01*
X868683Y1136658D01*
X868725Y1136950D01*
X868642Y1137283D01*
X868433Y1137533D01*
X868058Y1137783D01*
G01X869100Y1139133D02*
X869392Y1139383D01*
X869558Y1139717D01*
X869600Y1140092D01*
X869558Y1140425D01*
X869350Y1140758D01*
X869100Y1140967D01*
X868850Y1141008D01*
X868558Y1140925D01*
X868350Y1140633D01*
X868267Y1140342D01*
Y1139967D01*
G01Y1140342D02*
X868142Y1140592D01*
X867933Y1140800D01*
X867683Y1140883D01*
X867433Y1140800D01*
X867225Y1140592D01*
X867100Y1140217D01*
X867142Y1139842D01*
X867308Y1139467D01*
G01X845837Y1120841D02*
Y1123341D01*
X846878D01*
X847212Y1123216D01*
X847420Y1123049D01*
X847503Y1122716D01*
X847420Y1122383D01*
X847170Y1122174D01*
X846878Y1122049D01*
X845837D01*
G01X846878D02*
X847503Y1120841D01*
G01X848853Y1121341D02*
X849103Y1121049D01*
X849437Y1120883D01*
X849812Y1120841D01*
X850145Y1120883D01*
X850478Y1121091D01*
X850687Y1121341D01*
X850728Y1121591D01*
X850645Y1121883D01*
X850353Y1122091D01*
X850062Y1122174D01*
X849687D01*
G01X850062D02*
X850312Y1122299D01*
X850520Y1122508D01*
X850603Y1122758D01*
X850520Y1123008D01*
X850312Y1123216D01*
X849937Y1123341D01*
X849562Y1123299D01*
X849187Y1123133D01*
G01X852162Y1121133D02*
X852453Y1120924D01*
X852787Y1120841D01*
X853120Y1120924D01*
X853412Y1121174D01*
X853620Y1121549D01*
X853703Y1121924D01*
Y1122383D01*
X853620Y1122758D01*
X853412Y1123091D01*
X853162Y1123258D01*
X852870Y1123341D01*
X852537Y1123258D01*
X852287Y1123091D01*
X852120Y1122841D01*
X852037Y1122508D01*
X852120Y1122216D01*
X852328Y1121924D01*
X852578Y1121758D01*
X852870Y1121716D01*
X853203Y1121799D01*
X853453Y1122008D01*
X853703Y1122383D01*
G01X855970Y1120841D02*
Y1123341D01*
X855470Y1122841D01*
G01Y1120841D02*
X856470D01*
G01X858200Y1130000D02*
Y1134000D01*
X850800D01*
G01X845837Y1125841D02*
Y1128341D01*
X846878D01*
X847212Y1128216D01*
X847420Y1128049D01*
X847503Y1127716D01*
X847420Y1127383D01*
X847170Y1127174D01*
X846878Y1127049D01*
X845837D01*
G01X846878D02*
X847503Y1125841D01*
G01X848853Y1126341D02*
X849103Y1126049D01*
X849437Y1125883D01*
X849812Y1125841D01*
X850145Y1125883D01*
X850478Y1126091D01*
X850687Y1126341D01*
X850728Y1126591D01*
X850645Y1126883D01*
X850353Y1127091D01*
X850062Y1127174D01*
X849687D01*
G01X850062D02*
X850312Y1127299D01*
X850520Y1127508D01*
X850603Y1127758D01*
X850520Y1128008D01*
X850312Y1128216D01*
X849937Y1128341D01*
X849562Y1128299D01*
X849187Y1128133D01*
G01X852162Y1126133D02*
X852453Y1125924D01*
X852787Y1125841D01*
X853120Y1125924D01*
X853412Y1126174D01*
X853620Y1126549D01*
X853703Y1126924D01*
Y1127383D01*
X853620Y1127758D01*
X853412Y1128091D01*
X853162Y1128258D01*
X852870Y1128341D01*
X852537Y1128258D01*
X852287Y1128091D01*
X852120Y1127841D01*
X852037Y1127508D01*
X852120Y1127216D01*
X852328Y1126924D01*
X852578Y1126758D01*
X852870Y1126716D01*
X853203Y1126799D01*
X853453Y1127008D01*
X853703Y1127383D01*
G01X855178Y1127924D02*
X855428Y1128174D01*
X855720Y1128299D01*
X856053Y1128341D01*
X856470Y1128258D01*
X856762Y1128049D01*
X856845Y1127799D01*
X856803Y1127549D01*
X856637Y1127341D01*
X855803Y1126924D01*
X855428Y1126633D01*
X855178Y1126216D01*
X855095Y1125841D01*
X856845D01*
G01X858200Y1135000D02*
Y1139000D01*
X850800D01*
G01X861900Y1123817D02*
X859400D01*
Y1124817D01*
X859525Y1125150D01*
X859817Y1125400D01*
X860150Y1125483D01*
X860483Y1125400D01*
X860733Y1125192D01*
X860858Y1124817D01*
Y1123817D01*
G01X859608Y1128667D02*
X859483Y1128417D01*
X859400Y1128125D01*
Y1127792D01*
X859525Y1127417D01*
X859733Y1127125D01*
X859983Y1126917D01*
X860400Y1126750D01*
X860775Y1126708D01*
X861150Y1126792D01*
X861400Y1126917D01*
X861650Y1127167D01*
X861817Y1127458D01*
X861900Y1127750D01*
Y1128042D01*
X861817Y1128333D01*
X861692Y1128583D01*
X861525Y1128792D01*
G01X861900Y1130850D02*
X859400D01*
X859900Y1130350D01*
G01X861900D02*
Y1131350D01*
G01Y1133950D02*
X859400D01*
X859900Y1133450D01*
G01X861900D02*
Y1134450D01*
G01X861608Y1136342D02*
X861817Y1136633D01*
X861900Y1136967D01*
X861817Y1137300D01*
X861567Y1137592D01*
X861192Y1137800D01*
X860817Y1137883D01*
X860358D01*
X859983Y1137800D01*
X859650Y1137592D01*
X859483Y1137342D01*
X859400Y1137050D01*
X859483Y1136717D01*
X859650Y1136467D01*
X859900Y1136300D01*
X860233Y1136217D01*
X860525Y1136300D01*
X860817Y1136508D01*
X860983Y1136758D01*
X861025Y1137050D01*
X860942Y1137383D01*
X860733Y1137633D01*
X860358Y1137883D01*
G01X861900Y1140150D02*
X859400D01*
X859900Y1139650D01*
G01X861900D02*
Y1140650D01*
G01X888500Y1160417D02*
X886000D01*
Y1161417D01*
X886125Y1161750D01*
X886417Y1162000D01*
X886750Y1162083D01*
X887083Y1162000D01*
X887333Y1161792D01*
X887458Y1161417D01*
Y1160417D01*
G01X886208Y1165267D02*
X886083Y1165017D01*
X886000Y1164725D01*
Y1164392D01*
X886125Y1164017D01*
X886333Y1163725D01*
X886583Y1163517D01*
X887000Y1163350D01*
X887375Y1163308D01*
X887750Y1163392D01*
X888000Y1163517D01*
X888250Y1163767D01*
X888417Y1164058D01*
X888500Y1164350D01*
Y1164642D01*
X888417Y1164933D01*
X888292Y1165183D01*
X888125Y1165392D01*
G01X888500Y1167450D02*
X886000D01*
X886500Y1166950D01*
G01X888500D02*
Y1167950D01*
G01Y1170550D02*
X886000D01*
X886500Y1170050D01*
G01X888500D02*
Y1171050D01*
G01X888208Y1172942D02*
X888417Y1173233D01*
X888500Y1173567D01*
X888417Y1173900D01*
X888167Y1174192D01*
X887792Y1174400D01*
X887417Y1174483D01*
X886958D01*
X886583Y1174400D01*
X886250Y1174192D01*
X886083Y1173942D01*
X886000Y1173650D01*
X886083Y1173317D01*
X886250Y1173067D01*
X886500Y1172900D01*
X886833Y1172817D01*
X887125Y1172900D01*
X887417Y1173108D01*
X887583Y1173358D01*
X887625Y1173650D01*
X887542Y1173983D01*
X887333Y1174233D01*
X886958Y1174483D01*
G01X886417Y1175958D02*
X886167Y1176208D01*
X886042Y1176500D01*
X886000Y1176833D01*
X886083Y1177250D01*
X886292Y1177542D01*
X886542Y1177625D01*
X886792Y1177583D01*
X887000Y1177417D01*
X887417Y1176583D01*
X887708Y1176208D01*
X888125Y1175958D01*
X888500Y1175875D01*
Y1177625D01*
G01X846900Y1193500D02*
X846567Y1193542D01*
X846275Y1193708D01*
X846025Y1193958D01*
X845858Y1194250D01*
X845775Y1194583D01*
Y1194917D01*
X845858Y1195250D01*
X846025Y1195542D01*
X846275Y1195792D01*
X846567Y1195958D01*
X846900Y1196000D01*
X847233Y1195958D01*
X847525Y1195792D01*
X847775Y1195542D01*
X847942Y1195250D01*
X848025Y1194917D01*
Y1194583D01*
X847942Y1194250D01*
X847775Y1193958D01*
X847525Y1193708D01*
X847233Y1193542D01*
X846900Y1193500D01*
G01X847233Y1194167D02*
X847733Y1193500D01*
G01X849083Y1194000D02*
X849333Y1193708D01*
X849667Y1193542D01*
X850042Y1193500D01*
X850375Y1193542D01*
X850708Y1193750D01*
X850917Y1194000D01*
X850958Y1194250D01*
X850875Y1194542D01*
X850583Y1194750D01*
X850292Y1194833D01*
X849917D01*
G01X850292D02*
X850542Y1194958D01*
X850750Y1195167D01*
X850833Y1195417D01*
X850750Y1195667D01*
X850542Y1195875D01*
X850167Y1196000D01*
X849792Y1195958D01*
X849417Y1195792D01*
G01X853017Y1193500D02*
X853100Y1194042D01*
X853225Y1194500D01*
X853392Y1194917D01*
X853600Y1195375D01*
X853933Y1196000D01*
X852267D01*
G01X843000Y1191400D02*
Y1178400D01*
G01D02*
X857000D01*
G01D02*
Y1191400D01*
G01D02*
X843000D01*
G01X842500Y1193967D02*
X840000D01*
Y1195008D01*
X840125Y1195342D01*
X840292Y1195550D01*
X840625Y1195633D01*
X840958Y1195550D01*
X841167Y1195300D01*
X841292Y1195008D01*
Y1193967D01*
G01Y1195008D02*
X842500Y1195633D01*
G01X842208Y1197192D02*
X842417Y1197483D01*
X842500Y1197817D01*
X842417Y1198150D01*
X842167Y1198442D01*
X841792Y1198650D01*
X841417Y1198733D01*
X840958D01*
X840583Y1198650D01*
X840250Y1198442D01*
X840083Y1198192D01*
X840000Y1197900D01*
X840083Y1197567D01*
X840250Y1197317D01*
X840500Y1197150D01*
X840833Y1197067D01*
X841125Y1197150D01*
X841417Y1197358D01*
X841583Y1197608D01*
X841625Y1197900D01*
X841542Y1198233D01*
X841333Y1198483D01*
X840958Y1198733D01*
G01X842500Y1200917D02*
X841958Y1201000D01*
X841500Y1201125D01*
X841083Y1201292D01*
X840625Y1201500D01*
X840000Y1201833D01*
Y1200167D01*
G01X842208Y1203392D02*
X842417Y1203683D01*
X842500Y1204017D01*
X842417Y1204350D01*
X842167Y1204642D01*
X841792Y1204850D01*
X841417Y1204933D01*
X840958D01*
X840583Y1204850D01*
X840250Y1204642D01*
X840083Y1204392D01*
X840000Y1204100D01*
X840083Y1203767D01*
X840250Y1203517D01*
X840500Y1203350D01*
X840833Y1203267D01*
X841125Y1203350D01*
X841417Y1203558D01*
X841583Y1203808D01*
X841625Y1204100D01*
X841542Y1204433D01*
X841333Y1204683D01*
X840958Y1204933D01*
G01X842500Y1207700D02*
X840000D01*
X841792Y1206158D01*
Y1208242D01*
G01X846600Y1147600D02*
X842600D01*
Y1140200D01*
G01X852500D02*
X856500D01*
Y1147600D01*
G01X864217Y1192500D02*
Y1195000D01*
X865258D01*
X865592Y1194875D01*
X865800Y1194708D01*
X865883Y1194375D01*
X865800Y1194042D01*
X865550Y1193833D01*
X865258Y1193708D01*
X864217D01*
G01X865258D02*
X865883Y1192500D01*
G01X867442Y1192792D02*
X867733Y1192583D01*
X868067Y1192500D01*
X868400Y1192583D01*
X868692Y1192833D01*
X868900Y1193208D01*
X868983Y1193583D01*
Y1194042D01*
X868900Y1194417D01*
X868692Y1194750D01*
X868442Y1194917D01*
X868150Y1195000D01*
X867817Y1194917D01*
X867567Y1194750D01*
X867400Y1194500D01*
X867317Y1194167D01*
X867400Y1193875D01*
X867608Y1193583D01*
X867858Y1193417D01*
X868150Y1193375D01*
X868483Y1193458D01*
X868733Y1193667D01*
X868983Y1194042D01*
G01X871167Y1192500D02*
X871250Y1193042D01*
X871375Y1193500D01*
X871542Y1193917D01*
X871750Y1194375D01*
X872083Y1195000D01*
X870417D01*
G01X873642Y1192792D02*
X873933Y1192583D01*
X874267Y1192500D01*
X874600Y1192583D01*
X874892Y1192833D01*
X875100Y1193208D01*
X875183Y1193583D01*
Y1194042D01*
X875100Y1194417D01*
X874892Y1194750D01*
X874642Y1194917D01*
X874350Y1195000D01*
X874017Y1194917D01*
X873767Y1194750D01*
X873600Y1194500D01*
X873517Y1194167D01*
X873600Y1193875D01*
X873808Y1193583D01*
X874058Y1193417D01*
X874350Y1193375D01*
X874683Y1193458D01*
X874933Y1193667D01*
X875183Y1194042D01*
G01X876658Y1194583D02*
X876908Y1194833D01*
X877200Y1194958D01*
X877533Y1195000D01*
X877950Y1194917D01*
X878242Y1194708D01*
X878325Y1194458D01*
X878283Y1194208D01*
X878117Y1194000D01*
X877283Y1193583D01*
X876908Y1193292D01*
X876658Y1192875D01*
X876575Y1192500D01*
X878325D01*
G01X876800Y1183900D02*
X871600D01*
G01X876800Y1190900D02*
X869000D01*
G01X876800Y1183900D02*
Y1190900D01*
G01X863400Y1183900D02*
X872100D01*
G01X863400Y1190900D02*
Y1183900D01*
G01X869800Y1190900D02*
X863400D01*
G01X844983Y1176500D02*
Y1174708D01*
X845150Y1174333D01*
X845483Y1174083D01*
X845900Y1174000D01*
X846317Y1174083D01*
X846650Y1174333D01*
X846817Y1174708D01*
Y1176500D01*
G01X849000Y1174000D02*
Y1176500D01*
X848500Y1176000D01*
G01Y1174000D02*
X849500D01*
G01X852100D02*
Y1176500D01*
X851600Y1176000D01*
G01Y1174000D02*
X852600D01*
G01X839900Y1171800D02*
Y1152600D01*
X851100D01*
Y1171800D01*
X839900D01*
G01X847500D02*
X845500Y1169800D01*
X843500Y1171800D01*
G01X896167Y1189800D02*
Y1192300D01*
X897208D01*
X897542Y1192175D01*
X897750Y1192008D01*
X897833Y1191675D01*
X897750Y1191342D01*
X897500Y1191133D01*
X897208Y1191008D01*
X896167D01*
G01X897208D02*
X897833Y1189800D01*
G01X899392Y1190092D02*
X899683Y1189883D01*
X900017Y1189800D01*
X900350Y1189883D01*
X900642Y1190133D01*
X900850Y1190508D01*
X900933Y1190883D01*
Y1191342D01*
X900850Y1191717D01*
X900642Y1192050D01*
X900392Y1192217D01*
X900100Y1192300D01*
X899767Y1192217D01*
X899517Y1192050D01*
X899350Y1191800D01*
X899267Y1191467D01*
X899350Y1191175D01*
X899558Y1190883D01*
X899808Y1190717D01*
X900100Y1190675D01*
X900433Y1190758D01*
X900683Y1190967D01*
X900933Y1191342D01*
G01X902408Y1191883D02*
X902658Y1192133D01*
X902950Y1192258D01*
X903283Y1192300D01*
X903700Y1192217D01*
X903992Y1192008D01*
X904075Y1191758D01*
X904033Y1191508D01*
X903867Y1191300D01*
X903033Y1190883D01*
X902658Y1190592D01*
X902408Y1190175D01*
X902325Y1189800D01*
X904075D01*
G01X906800D02*
Y1192300D01*
X905258Y1190508D01*
X907342D01*
G01X908483Y1190300D02*
X908733Y1190008D01*
X909067Y1189842D01*
X909442Y1189800D01*
X909775Y1189842D01*
X910108Y1190050D01*
X910317Y1190300D01*
X910358Y1190550D01*
X910275Y1190842D01*
X909983Y1191050D01*
X909692Y1191133D01*
X909317D01*
G01X909692D02*
X909942Y1191258D01*
X910150Y1191467D01*
X910233Y1191717D01*
X910150Y1191967D01*
X909942Y1192175D01*
X909567Y1192300D01*
X909192Y1192258D01*
X908817Y1192092D01*
G01X889800Y1174100D02*
X915800D01*
G01X889800Y1187100D02*
Y1174100D01*
G01X915800Y1187100D02*
X889800D01*
G01X884500Y1160417D02*
X882000D01*
Y1161417D01*
X882125Y1161750D01*
X882417Y1162000D01*
X882750Y1162083D01*
X883083Y1162000D01*
X883333Y1161792D01*
X883458Y1161417D01*
Y1160417D01*
G01X882208Y1165267D02*
X882083Y1165017D01*
X882000Y1164725D01*
Y1164392D01*
X882125Y1164017D01*
X882333Y1163725D01*
X882583Y1163517D01*
X883000Y1163350D01*
X883375Y1163308D01*
X883750Y1163392D01*
X884000Y1163517D01*
X884250Y1163767D01*
X884417Y1164058D01*
X884500Y1164350D01*
Y1164642D01*
X884417Y1164933D01*
X884292Y1165183D01*
X884125Y1165392D01*
G01X884500Y1167450D02*
X882000D01*
X882500Y1166950D01*
G01X884500D02*
Y1167950D01*
G01Y1170550D02*
X882000D01*
X882500Y1170050D01*
G01X884500D02*
Y1171050D01*
G01X884208Y1172942D02*
X884417Y1173233D01*
X884500Y1173567D01*
X884417Y1173900D01*
X884167Y1174192D01*
X883792Y1174400D01*
X883417Y1174483D01*
X882958D01*
X882583Y1174400D01*
X882250Y1174192D01*
X882083Y1173942D01*
X882000Y1173650D01*
X882083Y1173317D01*
X882250Y1173067D01*
X882500Y1172900D01*
X882833Y1172817D01*
X883125Y1172900D01*
X883417Y1173108D01*
X883583Y1173358D01*
X883625Y1173650D01*
X883542Y1173983D01*
X883333Y1174233D01*
X882958Y1174483D01*
G01X882000Y1176750D02*
X882083Y1176417D01*
X882292Y1176167D01*
X882542Y1176000D01*
X882875Y1175875D01*
X883250Y1175833D01*
X883625Y1175875D01*
X883958Y1176000D01*
X884208Y1176167D01*
X884417Y1176417D01*
X884500Y1176750D01*
X884417Y1177083D01*
X884208Y1177333D01*
X883958Y1177500D01*
X883625Y1177625D01*
X883250Y1177667D01*
X882875Y1177625D01*
X882542Y1177500D01*
X882292Y1177333D01*
X882083Y1177083D01*
X882000Y1176750D01*
G01X871150Y1180350D02*
Y1161650D01*
X860850D01*
Y1180350D01*
X871150D01*
G01X861050Y1142150D02*
Y1160850D01*
X871350D01*
Y1142150D01*
X861050D01*
G01X904217Y1340792D02*
X903967Y1340917D01*
X903675Y1341000D01*
X903342D01*
X902967Y1340875D01*
X902675Y1340667D01*
X902467Y1340417D01*
X902300Y1340000D01*
X902258Y1339625D01*
X902342Y1339250D01*
X902467Y1339000D01*
X902717Y1338750D01*
X903008Y1338583D01*
X903300Y1338500D01*
X903592D01*
X903883Y1338583D01*
X904133Y1338708D01*
X904342Y1338875D01*
G01X905692Y1338792D02*
X905983Y1338583D01*
X906317Y1338500D01*
X906650Y1338583D01*
X906942Y1338833D01*
X907150Y1339208D01*
X907233Y1339583D01*
Y1340042D01*
X907150Y1340417D01*
X906942Y1340750D01*
X906692Y1340917D01*
X906400Y1341000D01*
X906067Y1340917D01*
X905817Y1340750D01*
X905650Y1340500D01*
X905567Y1340167D01*
X905650Y1339875D01*
X905858Y1339583D01*
X906108Y1339417D01*
X906400Y1339375D01*
X906733Y1339458D01*
X906983Y1339667D01*
X907233Y1340042D01*
G01X908583Y1338875D02*
X908833Y1338667D01*
X909125Y1338542D01*
X909500Y1338500D01*
X909875Y1338583D01*
X910167Y1338750D01*
X910375Y1339042D01*
X910417Y1339375D01*
X910333Y1339708D01*
X910125Y1339917D01*
X909833Y1340083D01*
X909542Y1340125D01*
X909250Y1340083D01*
X908875Y1339917D01*
X909000Y1341000D01*
X910125D01*
G01X912600Y1338500D02*
Y1341000D01*
X912100Y1340500D01*
G01Y1338500D02*
X913100D01*
G01X914992Y1338792D02*
X915283Y1338583D01*
X915617Y1338500D01*
X915950Y1338583D01*
X916242Y1338833D01*
X916450Y1339208D01*
X916533Y1339583D01*
Y1340042D01*
X916450Y1340417D01*
X916242Y1340750D01*
X915992Y1340917D01*
X915700Y1341000D01*
X915367Y1340917D01*
X915117Y1340750D01*
X914950Y1340500D01*
X914867Y1340167D01*
X914950Y1339875D01*
X915158Y1339583D01*
X915408Y1339417D01*
X915700Y1339375D01*
X916033Y1339458D01*
X916283Y1339667D01*
X916533Y1340042D01*
G01X860500Y1349400D02*
X860458Y1349067D01*
X860292Y1348775D01*
X860042Y1348525D01*
X859750Y1348358D01*
X859417Y1348275D01*
X859083D01*
X858750Y1348358D01*
X858458Y1348525D01*
X858208Y1348775D01*
X858042Y1349067D01*
X858000Y1349400D01*
X858042Y1349733D01*
X858208Y1350025D01*
X858458Y1350275D01*
X858750Y1350442D01*
X859083Y1350525D01*
X859417D01*
X859750Y1350442D01*
X860042Y1350275D01*
X860292Y1350025D01*
X860458Y1349733D01*
X860500Y1349400D01*
G01X859833Y1349733D02*
X860500Y1350233D01*
G01X860000Y1351583D02*
X860292Y1351833D01*
X860458Y1352167D01*
X860500Y1352542D01*
X860458Y1352875D01*
X860250Y1353208D01*
X860000Y1353417D01*
X859750Y1353458D01*
X859458Y1353375D01*
X859250Y1353083D01*
X859167Y1352792D01*
Y1352417D01*
G01Y1352792D02*
X859042Y1353042D01*
X858833Y1353250D01*
X858583Y1353333D01*
X858333Y1353250D01*
X858125Y1353042D01*
X858000Y1352667D01*
X858042Y1352292D01*
X858208Y1351917D01*
G01X860500Y1356100D02*
X858000D01*
X859792Y1354558D01*
Y1356642D01*
G01X862500Y1347488D02*
X875500D01*
G01D02*
Y1361488D01*
G01X862500D02*
Y1347488D01*
G01X902467Y1343000D02*
Y1345500D01*
X903508D01*
X903842Y1345375D01*
X904050Y1345208D01*
X904133Y1344875D01*
X904050Y1344542D01*
X903800Y1344333D01*
X903508Y1344208D01*
X902467D01*
G01X903508D02*
X904133Y1343000D01*
G01X905692Y1343292D02*
X905983Y1343083D01*
X906317Y1343000D01*
X906650Y1343083D01*
X906942Y1343333D01*
X907150Y1343708D01*
X907233Y1344083D01*
Y1344542D01*
X907150Y1344917D01*
X906942Y1345250D01*
X906692Y1345417D01*
X906400Y1345500D01*
X906067Y1345417D01*
X905817Y1345250D01*
X905650Y1345000D01*
X905567Y1344667D01*
X905650Y1344375D01*
X905858Y1344083D01*
X906108Y1343917D01*
X906400Y1343875D01*
X906733Y1343958D01*
X906983Y1344167D01*
X907233Y1344542D01*
G01X909417Y1343000D02*
X909500Y1343542D01*
X909625Y1344000D01*
X909792Y1344417D01*
X910000Y1344875D01*
X910333Y1345500D01*
X908667D01*
G01X912600Y1343000D02*
X912892Y1343042D01*
X913225Y1343167D01*
X913433Y1343375D01*
X913517Y1343667D01*
X913433Y1343958D01*
X913183Y1344208D01*
X912808Y1344333D01*
X912392D01*
X912142Y1344417D01*
X911933Y1344625D01*
X911850Y1344917D01*
X911975Y1345208D01*
X912267Y1345417D01*
X912600Y1345500D01*
X912933Y1345417D01*
X913225Y1345208D01*
X913350Y1344917D01*
X913267Y1344625D01*
X913058Y1344417D01*
X912808Y1344333D01*
X912392D01*
X912017Y1344208D01*
X911767Y1343958D01*
X911683Y1343667D01*
X911767Y1343375D01*
X911975Y1343167D01*
X912308Y1343042D01*
X912600Y1343000D01*
G01X914992Y1343292D02*
X915283Y1343083D01*
X915617Y1343000D01*
X915950Y1343083D01*
X916242Y1343333D01*
X916450Y1343708D01*
X916533Y1344083D01*
Y1344542D01*
X916450Y1344917D01*
X916242Y1345250D01*
X915992Y1345417D01*
X915700Y1345500D01*
X915367Y1345417D01*
X915117Y1345250D01*
X914950Y1345000D01*
X914867Y1344667D01*
X914950Y1344375D01*
X915158Y1344083D01*
X915408Y1343917D01*
X915700Y1343875D01*
X916033Y1343958D01*
X916283Y1344167D01*
X916533Y1344542D01*
G01X882875Y1344333D02*
X883208Y1344125D01*
X883583Y1344000D01*
X883917D01*
X884250Y1344125D01*
X884500Y1344333D01*
X884625Y1344625D01*
X884542Y1344917D01*
X884333Y1345167D01*
X883958Y1345333D01*
X883458Y1345417D01*
X883167Y1345583D01*
X883042Y1345875D01*
X883125Y1346167D01*
X883333Y1346375D01*
X883625Y1346500D01*
X883917D01*
X884208Y1346417D01*
X884458Y1346208D01*
G01X886017Y1344000D02*
Y1346500D01*
X887058D01*
X887392Y1346375D01*
X887600Y1346208D01*
X887683Y1345875D01*
X887600Y1345542D01*
X887350Y1345333D01*
X887058Y1345208D01*
X886017D01*
G01X887058D02*
X887683Y1344000D01*
G01X889950D02*
Y1346500D01*
X889450Y1346000D01*
G01Y1344000D02*
X890450D01*
G01X893050D02*
Y1346500D01*
X892550Y1346000D01*
G01Y1344000D02*
X893550D01*
G01X895358Y1346083D02*
X895608Y1346333D01*
X895900Y1346458D01*
X896233Y1346500D01*
X896650Y1346417D01*
X896942Y1346208D01*
X897025Y1345958D01*
X896983Y1345708D01*
X896817Y1345500D01*
X895983Y1345083D01*
X895608Y1344792D01*
X895358Y1344375D01*
X895275Y1344000D01*
X897025D01*
G01X899750D02*
Y1346500D01*
X898208Y1344708D01*
X900292D01*
G01X883433Y1342500D02*
Y1340708D01*
X883600Y1340333D01*
X883933Y1340083D01*
X884350Y1340000D01*
X884767Y1340083D01*
X885100Y1340333D01*
X885267Y1340708D01*
Y1342500D01*
G01X887450Y1340000D02*
Y1342500D01*
X886950Y1342000D01*
G01Y1340000D02*
X887950D01*
G01X889842Y1340292D02*
X890133Y1340083D01*
X890467Y1340000D01*
X890800Y1340083D01*
X891092Y1340333D01*
X891300Y1340708D01*
X891383Y1341083D01*
Y1341542D01*
X891300Y1341917D01*
X891092Y1342250D01*
X890842Y1342417D01*
X890550Y1342500D01*
X890217Y1342417D01*
X889967Y1342250D01*
X889800Y1342000D01*
X889717Y1341667D01*
X889800Y1341375D01*
X890008Y1341083D01*
X890258Y1340917D01*
X890550Y1340875D01*
X890883Y1340958D01*
X891133Y1341167D01*
X891383Y1341542D01*
G01X893650Y1340000D02*
X893942Y1340042D01*
X894275Y1340167D01*
X894483Y1340375D01*
X894567Y1340667D01*
X894483Y1340958D01*
X894233Y1341208D01*
X893858Y1341333D01*
X893442D01*
X893192Y1341417D01*
X892983Y1341625D01*
X892900Y1341917D01*
X893025Y1342208D01*
X893317Y1342417D01*
X893650Y1342500D01*
X893983Y1342417D01*
X894275Y1342208D01*
X894400Y1341917D01*
X894317Y1341625D01*
X894108Y1341417D01*
X893858Y1341333D01*
X893442D01*
X893067Y1341208D01*
X892817Y1340958D01*
X892733Y1340667D01*
X892817Y1340375D01*
X893025Y1340167D01*
X893358Y1340042D01*
X893650Y1340000D01*
G01X887800Y1348988D02*
Y1358988D01*
G01X901200D02*
Y1348988D01*
G01D02*
X887800D01*
G01X894567Y1384567D02*
Y1387067D01*
X895567D01*
X895900Y1386942D01*
X896150Y1386650D01*
X896233Y1386317D01*
X896150Y1385984D01*
X895942Y1385734D01*
X895567Y1385609D01*
X894567D01*
G01X899333Y1384567D02*
X897667D01*
Y1387067D01*
X899333D01*
G01X898667Y1385859D02*
X897667D01*
G01X901933Y1385900D02*
X902100Y1386025D01*
X902225Y1386234D01*
X902308Y1386525D01*
X902225Y1386775D01*
X902058Y1386942D01*
X901767Y1387067D01*
X900642D01*
Y1384567D01*
X902017D01*
X902308Y1384734D01*
X902475Y1384984D01*
X902558Y1385275D01*
X902475Y1385567D01*
X902225Y1385817D01*
X901933Y1385900D01*
X900642D01*
G01X906758Y1384567D02*
X907800Y1387067D01*
X908842Y1384567D01*
G01X908467Y1385442D02*
X907133D01*
G01X910900Y1387067D02*
Y1384567D01*
G01X909942Y1387067D02*
X911858D01*
G01X914000D02*
Y1384567D01*
G01X913042Y1387067D02*
X914958D01*
G01X916142Y1384567D02*
Y1387067D01*
X918058Y1384567D01*
Y1387067D01*
G01X920200Y1384567D02*
Y1387067D01*
X919700Y1386567D01*
G01Y1384567D02*
X920700D01*
G01X906075Y1366400D02*
X906408Y1366192D01*
X906783Y1366067D01*
X907117D01*
X907450Y1366192D01*
X907700Y1366400D01*
X907825Y1366692D01*
X907742Y1366984D01*
X907533Y1367234D01*
X907158Y1367400D01*
X906658Y1367484D01*
X906367Y1367650D01*
X906242Y1367942D01*
X906325Y1368234D01*
X906533Y1368442D01*
X906825Y1368567D01*
X907117D01*
X907408Y1368484D01*
X907658Y1368275D01*
G01X909133Y1366067D02*
Y1368567D01*
X909967D01*
X910300Y1368442D01*
X910550Y1368275D01*
X910758Y1368025D01*
X910925Y1367734D01*
X910967Y1367317D01*
X910925Y1366900D01*
X910758Y1366609D01*
X910550Y1366359D01*
X910300Y1366192D01*
X909967Y1366067D01*
X909133D01*
G01X912233D02*
Y1368567D01*
X913067D01*
X913400Y1368442D01*
X913650Y1368275D01*
X913858Y1368025D01*
X914025Y1367734D01*
X914067Y1367317D01*
X914025Y1366900D01*
X913858Y1366609D01*
X913650Y1366359D01*
X913400Y1366192D01*
X913067Y1366067D01*
X912233D01*
G01X918308D02*
X919350Y1368567D01*
X920392Y1366067D01*
G01X920017Y1366942D02*
X918683D01*
G01X923367Y1368359D02*
X923117Y1368484D01*
X922825Y1368567D01*
X922492D01*
X922117Y1368442D01*
X921825Y1368234D01*
X921617Y1367984D01*
X921450Y1367567D01*
X921408Y1367192D01*
X921492Y1366817D01*
X921617Y1366567D01*
X921867Y1366317D01*
X922158Y1366150D01*
X922450Y1366067D01*
X922742D01*
X923033Y1366150D01*
X923283Y1366275D01*
X923492Y1366442D01*
G01X925550Y1368567D02*
Y1366067D01*
G01X924592Y1368567D02*
X926508D01*
G01X928650Y1366067D02*
Y1368567D01*
X928150Y1368067D01*
G01Y1366067D02*
X929150D01*
G01X937654Y1402353D02*
X908754D01*
Y1389453D01*
X890454D01*
Y1402353D01*
X876954D01*
Y1563553D01*
X890454D01*
Y1576453D01*
X908754D01*
Y1563553D01*
X937654D01*
Y1553203D01*
X930954D01*
Y1412703D01*
X937654D01*
Y1402353D01*
G01X899917Y1373166D02*
Y1370666D01*
X901583D01*
G01X904683D02*
X903017D01*
Y1373166D01*
X904683D01*
G01X904017Y1371958D02*
X903017D01*
G01X906033Y1370666D02*
Y1373166D01*
X906867D01*
X907200Y1373041D01*
X907450Y1372874D01*
X907658Y1372624D01*
X907825Y1372333D01*
X907867Y1371916D01*
X907825Y1371499D01*
X907658Y1371208D01*
X907450Y1370958D01*
X907200Y1370791D01*
X906867Y1370666D01*
X906033D01*
G01X910050D02*
Y1373166D01*
X909550Y1372666D01*
G01Y1370666D02*
X910550D01*
G01X893906Y1374546D02*
Y1382146D01*
X905306D01*
Y1374546D01*
X893906D01*
G01X875500Y1361488D02*
X862500D01*
G01X857000Y1373100D02*
X856667Y1373142D01*
X856375Y1373308D01*
X856125Y1373558D01*
X855958Y1373850D01*
X855875Y1374183D01*
Y1374517D01*
X855958Y1374850D01*
X856125Y1375142D01*
X856375Y1375392D01*
X856667Y1375558D01*
X857000Y1375600D01*
X857333Y1375558D01*
X857625Y1375392D01*
X857875Y1375142D01*
X858042Y1374850D01*
X858125Y1374517D01*
Y1374183D01*
X858042Y1373850D01*
X857875Y1373558D01*
X857625Y1373308D01*
X857333Y1373142D01*
X857000Y1373100D01*
G01X857333Y1373767D02*
X857833Y1373100D01*
G01X859183Y1373600D02*
X859433Y1373308D01*
X859767Y1373142D01*
X860142Y1373100D01*
X860475Y1373142D01*
X860808Y1373350D01*
X861017Y1373600D01*
X861058Y1373850D01*
X860975Y1374142D01*
X860683Y1374350D01*
X860392Y1374433D01*
X860017D01*
G01X860392D02*
X860642Y1374558D01*
X860850Y1374767D01*
X860933Y1375017D01*
X860850Y1375267D01*
X860642Y1375475D01*
X860267Y1375600D01*
X859892Y1375558D01*
X859517Y1375392D01*
G01X862283Y1373475D02*
X862533Y1373267D01*
X862825Y1373142D01*
X863200Y1373100D01*
X863575Y1373183D01*
X863867Y1373350D01*
X864075Y1373642D01*
X864117Y1373975D01*
X864033Y1374308D01*
X863825Y1374517D01*
X863533Y1374683D01*
X863242Y1374725D01*
X862950Y1374683D01*
X862575Y1374517D01*
X862700Y1375600D01*
X863825D01*
G01X868000Y1363488D02*
X881000D01*
G01D02*
Y1377488D01*
G01D02*
X868000D01*
G01D02*
Y1363488D01*
G01X846875Y1368833D02*
X847208Y1368625D01*
X847583Y1368500D01*
X847917D01*
X848250Y1368625D01*
X848500Y1368833D01*
X848625Y1369125D01*
X848542Y1369417D01*
X848333Y1369667D01*
X847958Y1369833D01*
X847458Y1369917D01*
X847167Y1370083D01*
X847042Y1370375D01*
X847125Y1370667D01*
X847333Y1370875D01*
X847625Y1371000D01*
X847917D01*
X848208Y1370917D01*
X848458Y1370708D01*
G01X850017Y1368500D02*
Y1371000D01*
X851058D01*
X851392Y1370875D01*
X851600Y1370708D01*
X851683Y1370375D01*
X851600Y1370042D01*
X851350Y1369833D01*
X851058Y1369708D01*
X850017D01*
G01X851058D02*
X851683Y1368500D01*
G01X853950D02*
Y1371000D01*
X853450Y1370500D01*
G01Y1368500D02*
X854450D01*
G01X857050D02*
Y1371000D01*
X856550Y1370500D01*
G01Y1368500D02*
X857550D01*
G01X859358Y1370583D02*
X859608Y1370833D01*
X859900Y1370958D01*
X860233Y1371000D01*
X860650Y1370917D01*
X860942Y1370708D01*
X861025Y1370458D01*
X860983Y1370208D01*
X860817Y1370000D01*
X859983Y1369583D01*
X859608Y1369292D01*
X859358Y1368875D01*
X859275Y1368500D01*
X861025D01*
G01X862333Y1369000D02*
X862583Y1368708D01*
X862917Y1368542D01*
X863292Y1368500D01*
X863625Y1368542D01*
X863958Y1368750D01*
X864167Y1369000D01*
X864208Y1369250D01*
X864125Y1369542D01*
X863833Y1369750D01*
X863542Y1369833D01*
X863167D01*
G01X863542D02*
X863792Y1369958D01*
X864000Y1370167D01*
X864083Y1370417D01*
X864000Y1370667D01*
X863792Y1370875D01*
X863417Y1371000D01*
X863042Y1370958D01*
X862667Y1370792D01*
G01X859800Y1366488D02*
Y1362488D01*
X867200D01*
G01X862867Y1378500D02*
Y1381000D01*
X863908D01*
X864242Y1380875D01*
X864450Y1380708D01*
X864533Y1380375D01*
X864450Y1380042D01*
X864200Y1379833D01*
X863908Y1379708D01*
X862867D01*
G01X863908D02*
X864533Y1378500D01*
G01X866092Y1378792D02*
X866383Y1378583D01*
X866717Y1378500D01*
X867050Y1378583D01*
X867342Y1378833D01*
X867550Y1379208D01*
X867633Y1379583D01*
Y1380042D01*
X867550Y1380417D01*
X867342Y1380750D01*
X867092Y1380917D01*
X866800Y1381000D01*
X866467Y1380917D01*
X866217Y1380750D01*
X866050Y1380500D01*
X865967Y1380167D01*
X866050Y1379875D01*
X866258Y1379583D01*
X866508Y1379417D01*
X866800Y1379375D01*
X867133Y1379458D01*
X867383Y1379667D01*
X867633Y1380042D01*
G01X869817Y1378500D02*
X869900Y1379042D01*
X870025Y1379500D01*
X870192Y1379917D01*
X870400Y1380375D01*
X870733Y1381000D01*
X869067D01*
G01X873000Y1378500D02*
X873292Y1378542D01*
X873625Y1378667D01*
X873833Y1378875D01*
X873917Y1379167D01*
X873833Y1379458D01*
X873583Y1379708D01*
X873208Y1379833D01*
X872792D01*
X872542Y1379917D01*
X872333Y1380125D01*
X872250Y1380417D01*
X872375Y1380708D01*
X872667Y1380917D01*
X873000Y1381000D01*
X873333Y1380917D01*
X873625Y1380708D01*
X873750Y1380417D01*
X873667Y1380125D01*
X873458Y1379917D01*
X873208Y1379833D01*
X872792D01*
X872417Y1379708D01*
X872167Y1379458D01*
X872083Y1379167D01*
X872167Y1378875D01*
X872375Y1378667D01*
X872708Y1378542D01*
X873000Y1378500D01*
G01X876100D02*
X876392Y1378542D01*
X876725Y1378667D01*
X876933Y1378875D01*
X877017Y1379167D01*
X876933Y1379458D01*
X876683Y1379708D01*
X876308Y1379833D01*
X875892D01*
X875642Y1379917D01*
X875433Y1380125D01*
X875350Y1380417D01*
X875475Y1380708D01*
X875767Y1380917D01*
X876100Y1381000D01*
X876433Y1380917D01*
X876725Y1380708D01*
X876850Y1380417D01*
X876767Y1380125D01*
X876558Y1379917D01*
X876308Y1379833D01*
X875892D01*
X875517Y1379708D01*
X875267Y1379458D01*
X875183Y1379167D01*
X875267Y1378875D01*
X875475Y1378667D01*
X875808Y1378542D01*
X876100Y1378500D01*
G01X881988Y1367200D02*
Y1363200D01*
X889388D01*
G01X911700Y1360988D02*
Y1364988D01*
X904300D01*
G01X896748Y1361788D02*
X900748D01*
Y1369188D01*
G01X862967Y1381967D02*
Y1384467D01*
X864008D01*
X864342Y1384342D01*
X864550Y1384175D01*
X864633Y1383842D01*
X864550Y1383509D01*
X864300Y1383300D01*
X864008Y1383175D01*
X862967D01*
G01X864008D02*
X864633Y1381967D01*
G01X866192Y1382259D02*
X866483Y1382050D01*
X866817Y1381967D01*
X867150Y1382050D01*
X867442Y1382300D01*
X867650Y1382675D01*
X867733Y1383050D01*
Y1383509D01*
X867650Y1383884D01*
X867442Y1384217D01*
X867192Y1384384D01*
X866900Y1384467D01*
X866567Y1384384D01*
X866317Y1384217D01*
X866150Y1383967D01*
X866067Y1383634D01*
X866150Y1383342D01*
X866358Y1383050D01*
X866608Y1382884D01*
X866900Y1382842D01*
X867233Y1382925D01*
X867483Y1383134D01*
X867733Y1383509D01*
G01X869292Y1382259D02*
X869583Y1382050D01*
X869917Y1381967D01*
X870250Y1382050D01*
X870542Y1382300D01*
X870750Y1382675D01*
X870833Y1383050D01*
Y1383509D01*
X870750Y1383884D01*
X870542Y1384217D01*
X870292Y1384384D01*
X870000Y1384467D01*
X869667Y1384384D01*
X869417Y1384217D01*
X869250Y1383967D01*
X869167Y1383634D01*
X869250Y1383342D01*
X869458Y1383050D01*
X869708Y1382884D01*
X870000Y1382842D01*
X870333Y1382925D01*
X870583Y1383134D01*
X870833Y1383509D01*
G01X873100Y1381967D02*
Y1384467D01*
X872600Y1383967D01*
G01Y1381967D02*
X873600D01*
G01X875283Y1382467D02*
X875533Y1382175D01*
X875867Y1382009D01*
X876242Y1381967D01*
X876575Y1382009D01*
X876908Y1382217D01*
X877117Y1382467D01*
X877158Y1382717D01*
X877075Y1383009D01*
X876783Y1383217D01*
X876492Y1383300D01*
X876117D01*
G01X876492D02*
X876742Y1383425D01*
X876950Y1383634D01*
X877033Y1383884D01*
X876950Y1384134D01*
X876742Y1384342D01*
X876367Y1384467D01*
X875992Y1384425D01*
X875617Y1384259D01*
G01X881988Y1371700D02*
Y1367700D01*
X889388D01*
G01X874967Y1387466D02*
Y1389966D01*
X876008D01*
X876342Y1389841D01*
X876550Y1389674D01*
X876633Y1389341D01*
X876550Y1389008D01*
X876300Y1388799D01*
X876008Y1388674D01*
X874967D01*
G01X876008D02*
X876633Y1387466D01*
G01X878192Y1387758D02*
X878483Y1387549D01*
X878817Y1387466D01*
X879150Y1387549D01*
X879442Y1387799D01*
X879650Y1388174D01*
X879733Y1388549D01*
Y1389008D01*
X879650Y1389383D01*
X879442Y1389716D01*
X879192Y1389883D01*
X878900Y1389966D01*
X878567Y1389883D01*
X878317Y1389716D01*
X878150Y1389466D01*
X878067Y1389133D01*
X878150Y1388841D01*
X878358Y1388549D01*
X878608Y1388383D01*
X878900Y1388341D01*
X879233Y1388424D01*
X879483Y1388633D01*
X879733Y1389008D01*
G01X881292Y1387758D02*
X881583Y1387549D01*
X881917Y1387466D01*
X882250Y1387549D01*
X882542Y1387799D01*
X882750Y1388174D01*
X882833Y1388549D01*
Y1389008D01*
X882750Y1389383D01*
X882542Y1389716D01*
X882292Y1389883D01*
X882000Y1389966D01*
X881667Y1389883D01*
X881417Y1389716D01*
X881250Y1389466D01*
X881167Y1389133D01*
X881250Y1388841D01*
X881458Y1388549D01*
X881708Y1388383D01*
X882000Y1388341D01*
X882333Y1388424D01*
X882583Y1388633D01*
X882833Y1389008D01*
G01X884183Y1387966D02*
X884433Y1387674D01*
X884767Y1387508D01*
X885142Y1387466D01*
X885475Y1387508D01*
X885808Y1387716D01*
X886017Y1387966D01*
X886058Y1388216D01*
X885975Y1388508D01*
X885683Y1388716D01*
X885392Y1388799D01*
X885017D01*
G01X885392D02*
X885642Y1388924D01*
X885850Y1389133D01*
X885933Y1389383D01*
X885850Y1389633D01*
X885642Y1389841D01*
X885267Y1389966D01*
X884892Y1389924D01*
X884517Y1389758D01*
G01X888200Y1389966D02*
X887867Y1389883D01*
X887617Y1389674D01*
X887450Y1389424D01*
X887325Y1389091D01*
X887283Y1388716D01*
X887325Y1388341D01*
X887450Y1388008D01*
X887617Y1387758D01*
X887867Y1387549D01*
X888200Y1387466D01*
X888533Y1387549D01*
X888783Y1387758D01*
X888950Y1388008D01*
X889075Y1388341D01*
X889117Y1388716D01*
X889075Y1389091D01*
X888950Y1389424D01*
X888783Y1389674D01*
X888533Y1389883D01*
X888200Y1389966D01*
G01X891385Y1373351D02*
Y1369351D01*
X898785D01*
G01X873634Y1385767D02*
X871134D01*
Y1386808D01*
X871259Y1387142D01*
X871426Y1387350D01*
X871759Y1387433D01*
X872092Y1387350D01*
X872301Y1387100D01*
X872426Y1386808D01*
Y1385767D01*
G01Y1386808D02*
X873634Y1387433D01*
G01X873342Y1388992D02*
X873551Y1389283D01*
X873634Y1389617D01*
X873551Y1389950D01*
X873301Y1390242D01*
X872926Y1390450D01*
X872551Y1390533D01*
X872092D01*
X871717Y1390450D01*
X871384Y1390242D01*
X871217Y1389992D01*
X871134Y1389700D01*
X871217Y1389367D01*
X871384Y1389117D01*
X871634Y1388950D01*
X871967Y1388867D01*
X872259Y1388950D01*
X872551Y1389158D01*
X872717Y1389408D01*
X872759Y1389700D01*
X872676Y1390033D01*
X872467Y1390283D01*
X872092Y1390533D01*
G01X873342Y1392092D02*
X873551Y1392383D01*
X873634Y1392717D01*
X873551Y1393050D01*
X873301Y1393342D01*
X872926Y1393550D01*
X872551Y1393633D01*
X872092D01*
X871717Y1393550D01*
X871384Y1393342D01*
X871217Y1393092D01*
X871134Y1392800D01*
X871217Y1392467D01*
X871384Y1392217D01*
X871634Y1392050D01*
X871967Y1391967D01*
X872259Y1392050D01*
X872551Y1392258D01*
X872717Y1392508D01*
X872759Y1392800D01*
X872676Y1393133D01*
X872467Y1393383D01*
X872092Y1393633D01*
G01X871551Y1395108D02*
X871301Y1395358D01*
X871176Y1395650D01*
X871134Y1395983D01*
X871217Y1396400D01*
X871426Y1396692D01*
X871676Y1396775D01*
X871926Y1396733D01*
X872134Y1396567D01*
X872551Y1395733D01*
X872842Y1395358D01*
X873259Y1395108D01*
X873634Y1395025D01*
Y1396775D01*
G01X873342Y1398292D02*
X873551Y1398583D01*
X873634Y1398917D01*
X873551Y1399250D01*
X873301Y1399542D01*
X872926Y1399750D01*
X872551Y1399833D01*
X872092D01*
X871717Y1399750D01*
X871384Y1399542D01*
X871217Y1399292D01*
X871134Y1399000D01*
X871217Y1398667D01*
X871384Y1398417D01*
X871634Y1398250D01*
X871967Y1398167D01*
X872259Y1398250D01*
X872551Y1398458D01*
X872717Y1398708D01*
X872759Y1399000D01*
X872676Y1399333D01*
X872467Y1399583D01*
X872092Y1399833D01*
G01X888213Y1374496D02*
X892213D01*
Y1381896D01*
G01X887800Y1358988D02*
X901200D01*
G01X852385Y1519639D02*
X851552Y1518306D01*
X851052Y1516806D01*
Y1515472D01*
X851552Y1514139D01*
X852385Y1513139D01*
X853552Y1512639D01*
X854718Y1512972D01*
X855719Y1513806D01*
X856385Y1515306D01*
X856719Y1517306D01*
X857385Y1518472D01*
X858552Y1518972D01*
X859719Y1518639D01*
X860552Y1517806D01*
X861052Y1516639D01*
Y1515472D01*
X860719Y1514306D01*
X859885Y1513306D01*
G01X852385Y1509039D02*
X851552Y1507706D01*
X851052Y1506206D01*
Y1504872D01*
X851552Y1503539D01*
X852385Y1502539D01*
X853552Y1502039D01*
X854718Y1502372D01*
X855719Y1503206D01*
X856385Y1504706D01*
X856719Y1506706D01*
X857385Y1507872D01*
X858552Y1508372D01*
X859719Y1508039D01*
X860552Y1507206D01*
X861052Y1506039D01*
Y1504872D01*
X860719Y1503706D01*
X859885Y1502706D01*
G01X851052Y1498606D02*
X861052D01*
Y1495272D01*
X860552Y1493939D01*
X859885Y1492939D01*
X858885Y1492106D01*
X857718Y1491439D01*
X856052Y1491272D01*
X854385Y1491439D01*
X853219Y1492106D01*
X852218Y1492939D01*
X851552Y1493939D01*
X851052Y1495272D01*
Y1498606D01*
G01Y1484339D02*
X861052D01*
X859052Y1486339D01*
G01X851052D02*
Y1482339D01*
G01X869500Y1489617D02*
X869750Y1489825D01*
X869917Y1490075D01*
X870000Y1490367D01*
X869917Y1490700D01*
X869750Y1490950D01*
X869500Y1491200D01*
X869167Y1491283D01*
X867500D01*
G01X870000Y1493550D02*
X867500D01*
X868000Y1493050D01*
G01X870000D02*
Y1494050D01*
G01X868000Y1443917D02*
X865500D01*
Y1444917D01*
X865625Y1445250D01*
X865917Y1445500D01*
X866250Y1445583D01*
X866583Y1445500D01*
X866833Y1445292D01*
X866958Y1444917D01*
Y1443917D01*
G01X865708Y1448767D02*
X865583Y1448517D01*
X865500Y1448225D01*
Y1447892D01*
X865625Y1447517D01*
X865833Y1447225D01*
X866083Y1447017D01*
X866500Y1446850D01*
X866875Y1446808D01*
X867250Y1446892D01*
X867500Y1447017D01*
X867750Y1447267D01*
X867917Y1447558D01*
X868000Y1447850D01*
Y1448142D01*
X867917Y1448433D01*
X867792Y1448683D01*
X867625Y1448892D01*
G01X868000Y1450950D02*
X865500D01*
X866000Y1450450D01*
G01X868000D02*
Y1451450D01*
G01X865917Y1453258D02*
X865667Y1453508D01*
X865542Y1453800D01*
X865500Y1454133D01*
X865583Y1454550D01*
X865792Y1454842D01*
X866042Y1454925D01*
X866292Y1454883D01*
X866500Y1454717D01*
X866917Y1453883D01*
X867208Y1453508D01*
X867625Y1453258D01*
X868000Y1453175D01*
Y1454925D01*
G01X867500Y1456233D02*
X867792Y1456483D01*
X867958Y1456817D01*
X868000Y1457192D01*
X867958Y1457525D01*
X867750Y1457858D01*
X867500Y1458067D01*
X867250Y1458108D01*
X866958Y1458025D01*
X866750Y1457733D01*
X866667Y1457442D01*
Y1457067D01*
G01Y1457442D02*
X866542Y1457692D01*
X866333Y1457900D01*
X866083Y1457983D01*
X865833Y1457900D01*
X865625Y1457692D01*
X865500Y1457317D01*
X865542Y1456942D01*
X865708Y1456567D01*
G01X867708Y1459542D02*
X867917Y1459833D01*
X868000Y1460167D01*
X867917Y1460500D01*
X867667Y1460792D01*
X867292Y1461000D01*
X866917Y1461083D01*
X866458D01*
X866083Y1461000D01*
X865750Y1460792D01*
X865583Y1460542D01*
X865500Y1460250D01*
X865583Y1459917D01*
X865750Y1459667D01*
X866000Y1459500D01*
X866333Y1459417D01*
X866625Y1459500D01*
X866917Y1459708D01*
X867083Y1459958D01*
X867125Y1460250D01*
X867042Y1460583D01*
X866833Y1460833D01*
X866458Y1461083D01*
G01X870500Y1526617D02*
X868000D01*
Y1527617D01*
X868125Y1527950D01*
X868417Y1528200D01*
X868750Y1528283D01*
X869083Y1528200D01*
X869333Y1527992D01*
X869458Y1527617D01*
Y1526617D01*
G01X868208Y1531467D02*
X868083Y1531217D01*
X868000Y1530925D01*
Y1530592D01*
X868125Y1530217D01*
X868333Y1529925D01*
X868583Y1529717D01*
X869000Y1529550D01*
X869375Y1529508D01*
X869750Y1529592D01*
X870000Y1529717D01*
X870250Y1529967D01*
X870417Y1530258D01*
X870500Y1530550D01*
Y1530842D01*
X870417Y1531133D01*
X870292Y1531383D01*
X870125Y1531592D01*
G01X870500Y1533650D02*
X868000D01*
X868500Y1533150D01*
G01X870500D02*
Y1534150D01*
G01X868417Y1535958D02*
X868167Y1536208D01*
X868042Y1536500D01*
X868000Y1536833D01*
X868083Y1537250D01*
X868292Y1537542D01*
X868542Y1537625D01*
X868792Y1537583D01*
X869000Y1537417D01*
X869417Y1536583D01*
X869708Y1536208D01*
X870125Y1535958D01*
X870500Y1535875D01*
Y1537625D01*
G01X870000Y1538933D02*
X870292Y1539183D01*
X870458Y1539517D01*
X870500Y1539892D01*
X870458Y1540225D01*
X870250Y1540558D01*
X870000Y1540767D01*
X869750Y1540808D01*
X869458Y1540725D01*
X869250Y1540433D01*
X869167Y1540142D01*
Y1539767D01*
G01Y1540142D02*
X869042Y1540392D01*
X868833Y1540600D01*
X868583Y1540683D01*
X868333Y1540600D01*
X868125Y1540392D01*
X868000Y1540017D01*
X868042Y1539642D01*
X868208Y1539267D01*
G01X870500Y1542950D02*
X870458Y1543242D01*
X870333Y1543575D01*
X870125Y1543783D01*
X869833Y1543867D01*
X869542Y1543783D01*
X869292Y1543533D01*
X869167Y1543158D01*
Y1542742D01*
X869083Y1542492D01*
X868875Y1542283D01*
X868583Y1542200D01*
X868292Y1542325D01*
X868083Y1542617D01*
X868000Y1542950D01*
X868083Y1543283D01*
X868292Y1543575D01*
X868583Y1543700D01*
X868875Y1543617D01*
X869083Y1543408D01*
X869167Y1543158D01*
Y1542742D01*
X869292Y1542367D01*
X869542Y1542117D01*
X869833Y1542033D01*
X870125Y1542117D01*
X870333Y1542325D01*
X870458Y1542658D01*
X870500Y1542950D01*
G01X862900Y1570617D02*
X860400D01*
Y1571617D01*
X860525Y1571950D01*
X860817Y1572200D01*
X861150Y1572283D01*
X861483Y1572200D01*
X861733Y1571992D01*
X861858Y1571617D01*
Y1570617D01*
G01X860608Y1575467D02*
X860483Y1575217D01*
X860400Y1574925D01*
Y1574592D01*
X860525Y1574217D01*
X860733Y1573925D01*
X860983Y1573717D01*
X861400Y1573550D01*
X861775Y1573508D01*
X862150Y1573592D01*
X862400Y1573717D01*
X862650Y1573967D01*
X862817Y1574258D01*
X862900Y1574550D01*
Y1574842D01*
X862817Y1575133D01*
X862692Y1575383D01*
X862525Y1575592D01*
G01X862900Y1577650D02*
X860400D01*
X860900Y1577150D01*
G01X862900D02*
Y1578150D01*
G01X860817Y1579958D02*
X860567Y1580208D01*
X860442Y1580500D01*
X860400Y1580833D01*
X860483Y1581250D01*
X860692Y1581542D01*
X860942Y1581625D01*
X861192Y1581583D01*
X861400Y1581417D01*
X861817Y1580583D01*
X862108Y1580208D01*
X862525Y1579958D01*
X862900Y1579875D01*
Y1581625D01*
G01X862400Y1582933D02*
X862692Y1583183D01*
X862858Y1583517D01*
X862900Y1583892D01*
X862858Y1584225D01*
X862650Y1584558D01*
X862400Y1584767D01*
X862150Y1584808D01*
X861858Y1584725D01*
X861650Y1584433D01*
X861567Y1584142D01*
Y1583767D01*
G01Y1584142D02*
X861442Y1584392D01*
X861233Y1584600D01*
X860983Y1584683D01*
X860733Y1584600D01*
X860525Y1584392D01*
X860400Y1584017D01*
X860442Y1583642D01*
X860608Y1583267D01*
G01X862900Y1586867D02*
X862358Y1586950D01*
X861900Y1587075D01*
X861483Y1587242D01*
X861025Y1587450D01*
X860400Y1587783D01*
Y1586117D01*
G01X846517Y1527000D02*
Y1529500D01*
X847558D01*
X847892Y1529375D01*
X848100Y1529208D01*
X848183Y1528875D01*
X848100Y1528542D01*
X847850Y1528333D01*
X847558Y1528208D01*
X846517D01*
G01X847558D02*
X848183Y1527000D01*
G01X849533Y1527500D02*
X849783Y1527208D01*
X850117Y1527042D01*
X850492Y1527000D01*
X850825Y1527042D01*
X851158Y1527250D01*
X851367Y1527500D01*
X851408Y1527750D01*
X851325Y1528042D01*
X851033Y1528250D01*
X850742Y1528333D01*
X850367D01*
G01X850742D02*
X850992Y1528458D01*
X851200Y1528667D01*
X851283Y1528917D01*
X851200Y1529167D01*
X850992Y1529375D01*
X850617Y1529500D01*
X850242Y1529458D01*
X849867Y1529292D01*
G01X853550Y1527000D02*
X853842Y1527042D01*
X854175Y1527167D01*
X854383Y1527375D01*
X854467Y1527667D01*
X854383Y1527958D01*
X854133Y1528208D01*
X853758Y1528333D01*
X853342D01*
X853092Y1528417D01*
X852883Y1528625D01*
X852800Y1528917D01*
X852925Y1529208D01*
X853217Y1529417D01*
X853550Y1529500D01*
X853883Y1529417D01*
X854175Y1529208D01*
X854300Y1528917D01*
X854217Y1528625D01*
X854008Y1528417D01*
X853758Y1528333D01*
X853342D01*
X852967Y1528208D01*
X852717Y1527958D01*
X852633Y1527667D01*
X852717Y1527375D01*
X852925Y1527167D01*
X853258Y1527042D01*
X853550Y1527000D01*
G01X855733Y1527375D02*
X855983Y1527167D01*
X856275Y1527042D01*
X856650Y1527000D01*
X857025Y1527083D01*
X857317Y1527250D01*
X857525Y1527542D01*
X857567Y1527875D01*
X857483Y1528208D01*
X857275Y1528417D01*
X856983Y1528583D01*
X856692Y1528625D01*
X856400Y1528583D01*
X856025Y1528417D01*
X856150Y1529500D01*
X857275D01*
G01X858200Y1535500D02*
Y1539500D01*
X850800D01*
G01X846517Y1531000D02*
Y1533500D01*
X847558D01*
X847892Y1533375D01*
X848100Y1533208D01*
X848183Y1532875D01*
X848100Y1532542D01*
X847850Y1532333D01*
X847558Y1532208D01*
X846517D01*
G01X847558D02*
X848183Y1531000D01*
G01X849533Y1531500D02*
X849783Y1531208D01*
X850117Y1531042D01*
X850492Y1531000D01*
X850825Y1531042D01*
X851158Y1531250D01*
X851367Y1531500D01*
X851408Y1531750D01*
X851325Y1532042D01*
X851033Y1532250D01*
X850742Y1532333D01*
X850367D01*
G01X850742D02*
X850992Y1532458D01*
X851200Y1532667D01*
X851283Y1532917D01*
X851200Y1533167D01*
X850992Y1533375D01*
X850617Y1533500D01*
X850242Y1533458D01*
X849867Y1533292D01*
G01X853550Y1531000D02*
X853842Y1531042D01*
X854175Y1531167D01*
X854383Y1531375D01*
X854467Y1531667D01*
X854383Y1531958D01*
X854133Y1532208D01*
X853758Y1532333D01*
X853342D01*
X853092Y1532417D01*
X852883Y1532625D01*
X852800Y1532917D01*
X852925Y1533208D01*
X853217Y1533417D01*
X853550Y1533500D01*
X853883Y1533417D01*
X854175Y1533208D01*
X854300Y1532917D01*
X854217Y1532625D01*
X854008Y1532417D01*
X853758Y1532333D01*
X853342D01*
X852967Y1532208D01*
X852717Y1531958D01*
X852633Y1531667D01*
X852717Y1531375D01*
X852925Y1531167D01*
X853258Y1531042D01*
X853550Y1531000D01*
G01X855858Y1532042D02*
X856150Y1532333D01*
X856400Y1532500D01*
X856733Y1532583D01*
X857025Y1532500D01*
X857233Y1532333D01*
X857400Y1532083D01*
X857442Y1531792D01*
X857400Y1531542D01*
X857233Y1531292D01*
X856983Y1531083D01*
X856692Y1531000D01*
X856358Y1531083D01*
X856067Y1531333D01*
X855900Y1531708D01*
X855858Y1532125D01*
X855942Y1532667D01*
X856067Y1532958D01*
X856275Y1533250D01*
X856567Y1533458D01*
X856858Y1533500D01*
X857150Y1533417D01*
X857358Y1533208D01*
G01X858200Y1540500D02*
Y1544500D01*
X850800D01*
G01X847600Y1553200D02*
X843600D01*
Y1545800D01*
G01X853500D02*
X857500D01*
Y1553200D01*
G01X839900Y1577300D02*
Y1558100D01*
X851100D01*
Y1577300D01*
X839900D01*
G01X847500D02*
X845500Y1575300D01*
X843500Y1577300D01*
G01X887300Y1567617D02*
X884800D01*
Y1568617D01*
X884925Y1568950D01*
X885217Y1569200D01*
X885550Y1569283D01*
X885883Y1569200D01*
X886133Y1568992D01*
X886258Y1568617D01*
Y1567617D01*
G01X885008Y1572467D02*
X884883Y1572217D01*
X884800Y1571925D01*
Y1571592D01*
X884925Y1571217D01*
X885133Y1570925D01*
X885383Y1570717D01*
X885800Y1570550D01*
X886175Y1570508D01*
X886550Y1570592D01*
X886800Y1570717D01*
X887050Y1570967D01*
X887217Y1571258D01*
X887300Y1571550D01*
Y1571842D01*
X887217Y1572133D01*
X887092Y1572383D01*
X886925Y1572592D01*
G01X887300Y1574650D02*
X884800D01*
X885300Y1574150D01*
G01X887300D02*
Y1575150D01*
G01X885217Y1576958D02*
X884967Y1577208D01*
X884842Y1577500D01*
X884800Y1577833D01*
X884883Y1578250D01*
X885092Y1578542D01*
X885342Y1578625D01*
X885592Y1578583D01*
X885800Y1578417D01*
X886217Y1577583D01*
X886508Y1577208D01*
X886925Y1576958D01*
X887300Y1576875D01*
Y1578625D01*
G01X886800Y1579933D02*
X887092Y1580183D01*
X887258Y1580517D01*
X887300Y1580892D01*
X887258Y1581225D01*
X887050Y1581558D01*
X886800Y1581767D01*
X886550Y1581808D01*
X886258Y1581725D01*
X886050Y1581433D01*
X885967Y1581142D01*
Y1580767D01*
G01Y1581142D02*
X885842Y1581392D01*
X885633Y1581600D01*
X885383Y1581683D01*
X885133Y1581600D01*
X884925Y1581392D01*
X884800Y1581017D01*
X884842Y1580642D01*
X885008Y1580267D01*
G01X886925Y1583033D02*
X887133Y1583283D01*
X887258Y1583575D01*
X887300Y1583950D01*
X887217Y1584325D01*
X887050Y1584617D01*
X886758Y1584825D01*
X886425Y1584867D01*
X886092Y1584783D01*
X885883Y1584575D01*
X885717Y1584283D01*
X885675Y1583992D01*
X885717Y1583700D01*
X885883Y1583325D01*
X884800Y1583450D01*
Y1584575D01*
G01X879650Y1586850D02*
Y1568150D01*
X869350D01*
Y1586850D01*
X879650D01*
G01X861700Y1529317D02*
X859200D01*
Y1530317D01*
X859325Y1530650D01*
X859617Y1530900D01*
X859950Y1530983D01*
X860283Y1530900D01*
X860533Y1530692D01*
X860658Y1530317D01*
Y1529317D01*
G01X859408Y1534167D02*
X859283Y1533917D01*
X859200Y1533625D01*
Y1533292D01*
X859325Y1532917D01*
X859533Y1532625D01*
X859783Y1532417D01*
X860200Y1532250D01*
X860575Y1532208D01*
X860950Y1532292D01*
X861200Y1532417D01*
X861450Y1532667D01*
X861617Y1532958D01*
X861700Y1533250D01*
Y1533542D01*
X861617Y1533833D01*
X861492Y1534083D01*
X861325Y1534292D01*
G01X861700Y1536350D02*
X859200D01*
X859700Y1535850D01*
G01X861700D02*
Y1536850D01*
G01X859617Y1538658D02*
X859367Y1538908D01*
X859242Y1539200D01*
X859200Y1539533D01*
X859283Y1539950D01*
X859492Y1540242D01*
X859742Y1540325D01*
X859992Y1540283D01*
X860200Y1540117D01*
X860617Y1539283D01*
X860908Y1538908D01*
X861325Y1538658D01*
X861700Y1538575D01*
Y1540325D01*
G01X861200Y1541633D02*
X861492Y1541883D01*
X861658Y1542217D01*
X861700Y1542592D01*
X861658Y1542925D01*
X861450Y1543258D01*
X861200Y1543467D01*
X860950Y1543508D01*
X860658Y1543425D01*
X860450Y1543133D01*
X860367Y1542842D01*
Y1542467D01*
G01Y1542842D02*
X860242Y1543092D01*
X860033Y1543300D01*
X859783Y1543383D01*
X859533Y1543300D01*
X859325Y1543092D01*
X859200Y1542717D01*
X859242Y1542342D01*
X859408Y1541967D01*
G01X860658Y1544858D02*
X860367Y1545150D01*
X860200Y1545400D01*
X860117Y1545733D01*
X860200Y1546025D01*
X860367Y1546233D01*
X860617Y1546400D01*
X860908Y1546442D01*
X861158Y1546400D01*
X861408Y1546233D01*
X861617Y1545983D01*
X861700Y1545692D01*
X861617Y1545358D01*
X861367Y1545067D01*
X860992Y1544900D01*
X860575Y1544858D01*
X860033Y1544942D01*
X859742Y1545067D01*
X859450Y1545275D01*
X859242Y1545567D01*
X859200Y1545858D01*
X859283Y1546150D01*
X859492Y1546358D01*
G01X861150Y1548350D02*
Y1567050D01*
X871450D01*
Y1548350D01*
X861150D01*
G01X847900Y1599000D02*
X847567Y1599042D01*
X847275Y1599208D01*
X847025Y1599458D01*
X846858Y1599750D01*
X846775Y1600083D01*
Y1600417D01*
X846858Y1600750D01*
X847025Y1601042D01*
X847275Y1601292D01*
X847567Y1601458D01*
X847900Y1601500D01*
X848233Y1601458D01*
X848525Y1601292D01*
X848775Y1601042D01*
X848942Y1600750D01*
X849025Y1600417D01*
Y1600083D01*
X848942Y1599750D01*
X848775Y1599458D01*
X848525Y1599208D01*
X848233Y1599042D01*
X847900Y1599000D01*
G01X848233Y1599667D02*
X848733Y1599000D01*
G01X850083Y1599500D02*
X850333Y1599208D01*
X850667Y1599042D01*
X851042Y1599000D01*
X851375Y1599042D01*
X851708Y1599250D01*
X851917Y1599500D01*
X851958Y1599750D01*
X851875Y1600042D01*
X851583Y1600250D01*
X851292Y1600333D01*
X850917D01*
G01X851292D02*
X851542Y1600458D01*
X851750Y1600667D01*
X851833Y1600917D01*
X851750Y1601167D01*
X851542Y1601375D01*
X851167Y1601500D01*
X850792Y1601458D01*
X850417Y1601292D01*
G01X853308Y1601083D02*
X853558Y1601333D01*
X853850Y1601458D01*
X854183Y1601500D01*
X854600Y1601417D01*
X854892Y1601208D01*
X854975Y1600958D01*
X854933Y1600708D01*
X854767Y1600500D01*
X853933Y1600083D01*
X853558Y1599792D01*
X853308Y1599375D01*
X853225Y1599000D01*
X854975D01*
G01X843000Y1596900D02*
Y1583900D01*
G01D02*
X857000D01*
G01D02*
Y1596900D01*
G01D02*
X843000D01*
G01Y1598967D02*
X840500D01*
Y1600008D01*
X840625Y1600342D01*
X840792Y1600550D01*
X841125Y1600633D01*
X841458Y1600550D01*
X841667Y1600300D01*
X841792Y1600008D01*
Y1598967D01*
G01Y1600008D02*
X843000Y1600633D01*
G01X842708Y1602192D02*
X842917Y1602483D01*
X843000Y1602817D01*
X842917Y1603150D01*
X842667Y1603442D01*
X842292Y1603650D01*
X841917Y1603733D01*
X841458D01*
X841083Y1603650D01*
X840750Y1603442D01*
X840583Y1603192D01*
X840500Y1602900D01*
X840583Y1602567D01*
X840750Y1602317D01*
X841000Y1602150D01*
X841333Y1602067D01*
X841625Y1602150D01*
X841917Y1602358D01*
X842083Y1602608D01*
X842125Y1602900D01*
X842042Y1603233D01*
X841833Y1603483D01*
X841458Y1603733D01*
G01X843000Y1605917D02*
X842458Y1606000D01*
X842000Y1606125D01*
X841583Y1606292D01*
X841125Y1606500D01*
X840500Y1606833D01*
Y1605167D01*
G01X843000Y1609100D02*
X842958Y1609392D01*
X842833Y1609725D01*
X842625Y1609933D01*
X842333Y1610017D01*
X842042Y1609933D01*
X841792Y1609683D01*
X841667Y1609308D01*
Y1608892D01*
X841583Y1608642D01*
X841375Y1608433D01*
X841083Y1608350D01*
X840792Y1608475D01*
X840583Y1608767D01*
X840500Y1609100D01*
X840583Y1609433D01*
X840792Y1609725D01*
X841083Y1609850D01*
X841375Y1609767D01*
X841583Y1609558D01*
X841667Y1609308D01*
Y1608892D01*
X841792Y1608517D01*
X842042Y1608267D01*
X842333Y1608183D01*
X842625Y1608267D01*
X842833Y1608475D01*
X842958Y1608808D01*
X843000Y1609100D01*
G01X841958Y1611408D02*
X841667Y1611700D01*
X841500Y1611950D01*
X841417Y1612283D01*
X841500Y1612575D01*
X841667Y1612783D01*
X841917Y1612950D01*
X842208Y1612992D01*
X842458Y1612950D01*
X842708Y1612783D01*
X842917Y1612533D01*
X843000Y1612242D01*
X842917Y1611908D01*
X842667Y1611617D01*
X842292Y1611450D01*
X841875Y1611408D01*
X841333Y1611492D01*
X841042Y1611617D01*
X840750Y1611825D01*
X840542Y1612117D01*
X840500Y1612408D01*
X840583Y1612700D01*
X840792Y1612908D01*
G01X862817Y1599500D02*
Y1602000D01*
X863858D01*
X864192Y1601875D01*
X864400Y1601708D01*
X864483Y1601375D01*
X864400Y1601042D01*
X864150Y1600833D01*
X863858Y1600708D01*
X862817D01*
G01X863858D02*
X864483Y1599500D01*
G01X866042Y1599792D02*
X866333Y1599583D01*
X866667Y1599500D01*
X867000Y1599583D01*
X867292Y1599833D01*
X867500Y1600208D01*
X867583Y1600583D01*
Y1601042D01*
X867500Y1601417D01*
X867292Y1601750D01*
X867042Y1601917D01*
X866750Y1602000D01*
X866417Y1601917D01*
X866167Y1601750D01*
X866000Y1601500D01*
X865917Y1601167D01*
X866000Y1600875D01*
X866208Y1600583D01*
X866458Y1600417D01*
X866750Y1600375D01*
X867083Y1600458D01*
X867333Y1600667D01*
X867583Y1601042D01*
G01X869767Y1599500D02*
X869850Y1600042D01*
X869975Y1600500D01*
X870142Y1600917D01*
X870350Y1601375D01*
X870683Y1602000D01*
X869017D01*
G01X872950Y1599500D02*
X873242Y1599542D01*
X873575Y1599667D01*
X873783Y1599875D01*
X873867Y1600167D01*
X873783Y1600458D01*
X873533Y1600708D01*
X873158Y1600833D01*
X872742D01*
X872492Y1600917D01*
X872283Y1601125D01*
X872200Y1601417D01*
X872325Y1601708D01*
X872617Y1601917D01*
X872950Y1602000D01*
X873283Y1601917D01*
X873575Y1601708D01*
X873700Y1601417D01*
X873617Y1601125D01*
X873408Y1600917D01*
X873158Y1600833D01*
X872742D01*
X872367Y1600708D01*
X872117Y1600458D01*
X872033Y1600167D01*
X872117Y1599875D01*
X872325Y1599667D01*
X872658Y1599542D01*
X872950Y1599500D01*
G01X876550D02*
Y1602000D01*
X875008Y1600208D01*
X877092D01*
G01X876800Y1590900D02*
X871600D01*
G01X876800Y1597900D02*
X869000D01*
G01X876800Y1590900D02*
Y1597900D01*
G01X863400Y1590900D02*
X872100D01*
G01X863400Y1597900D02*
Y1590900D01*
G01X869800Y1597900D02*
X863400D01*
G01X846983Y1581500D02*
Y1579708D01*
X847150Y1579333D01*
X847483Y1579083D01*
X847900Y1579000D01*
X848317Y1579083D01*
X848650Y1579333D01*
X848817Y1579708D01*
Y1581500D01*
G01X851000Y1579000D02*
Y1581500D01*
X850500Y1581000D01*
G01Y1579000D02*
X851500D01*
G01X854100Y1581500D02*
X853767Y1581417D01*
X853517Y1581208D01*
X853350Y1580958D01*
X853225Y1580625D01*
X853183Y1580250D01*
X853225Y1579875D01*
X853350Y1579542D01*
X853517Y1579292D01*
X853767Y1579083D01*
X854100Y1579000D01*
X854433Y1579083D01*
X854683Y1579292D01*
X854850Y1579542D01*
X854975Y1579875D01*
X855017Y1580250D01*
X854975Y1580625D01*
X854850Y1580958D01*
X854683Y1581208D01*
X854433Y1581417D01*
X854100Y1581500D01*
G01X894467Y1594000D02*
Y1596500D01*
X895508D01*
X895842Y1596375D01*
X896050Y1596208D01*
X896133Y1595875D01*
X896050Y1595542D01*
X895800Y1595333D01*
X895508Y1595208D01*
X894467D01*
G01X895508D02*
X896133Y1594000D01*
G01X897692Y1594292D02*
X897983Y1594083D01*
X898317Y1594000D01*
X898650Y1594083D01*
X898942Y1594333D01*
X899150Y1594708D01*
X899233Y1595083D01*
Y1595542D01*
X899150Y1595917D01*
X898942Y1596250D01*
X898692Y1596417D01*
X898400Y1596500D01*
X898067Y1596417D01*
X897817Y1596250D01*
X897650Y1596000D01*
X897567Y1595667D01*
X897650Y1595375D01*
X897858Y1595083D01*
X898108Y1594917D01*
X898400Y1594875D01*
X898733Y1594958D01*
X898983Y1595167D01*
X899233Y1595542D01*
G01X900708Y1596083D02*
X900958Y1596333D01*
X901250Y1596458D01*
X901583Y1596500D01*
X902000Y1596417D01*
X902292Y1596208D01*
X902375Y1595958D01*
X902333Y1595708D01*
X902167Y1595500D01*
X901333Y1595083D01*
X900958Y1594792D01*
X900708Y1594375D01*
X900625Y1594000D01*
X902375D01*
G01X905100D02*
Y1596500D01*
X903558Y1594708D01*
X905642D01*
G01X907700Y1594000D02*
X907992Y1594042D01*
X908325Y1594167D01*
X908533Y1594375D01*
X908617Y1594667D01*
X908533Y1594958D01*
X908283Y1595208D01*
X907908Y1595333D01*
X907492D01*
X907242Y1595417D01*
X907033Y1595625D01*
X906950Y1595917D01*
X907075Y1596208D01*
X907367Y1596417D01*
X907700Y1596500D01*
X908033Y1596417D01*
X908325Y1596208D01*
X908450Y1595917D01*
X908367Y1595625D01*
X908158Y1595417D01*
X907908Y1595333D01*
X907492D01*
X907117Y1595208D01*
X906867Y1594958D01*
X906783Y1594667D01*
X906867Y1594375D01*
X907075Y1594167D01*
X907408Y1594042D01*
X907700Y1594000D01*
G01X888300Y1578100D02*
X914300D01*
G01X888300Y1591100D02*
Y1578100D01*
G01X914300Y1591100D02*
X888300D01*
G01X855004Y1681462D02*
Y1683962D01*
X856004D01*
X856337Y1683837D01*
X856587Y1683545D01*
X856670Y1683212D01*
X856587Y1682879D01*
X856379Y1682629D01*
X856004Y1682504D01*
X855004D01*
G01X859854Y1683754D02*
X859604Y1683879D01*
X859312Y1683962D01*
X858979D01*
X858604Y1683837D01*
X858312Y1683629D01*
X858104Y1683379D01*
X857937Y1682962D01*
X857895Y1682587D01*
X857979Y1682212D01*
X858104Y1681962D01*
X858354Y1681712D01*
X858645Y1681545D01*
X858937Y1681462D01*
X859229D01*
X859520Y1681545D01*
X859770Y1681670D01*
X859979Y1681837D01*
G01X862037Y1681462D02*
Y1683962D01*
X861537Y1683462D01*
G01Y1681462D02*
X862537D01*
G01X864345Y1683545D02*
X864595Y1683795D01*
X864887Y1683920D01*
X865220Y1683962D01*
X865637Y1683879D01*
X865929Y1683670D01*
X866012Y1683420D01*
X865970Y1683170D01*
X865804Y1682962D01*
X864970Y1682545D01*
X864595Y1682254D01*
X864345Y1681837D01*
X864262Y1681462D01*
X866012D01*
G01X867320Y1681837D02*
X867570Y1681629D01*
X867862Y1681504D01*
X868237Y1681462D01*
X868612Y1681545D01*
X868904Y1681712D01*
X869112Y1682004D01*
X869154Y1682337D01*
X869070Y1682670D01*
X868862Y1682879D01*
X868570Y1683045D01*
X868279Y1683087D01*
X867987Y1683045D01*
X867612Y1682879D01*
X867737Y1683962D01*
X868862D01*
G01X870629Y1681754D02*
X870920Y1681545D01*
X871254Y1681462D01*
X871587Y1681545D01*
X871879Y1681795D01*
X872087Y1682170D01*
X872170Y1682545D01*
Y1683004D01*
X872087Y1683379D01*
X871879Y1683712D01*
X871629Y1683879D01*
X871337Y1683962D01*
X871004Y1683879D01*
X870754Y1683712D01*
X870587Y1683462D01*
X870504Y1683129D01*
X870587Y1682837D01*
X870795Y1682545D01*
X871045Y1682379D01*
X871337Y1682337D01*
X871670Y1682420D01*
X871920Y1682629D01*
X872170Y1683004D01*
G01X900329Y1662737D02*
X897829D01*
Y1663737D01*
X897954Y1664070D01*
X898246Y1664320D01*
X898579Y1664403D01*
X898912Y1664320D01*
X899162Y1664112D01*
X899287Y1663737D01*
Y1662737D01*
G01X898037Y1667587D02*
X897912Y1667337D01*
X897829Y1667045D01*
Y1666712D01*
X897954Y1666337D01*
X898162Y1666045D01*
X898412Y1665837D01*
X898829Y1665670D01*
X899204Y1665628D01*
X899579Y1665712D01*
X899829Y1665837D01*
X900079Y1666087D01*
X900246Y1666378D01*
X900329Y1666670D01*
Y1666962D01*
X900246Y1667253D01*
X900121Y1667503D01*
X899954Y1667712D01*
G01X900329Y1669770D02*
X897829D01*
X898329Y1669270D01*
G01X900329D02*
Y1670270D01*
G01X898246Y1672078D02*
X897996Y1672328D01*
X897871Y1672620D01*
X897829Y1672953D01*
X897912Y1673370D01*
X898121Y1673662D01*
X898371Y1673745D01*
X898621Y1673703D01*
X898829Y1673537D01*
X899246Y1672703D01*
X899537Y1672328D01*
X899954Y1672078D01*
X900329Y1671995D01*
Y1673745D01*
G01Y1675970D02*
X900287Y1676262D01*
X900162Y1676595D01*
X899954Y1676803D01*
X899662Y1676887D01*
X899371Y1676803D01*
X899121Y1676553D01*
X898996Y1676178D01*
Y1675762D01*
X898912Y1675512D01*
X898704Y1675303D01*
X898412Y1675220D01*
X898121Y1675345D01*
X897912Y1675637D01*
X897829Y1675970D01*
X897912Y1676303D01*
X898121Y1676595D01*
X898412Y1676720D01*
X898704Y1676637D01*
X898912Y1676428D01*
X898996Y1676178D01*
Y1675762D01*
X899121Y1675387D01*
X899371Y1675137D01*
X899662Y1675053D01*
X899954Y1675137D01*
X900162Y1675345D01*
X900287Y1675678D01*
X900329Y1675970D01*
G01Y1679070D02*
X897829D01*
X898329Y1678570D01*
G01X900329D02*
Y1679570D01*
G01X848000Y1685917D02*
X845500D01*
Y1686917D01*
X845625Y1687250D01*
X845917Y1687500D01*
X846250Y1687583D01*
X846583Y1687500D01*
X846833Y1687292D01*
X846958Y1686917D01*
Y1685917D01*
G01X845708Y1690767D02*
X845583Y1690517D01*
X845500Y1690225D01*
Y1689892D01*
X845625Y1689517D01*
X845833Y1689225D01*
X846083Y1689017D01*
X846500Y1688850D01*
X846875Y1688808D01*
X847250Y1688892D01*
X847500Y1689017D01*
X847750Y1689267D01*
X847917Y1689558D01*
X848000Y1689850D01*
Y1690142D01*
X847917Y1690433D01*
X847792Y1690683D01*
X847625Y1690892D01*
G01X848000Y1692950D02*
X845500D01*
X846000Y1692450D01*
G01X848000D02*
Y1693450D01*
G01X845917Y1695258D02*
X845667Y1695508D01*
X845542Y1695800D01*
X845500Y1696133D01*
X845583Y1696550D01*
X845792Y1696842D01*
X846042Y1696925D01*
X846292Y1696883D01*
X846500Y1696717D01*
X846917Y1695883D01*
X847208Y1695508D01*
X847625Y1695258D01*
X848000Y1695175D01*
Y1696925D01*
G01Y1699067D02*
X847458Y1699150D01*
X847000Y1699275D01*
X846583Y1699442D01*
X846125Y1699650D01*
X845500Y1699983D01*
Y1698317D01*
G01X847500Y1701333D02*
X847792Y1701583D01*
X847958Y1701917D01*
X848000Y1702292D01*
X847958Y1702625D01*
X847750Y1702958D01*
X847500Y1703167D01*
X847250Y1703208D01*
X846958Y1703125D01*
X846750Y1702833D01*
X846667Y1702542D01*
Y1702167D01*
G01Y1702542D02*
X846542Y1702792D01*
X846333Y1703000D01*
X846083Y1703083D01*
X845833Y1703000D01*
X845625Y1702792D01*
X845500Y1702417D01*
X845542Y1702042D01*
X845708Y1701667D01*
G01X869500Y1686417D02*
X867000D01*
Y1687417D01*
X867125Y1687750D01*
X867417Y1688000D01*
X867750Y1688083D01*
X868083Y1688000D01*
X868333Y1687792D01*
X868458Y1687417D01*
Y1686417D01*
G01X867208Y1691267D02*
X867083Y1691017D01*
X867000Y1690725D01*
Y1690392D01*
X867125Y1690017D01*
X867333Y1689725D01*
X867583Y1689517D01*
X868000Y1689350D01*
X868375Y1689308D01*
X868750Y1689392D01*
X869000Y1689517D01*
X869250Y1689767D01*
X869417Y1690058D01*
X869500Y1690350D01*
Y1690642D01*
X869417Y1690933D01*
X869292Y1691183D01*
X869125Y1691392D01*
G01X869500Y1693450D02*
X867000D01*
X867500Y1692950D01*
G01X869500D02*
Y1693950D01*
G01X867417Y1695758D02*
X867167Y1696008D01*
X867042Y1696300D01*
X867000Y1696633D01*
X867083Y1697050D01*
X867292Y1697342D01*
X867542Y1697425D01*
X867792Y1697383D01*
X868000Y1697217D01*
X868417Y1696383D01*
X868708Y1696008D01*
X869125Y1695758D01*
X869500Y1695675D01*
Y1697425D01*
G01Y1699567D02*
X868958Y1699650D01*
X868500Y1699775D01*
X868083Y1699942D01*
X867625Y1700150D01*
X867000Y1700483D01*
Y1698817D01*
G01X869500Y1703250D02*
X867000D01*
X868792Y1701708D01*
Y1703792D01*
G01X909829Y1664237D02*
X907329D01*
Y1665237D01*
X907454Y1665570D01*
X907746Y1665820D01*
X908079Y1665903D01*
X908412Y1665820D01*
X908662Y1665612D01*
X908787Y1665237D01*
Y1664237D01*
G01X909829Y1667337D02*
X907329D01*
Y1668378D01*
X907454Y1668712D01*
X907621Y1668920D01*
X907954Y1669003D01*
X908287Y1668920D01*
X908496Y1668670D01*
X908621Y1668378D01*
Y1667337D01*
G01Y1668378D02*
X909829Y1669003D01*
G01X909537Y1670562D02*
X909746Y1670853D01*
X909829Y1671187D01*
X909746Y1671520D01*
X909496Y1671812D01*
X909121Y1672020D01*
X908746Y1672103D01*
X908287D01*
X907912Y1672020D01*
X907579Y1671812D01*
X907412Y1671562D01*
X907329Y1671270D01*
X907412Y1670937D01*
X907579Y1670687D01*
X907829Y1670520D01*
X908162Y1670437D01*
X908454Y1670520D01*
X908746Y1670728D01*
X908912Y1670978D01*
X908954Y1671270D01*
X908871Y1671603D01*
X908662Y1671853D01*
X908287Y1672103D01*
G01X907329Y1674370D02*
X907412Y1674037D01*
X907621Y1673787D01*
X907871Y1673620D01*
X908204Y1673495D01*
X908579Y1673453D01*
X908954Y1673495D01*
X909287Y1673620D01*
X909537Y1673787D01*
X909746Y1674037D01*
X909829Y1674370D01*
X909746Y1674703D01*
X909537Y1674953D01*
X909287Y1675120D01*
X908954Y1675245D01*
X908579Y1675287D01*
X908204Y1675245D01*
X907871Y1675120D01*
X907621Y1674953D01*
X907412Y1674703D01*
X907329Y1674370D01*
G01X909829Y1677470D02*
X909787Y1677762D01*
X909662Y1678095D01*
X909454Y1678303D01*
X909162Y1678387D01*
X908871Y1678303D01*
X908621Y1678053D01*
X908496Y1677678D01*
Y1677262D01*
X908412Y1677012D01*
X908204Y1676803D01*
X907912Y1676720D01*
X907621Y1676845D01*
X907412Y1677137D01*
X907329Y1677470D01*
X907412Y1677803D01*
X907621Y1678095D01*
X907912Y1678220D01*
X908204Y1678137D01*
X908412Y1677928D01*
X908496Y1677678D01*
Y1677262D01*
X908621Y1676887D01*
X908871Y1676637D01*
X909162Y1676553D01*
X909454Y1676637D01*
X909662Y1676845D01*
X909787Y1677178D01*
X909829Y1677470D01*
G01Y1680570D02*
X907329D01*
X907829Y1680070D01*
G01X909829D02*
Y1681070D01*
G01X908000Y1693200D02*
X904000D01*
Y1685800D01*
G01X917200Y1693000D02*
Y1697000D01*
X909800D01*
G01X917200Y1701000D02*
Y1705000D01*
X909800D01*
G01X873500Y1686417D02*
X871000D01*
Y1687417D01*
X871125Y1687750D01*
X871417Y1688000D01*
X871750Y1688083D01*
X872083Y1688000D01*
X872333Y1687792D01*
X872458Y1687417D01*
Y1686417D01*
G01X873500Y1689517D02*
X871000D01*
Y1690558D01*
X871125Y1690892D01*
X871292Y1691100D01*
X871625Y1691183D01*
X871958Y1691100D01*
X872167Y1690850D01*
X872292Y1690558D01*
Y1689517D01*
G01Y1690558D02*
X873500Y1691183D01*
G01X873208Y1692742D02*
X873417Y1693033D01*
X873500Y1693367D01*
X873417Y1693700D01*
X873167Y1693992D01*
X872792Y1694200D01*
X872417Y1694283D01*
X871958D01*
X871583Y1694200D01*
X871250Y1693992D01*
X871083Y1693742D01*
X871000Y1693450D01*
X871083Y1693117D01*
X871250Y1692867D01*
X871500Y1692700D01*
X871833Y1692617D01*
X872125Y1692700D01*
X872417Y1692908D01*
X872583Y1693158D01*
X872625Y1693450D01*
X872542Y1693783D01*
X872333Y1694033D01*
X871958Y1694283D01*
G01X871000Y1696550D02*
X871083Y1696217D01*
X871292Y1695967D01*
X871542Y1695800D01*
X871875Y1695675D01*
X872250Y1695633D01*
X872625Y1695675D01*
X872958Y1695800D01*
X873208Y1695967D01*
X873417Y1696217D01*
X873500Y1696550D01*
X873417Y1696883D01*
X873208Y1697133D01*
X872958Y1697300D01*
X872625Y1697425D01*
X872250Y1697467D01*
X871875Y1697425D01*
X871542Y1697300D01*
X871292Y1697133D01*
X871083Y1696883D01*
X871000Y1696550D01*
G01X873500Y1699650D02*
X873458Y1699942D01*
X873333Y1700275D01*
X873125Y1700483D01*
X872833Y1700567D01*
X872542Y1700483D01*
X872292Y1700233D01*
X872167Y1699858D01*
Y1699442D01*
X872083Y1699192D01*
X871875Y1698983D01*
X871583Y1698900D01*
X871292Y1699025D01*
X871083Y1699317D01*
X871000Y1699650D01*
X871083Y1699983D01*
X871292Y1700275D01*
X871583Y1700400D01*
X871875Y1700317D01*
X872083Y1700108D01*
X872167Y1699858D01*
Y1699442D01*
X872292Y1699067D01*
X872542Y1698817D01*
X872833Y1698733D01*
X873125Y1698817D01*
X873333Y1699025D01*
X873458Y1699358D01*
X873500Y1699650D01*
G01X871000Y1702750D02*
X871083Y1702417D01*
X871292Y1702167D01*
X871542Y1702000D01*
X871875Y1701875D01*
X872250Y1701833D01*
X872625Y1701875D01*
X872958Y1702000D01*
X873208Y1702167D01*
X873417Y1702417D01*
X873500Y1702750D01*
X873417Y1703083D01*
X873208Y1703333D01*
X872958Y1703500D01*
X872625Y1703625D01*
X872250Y1703667D01*
X871875Y1703625D01*
X871542Y1703500D01*
X871292Y1703333D01*
X871083Y1703083D01*
X871000Y1702750D01*
G01X879500Y1694300D02*
X883500D01*
Y1701700D01*
G01X852000Y1685917D02*
X849500D01*
Y1686917D01*
X849625Y1687250D01*
X849917Y1687500D01*
X850250Y1687583D01*
X850583Y1687500D01*
X850833Y1687292D01*
X850958Y1686917D01*
Y1685917D01*
G01X852000Y1689017D02*
X849500D01*
Y1690058D01*
X849625Y1690392D01*
X849792Y1690600D01*
X850125Y1690683D01*
X850458Y1690600D01*
X850667Y1690350D01*
X850792Y1690058D01*
Y1689017D01*
G01Y1690058D02*
X852000Y1690683D01*
G01X851708Y1692242D02*
X851917Y1692533D01*
X852000Y1692867D01*
X851917Y1693200D01*
X851667Y1693492D01*
X851292Y1693700D01*
X850917Y1693783D01*
X850458D01*
X850083Y1693700D01*
X849750Y1693492D01*
X849583Y1693242D01*
X849500Y1692950D01*
X849583Y1692617D01*
X849750Y1692367D01*
X850000Y1692200D01*
X850333Y1692117D01*
X850625Y1692200D01*
X850917Y1692408D01*
X851083Y1692658D01*
X851125Y1692950D01*
X851042Y1693283D01*
X850833Y1693533D01*
X850458Y1693783D01*
G01X849500Y1696050D02*
X849583Y1695717D01*
X849792Y1695467D01*
X850042Y1695300D01*
X850375Y1695175D01*
X850750Y1695133D01*
X851125Y1695175D01*
X851458Y1695300D01*
X851708Y1695467D01*
X851917Y1695717D01*
X852000Y1696050D01*
X851917Y1696383D01*
X851708Y1696633D01*
X851458Y1696800D01*
X851125Y1696925D01*
X850750Y1696967D01*
X850375Y1696925D01*
X850042Y1696800D01*
X849792Y1696633D01*
X849583Y1696383D01*
X849500Y1696050D01*
G01X852000Y1699150D02*
X851958Y1699442D01*
X851833Y1699775D01*
X851625Y1699983D01*
X851333Y1700067D01*
X851042Y1699983D01*
X850792Y1699733D01*
X850667Y1699358D01*
Y1698942D01*
X850583Y1698692D01*
X850375Y1698483D01*
X850083Y1698400D01*
X849792Y1698525D01*
X849583Y1698817D01*
X849500Y1699150D01*
X849583Y1699483D01*
X849792Y1699775D01*
X850083Y1699900D01*
X850375Y1699817D01*
X850583Y1699608D01*
X850667Y1699358D01*
Y1698942D01*
X850792Y1698567D01*
X851042Y1698317D01*
X851333Y1698233D01*
X851625Y1698317D01*
X851833Y1698525D01*
X851958Y1698858D01*
X852000Y1699150D01*
G01Y1702750D02*
X849500D01*
X851292Y1701208D01*
Y1703292D01*
G01X861500Y1704700D02*
X857500D01*
Y1697300D01*
G01X905329Y1662737D02*
X902829D01*
Y1663737D01*
X902954Y1664070D01*
X903246Y1664320D01*
X903579Y1664403D01*
X903912Y1664320D01*
X904162Y1664112D01*
X904287Y1663737D01*
Y1662737D01*
G01X905329Y1665837D02*
X902829D01*
Y1666878D01*
X902954Y1667212D01*
X903121Y1667420D01*
X903454Y1667503D01*
X903787Y1667420D01*
X903996Y1667170D01*
X904121Y1666878D01*
Y1665837D01*
G01Y1666878D02*
X905329Y1667503D01*
G01X905037Y1669062D02*
X905246Y1669353D01*
X905329Y1669687D01*
X905246Y1670020D01*
X904996Y1670312D01*
X904621Y1670520D01*
X904246Y1670603D01*
X903787D01*
X903412Y1670520D01*
X903079Y1670312D01*
X902912Y1670062D01*
X902829Y1669770D01*
X902912Y1669437D01*
X903079Y1669187D01*
X903329Y1669020D01*
X903662Y1668937D01*
X903954Y1669020D01*
X904246Y1669228D01*
X904412Y1669478D01*
X904454Y1669770D01*
X904371Y1670103D01*
X904162Y1670353D01*
X903787Y1670603D01*
G01X902829Y1672870D02*
X902912Y1672537D01*
X903121Y1672287D01*
X903371Y1672120D01*
X903704Y1671995D01*
X904079Y1671953D01*
X904454Y1671995D01*
X904787Y1672120D01*
X905037Y1672287D01*
X905246Y1672537D01*
X905329Y1672870D01*
X905246Y1673203D01*
X905037Y1673453D01*
X904787Y1673620D01*
X904454Y1673745D01*
X904079Y1673787D01*
X903704Y1673745D01*
X903371Y1673620D01*
X903121Y1673453D01*
X902912Y1673203D01*
X902829Y1672870D01*
G01X905329Y1675970D02*
X905287Y1676262D01*
X905162Y1676595D01*
X904954Y1676803D01*
X904662Y1676887D01*
X904371Y1676803D01*
X904121Y1676553D01*
X903996Y1676178D01*
Y1675762D01*
X903912Y1675512D01*
X903704Y1675303D01*
X903412Y1675220D01*
X903121Y1675345D01*
X902912Y1675637D01*
X902829Y1675970D01*
X902912Y1676303D01*
X903121Y1676595D01*
X903412Y1676720D01*
X903704Y1676637D01*
X903912Y1676428D01*
X903996Y1676178D01*
Y1675762D01*
X904121Y1675387D01*
X904371Y1675137D01*
X904662Y1675053D01*
X904954Y1675137D01*
X905162Y1675345D01*
X905287Y1675678D01*
X905329Y1675970D01*
G01X904829Y1678153D02*
X905121Y1678403D01*
X905287Y1678737D01*
X905329Y1679112D01*
X905287Y1679445D01*
X905079Y1679778D01*
X904829Y1679987D01*
X904579Y1680028D01*
X904287Y1679945D01*
X904079Y1679653D01*
X903996Y1679362D01*
Y1678987D01*
G01Y1679362D02*
X903871Y1679612D01*
X903662Y1679820D01*
X903412Y1679903D01*
X903162Y1679820D01*
X902954Y1679612D01*
X902829Y1679237D01*
X902871Y1678862D01*
X903037Y1678487D01*
G01X881000Y1726700D02*
Y1720300D01*
G01D02*
X888000D01*
G01D02*
Y1729000D01*
G01X854905Y1667899D02*
Y1670399D01*
X855905D01*
X856238Y1670274D01*
X856488Y1669982D01*
X856571Y1669649D01*
X856488Y1669316D01*
X856280Y1669066D01*
X855905Y1668941D01*
X854905D01*
G01X858005Y1667899D02*
Y1670399D01*
X859046D01*
X859380Y1670274D01*
X859588Y1670107D01*
X859671Y1669774D01*
X859588Y1669441D01*
X859338Y1669232D01*
X859046Y1669107D01*
X858005D01*
G01X859046D02*
X859671Y1667899D01*
G01X861230Y1668191D02*
X861521Y1667982D01*
X861855Y1667899D01*
X862188Y1667982D01*
X862480Y1668232D01*
X862688Y1668607D01*
X862771Y1668982D01*
Y1669441D01*
X862688Y1669816D01*
X862480Y1670149D01*
X862230Y1670316D01*
X861938Y1670399D01*
X861605Y1670316D01*
X861355Y1670149D01*
X861188Y1669899D01*
X861105Y1669566D01*
X861188Y1669274D01*
X861396Y1668982D01*
X861646Y1668816D01*
X861938Y1668774D01*
X862271Y1668857D01*
X862521Y1669066D01*
X862771Y1669441D01*
G01X865038Y1670399D02*
X864705Y1670316D01*
X864455Y1670107D01*
X864288Y1669857D01*
X864163Y1669524D01*
X864121Y1669149D01*
X864163Y1668774D01*
X864288Y1668441D01*
X864455Y1668191D01*
X864705Y1667982D01*
X865038Y1667899D01*
X865371Y1667982D01*
X865621Y1668191D01*
X865788Y1668441D01*
X865913Y1668774D01*
X865955Y1669149D01*
X865913Y1669524D01*
X865788Y1669857D01*
X865621Y1670107D01*
X865371Y1670316D01*
X865038Y1670399D01*
G01X868138Y1667899D02*
X868430Y1667941D01*
X868763Y1668066D01*
X868971Y1668274D01*
X869055Y1668566D01*
X868971Y1668857D01*
X868721Y1669107D01*
X868346Y1669232D01*
X867930D01*
X867680Y1669316D01*
X867471Y1669524D01*
X867388Y1669816D01*
X867513Y1670107D01*
X867805Y1670316D01*
X868138Y1670399D01*
X868471Y1670316D01*
X868763Y1670107D01*
X868888Y1669816D01*
X868805Y1669524D01*
X868596Y1669316D01*
X868346Y1669232D01*
X867930D01*
X867555Y1669107D01*
X867305Y1668857D01*
X867221Y1668566D01*
X867305Y1668274D01*
X867513Y1668066D01*
X867846Y1667941D01*
X868138Y1667899D01*
G01X870446Y1668941D02*
X870738Y1669232D01*
X870988Y1669399D01*
X871321Y1669482D01*
X871613Y1669399D01*
X871821Y1669232D01*
X871988Y1668982D01*
X872030Y1668691D01*
X871988Y1668441D01*
X871821Y1668191D01*
X871571Y1667982D01*
X871280Y1667899D01*
X870946Y1667982D01*
X870655Y1668232D01*
X870488Y1668607D01*
X870446Y1669024D01*
X870530Y1669566D01*
X870655Y1669857D01*
X870863Y1670149D01*
X871155Y1670357D01*
X871446Y1670399D01*
X871738Y1670316D01*
X871946Y1670107D01*
G01X893153Y1664249D02*
Y1656249D01*
X875553D01*
Y1664249D01*
X893153D01*
G01X898967Y1721400D02*
Y1723900D01*
X899967D01*
X900300Y1723775D01*
X900550Y1723483D01*
X900633Y1723150D01*
X900550Y1722817D01*
X900342Y1722567D01*
X899967Y1722442D01*
X898967D01*
G01X901983Y1723900D02*
Y1722108D01*
X902150Y1721733D01*
X902483Y1721483D01*
X902900Y1721400D01*
X903317Y1721483D01*
X903650Y1721733D01*
X903817Y1722108D01*
Y1723900D01*
G01X905208Y1723483D02*
X905458Y1723733D01*
X905750Y1723858D01*
X906083Y1723900D01*
X906500Y1723817D01*
X906792Y1723608D01*
X906875Y1723358D01*
X906833Y1723108D01*
X906667Y1722900D01*
X905833Y1722483D01*
X905458Y1722192D01*
X905208Y1721775D01*
X905125Y1721400D01*
X906875D01*
G01X884594Y1710984D02*
X881594D01*
G01X896453Y1718906D02*
Y1720906D01*
G01X894484Y1701094D02*
Y1699094D01*
G01X903400Y1714900D02*
Y1719900D01*
X898400D01*
G01X888600D02*
X883600D01*
Y1714900D01*
G01Y1705100D02*
Y1700100D01*
X888600D01*
G01X839800Y1734000D02*
X875200D01*
Y1706000D01*
X839800D01*
Y1734000D01*
G01X854905Y1671899D02*
Y1674399D01*
X855905D01*
X856238Y1674274D01*
X856488Y1673982D01*
X856571Y1673649D01*
X856488Y1673316D01*
X856280Y1673066D01*
X855905Y1672941D01*
X854905D01*
G01X859755Y1674191D02*
X859505Y1674316D01*
X859213Y1674399D01*
X858880D01*
X858505Y1674274D01*
X858213Y1674066D01*
X858005Y1673816D01*
X857838Y1673399D01*
X857796Y1673024D01*
X857880Y1672649D01*
X858005Y1672399D01*
X858255Y1672149D01*
X858546Y1671982D01*
X858838Y1671899D01*
X859130D01*
X859421Y1671982D01*
X859671Y1672107D01*
X859880Y1672274D01*
G01X861938Y1671899D02*
Y1674399D01*
X861438Y1673899D01*
G01Y1671899D02*
X862438D01*
G01X864246Y1673982D02*
X864496Y1674232D01*
X864788Y1674357D01*
X865121Y1674399D01*
X865538Y1674316D01*
X865830Y1674107D01*
X865913Y1673857D01*
X865871Y1673607D01*
X865705Y1673399D01*
X864871Y1672982D01*
X864496Y1672691D01*
X864246Y1672274D01*
X864163Y1671899D01*
X865913D01*
G01X868055D02*
X868138Y1672441D01*
X868263Y1672899D01*
X868430Y1673316D01*
X868638Y1673774D01*
X868971Y1674399D01*
X867305D01*
G01X870446Y1672941D02*
X870738Y1673232D01*
X870988Y1673399D01*
X871321Y1673482D01*
X871613Y1673399D01*
X871821Y1673232D01*
X871988Y1672982D01*
X872030Y1672691D01*
X871988Y1672441D01*
X871821Y1672191D01*
X871571Y1671982D01*
X871280Y1671899D01*
X870946Y1671982D01*
X870655Y1672232D01*
X870488Y1672607D01*
X870446Y1673024D01*
X870530Y1673566D01*
X870655Y1673857D01*
X870863Y1674149D01*
X871155Y1674357D01*
X871446Y1674399D01*
X871738Y1674316D01*
X871946Y1674107D01*
G01X874993Y1676187D02*
X893693D01*
Y1665887D01*
X874993D01*
Y1676187D01*
G01X854905Y1675899D02*
Y1678399D01*
X855905D01*
X856238Y1678274D01*
X856488Y1677982D01*
X856571Y1677649D01*
X856488Y1677316D01*
X856280Y1677066D01*
X855905Y1676941D01*
X854905D01*
G01X859755Y1678191D02*
X859505Y1678316D01*
X859213Y1678399D01*
X858880D01*
X858505Y1678274D01*
X858213Y1678066D01*
X858005Y1677816D01*
X857838Y1677399D01*
X857796Y1677024D01*
X857880Y1676649D01*
X858005Y1676399D01*
X858255Y1676149D01*
X858546Y1675982D01*
X858838Y1675899D01*
X859130D01*
X859421Y1675982D01*
X859671Y1676107D01*
X859880Y1676274D01*
G01X861938Y1675899D02*
Y1678399D01*
X861438Y1677899D01*
G01Y1675899D02*
X862438D01*
G01X864246Y1677982D02*
X864496Y1678232D01*
X864788Y1678357D01*
X865121Y1678399D01*
X865538Y1678316D01*
X865830Y1678107D01*
X865913Y1677857D01*
X865871Y1677607D01*
X865705Y1677399D01*
X864871Y1676982D01*
X864496Y1676691D01*
X864246Y1676274D01*
X864163Y1675899D01*
X865913D01*
G01X868138D02*
X868430Y1675941D01*
X868763Y1676066D01*
X868971Y1676274D01*
X869055Y1676566D01*
X868971Y1676857D01*
X868721Y1677107D01*
X868346Y1677232D01*
X867930D01*
X867680Y1677316D01*
X867471Y1677524D01*
X867388Y1677816D01*
X867513Y1678107D01*
X867805Y1678316D01*
X868138Y1678399D01*
X868471Y1678316D01*
X868763Y1678107D01*
X868888Y1677816D01*
X868805Y1677524D01*
X868596Y1677316D01*
X868346Y1677232D01*
X867930D01*
X867555Y1677107D01*
X867305Y1676857D01*
X867221Y1676566D01*
X867305Y1676274D01*
X867513Y1676066D01*
X867846Y1675941D01*
X868138Y1675899D01*
G01X871738D02*
Y1678399D01*
X870196Y1676607D01*
X872280D01*
G01X874993Y1688650D02*
X893693D01*
Y1678350D01*
X874993D01*
Y1688650D01*
G01X902367Y1790367D02*
Y1792867D01*
X903367D01*
X903700Y1792742D01*
X903950Y1792450D01*
X904033Y1792117D01*
X903950Y1791784D01*
X903742Y1791534D01*
X903367Y1791409D01*
X902367D01*
G01X907133Y1790367D02*
X905467D01*
Y1792867D01*
X907133D01*
G01X906467Y1791659D02*
X905467D01*
G01X909733Y1791700D02*
X909900Y1791825D01*
X910025Y1792034D01*
X910108Y1792325D01*
X910025Y1792575D01*
X909858Y1792742D01*
X909567Y1792867D01*
X908442D01*
Y1790367D01*
X909817D01*
X910108Y1790534D01*
X910275Y1790784D01*
X910358Y1791075D01*
X910275Y1791367D01*
X910025Y1791617D01*
X909733Y1791700D01*
X908442D01*
G01X914558Y1790367D02*
X915600Y1792867D01*
X916642Y1790367D01*
G01X916267Y1791242D02*
X914933D01*
G01X918700Y1792867D02*
Y1790367D01*
G01X917742Y1792867D02*
X919658D01*
G01X921800D02*
Y1790367D01*
G01X920842Y1792867D02*
X922758D01*
G01X923942Y1790367D02*
Y1792867D01*
X925858Y1790367D01*
Y1792867D01*
G01X928000D02*
X927667Y1792784D01*
X927417Y1792575D01*
X927250Y1792325D01*
X927125Y1791992D01*
X927083Y1791617D01*
X927125Y1791242D01*
X927250Y1790909D01*
X927417Y1790659D01*
X927667Y1790450D01*
X928000Y1790367D01*
X928333Y1790450D01*
X928583Y1790659D01*
X928750Y1790909D01*
X928875Y1791242D01*
X928917Y1791617D01*
X928875Y1791992D01*
X928750Y1792325D01*
X928583Y1792575D01*
X928333Y1792784D01*
X928000Y1792867D01*
G01X899760Y1778776D02*
Y1776276D01*
X901426D01*
G01X904526D02*
X902860D01*
Y1778776D01*
X904526D01*
G01X903860Y1777568D02*
X902860D01*
G01X905876Y1776276D02*
Y1778776D01*
X906710D01*
X907043Y1778651D01*
X907293Y1778484D01*
X907501Y1778234D01*
X907668Y1777943D01*
X907710Y1777526D01*
X907668Y1777109D01*
X907501Y1776818D01*
X907293Y1776568D01*
X907043Y1776401D01*
X906710Y1776276D01*
X905876D01*
G01X909893D02*
Y1778776D01*
X909393Y1778276D01*
G01Y1776276D02*
X910393D01*
G01X912993Y1778776D02*
X912660Y1778693D01*
X912410Y1778484D01*
X912243Y1778234D01*
X912118Y1777901D01*
X912076Y1777526D01*
X912118Y1777151D01*
X912243Y1776818D01*
X912410Y1776568D01*
X912660Y1776359D01*
X912993Y1776276D01*
X913326Y1776359D01*
X913576Y1776568D01*
X913743Y1776818D01*
X913868Y1777151D01*
X913910Y1777526D01*
X913868Y1777901D01*
X913743Y1778234D01*
X913576Y1778484D01*
X913326Y1778693D01*
X912993Y1778776D01*
G01X916093D02*
X915760Y1778693D01*
X915510Y1778484D01*
X915343Y1778234D01*
X915218Y1777901D01*
X915176Y1777526D01*
X915218Y1777151D01*
X915343Y1776818D01*
X915510Y1776568D01*
X915760Y1776359D01*
X916093Y1776276D01*
X916426Y1776359D01*
X916676Y1776568D01*
X916843Y1776818D01*
X916968Y1777151D01*
X917010Y1777526D01*
X916968Y1777901D01*
X916843Y1778234D01*
X916676Y1778484D01*
X916426Y1778693D01*
X916093Y1778776D01*
G01X893906Y1780058D02*
Y1787658D01*
X905306D01*
Y1780058D01*
X893906D01*
G01X899217Y1752892D02*
X898967Y1753017D01*
X898675Y1753100D01*
X898342D01*
X897967Y1752975D01*
X897675Y1752767D01*
X897467Y1752517D01*
X897300Y1752100D01*
X897258Y1751725D01*
X897342Y1751350D01*
X897467Y1751100D01*
X897717Y1750850D01*
X898008Y1750683D01*
X898300Y1750600D01*
X898592D01*
X898883Y1750683D01*
X899133Y1750808D01*
X899342Y1750975D01*
G01X900692Y1750892D02*
X900983Y1750683D01*
X901317Y1750600D01*
X901650Y1750683D01*
X901942Y1750933D01*
X902150Y1751308D01*
X902233Y1751683D01*
Y1752142D01*
X902150Y1752517D01*
X901942Y1752850D01*
X901692Y1753017D01*
X901400Y1753100D01*
X901067Y1753017D01*
X900817Y1752850D01*
X900650Y1752600D01*
X900567Y1752267D01*
X900650Y1751975D01*
X900858Y1751683D01*
X901108Y1751517D01*
X901400Y1751475D01*
X901733Y1751558D01*
X901983Y1751767D01*
X902233Y1752142D01*
G01X903583Y1750975D02*
X903833Y1750767D01*
X904125Y1750642D01*
X904500Y1750600D01*
X904875Y1750683D01*
X905167Y1750850D01*
X905375Y1751142D01*
X905417Y1751475D01*
X905333Y1751808D01*
X905125Y1752017D01*
X904833Y1752183D01*
X904542Y1752225D01*
X904250Y1752183D01*
X903875Y1752017D01*
X904000Y1753100D01*
X905125D01*
G01X907600Y1750600D02*
Y1753100D01*
X907100Y1752600D01*
G01Y1750600D02*
X908100D01*
G01X910700D02*
X910992Y1750642D01*
X911325Y1750767D01*
X911533Y1750975D01*
X911617Y1751267D01*
X911533Y1751558D01*
X911283Y1751808D01*
X910908Y1751933D01*
X910492D01*
X910242Y1752017D01*
X910033Y1752225D01*
X909950Y1752517D01*
X910075Y1752808D01*
X910367Y1753017D01*
X910700Y1753100D01*
X911033Y1753017D01*
X911325Y1752808D01*
X911450Y1752517D01*
X911367Y1752225D01*
X911158Y1752017D01*
X910908Y1751933D01*
X910492D01*
X910117Y1751808D01*
X909867Y1751558D01*
X909783Y1751267D01*
X909867Y1750975D01*
X910075Y1750767D01*
X910408Y1750642D01*
X910700Y1750600D01*
G01X851500Y1740600D02*
X851167Y1740642D01*
X850875Y1740808D01*
X850625Y1741058D01*
X850458Y1741350D01*
X850375Y1741683D01*
Y1742017D01*
X850458Y1742350D01*
X850625Y1742642D01*
X850875Y1742892D01*
X851167Y1743058D01*
X851500Y1743100D01*
X851833Y1743058D01*
X852125Y1742892D01*
X852375Y1742642D01*
X852542Y1742350D01*
X852625Y1742017D01*
Y1741683D01*
X852542Y1741350D01*
X852375Y1741058D01*
X852125Y1740808D01*
X851833Y1740642D01*
X851500Y1740600D01*
G01X851833Y1741267D02*
X852333Y1740600D01*
G01X853808Y1742683D02*
X854058Y1742933D01*
X854350Y1743058D01*
X854683Y1743100D01*
X855100Y1743017D01*
X855392Y1742808D01*
X855475Y1742558D01*
X855433Y1742308D01*
X855267Y1742100D01*
X854433Y1741683D01*
X854058Y1741392D01*
X853808Y1740975D01*
X853725Y1740600D01*
X855475D01*
G01X857700D02*
X857992Y1740642D01*
X858325Y1740767D01*
X858533Y1740975D01*
X858617Y1741267D01*
X858533Y1741558D01*
X858283Y1741808D01*
X857908Y1741933D01*
X857492D01*
X857242Y1742017D01*
X857033Y1742225D01*
X856950Y1742517D01*
X857075Y1742808D01*
X857367Y1743017D01*
X857700Y1743100D01*
X858033Y1743017D01*
X858325Y1742808D01*
X858450Y1742517D01*
X858367Y1742225D01*
X858158Y1742017D01*
X857908Y1741933D01*
X857492D01*
X857117Y1741808D01*
X856867Y1741558D01*
X856783Y1741267D01*
X856867Y1740975D01*
X857075Y1740767D01*
X857408Y1740642D01*
X857700Y1740600D01*
G01X862500Y1767000D02*
Y1753000D01*
G01X875500Y1767000D02*
X862500D01*
G01X875500Y1753000D02*
Y1767000D01*
G01X862500Y1753000D02*
X875500D01*
G01X857300Y1745800D02*
X857258Y1745467D01*
X857092Y1745175D01*
X856842Y1744925D01*
X856550Y1744758D01*
X856217Y1744675D01*
X855883D01*
X855550Y1744758D01*
X855258Y1744925D01*
X855008Y1745175D01*
X854842Y1745467D01*
X854800Y1745800D01*
X854842Y1746133D01*
X855008Y1746425D01*
X855258Y1746675D01*
X855550Y1746842D01*
X855883Y1746925D01*
X856217D01*
X856550Y1746842D01*
X856842Y1746675D01*
X857092Y1746425D01*
X857258Y1746133D01*
X857300Y1745800D01*
G01X856633Y1746133D02*
X857300Y1746633D01*
G01X856800Y1747983D02*
X857092Y1748233D01*
X857258Y1748567D01*
X857300Y1748942D01*
X857258Y1749275D01*
X857050Y1749608D01*
X856800Y1749817D01*
X856550Y1749858D01*
X856258Y1749775D01*
X856050Y1749483D01*
X855967Y1749192D01*
Y1748817D01*
G01Y1749192D02*
X855842Y1749442D01*
X855633Y1749650D01*
X855383Y1749733D01*
X855133Y1749650D01*
X854925Y1749442D01*
X854800Y1749067D01*
X854842Y1748692D01*
X855008Y1748317D01*
G01X854800Y1752000D02*
X854883Y1751667D01*
X855092Y1751417D01*
X855342Y1751250D01*
X855675Y1751125D01*
X856050Y1751083D01*
X856425Y1751125D01*
X856758Y1751250D01*
X857008Y1751417D01*
X857217Y1751667D01*
X857300Y1752000D01*
X857217Y1752333D01*
X857008Y1752583D01*
X856758Y1752750D01*
X856425Y1752875D01*
X856050Y1752917D01*
X855675Y1752875D01*
X855342Y1752750D01*
X855092Y1752583D01*
X854883Y1752333D01*
X854800Y1752000D01*
G01X868000Y1783000D02*
Y1769000D01*
G01X881000Y1783000D02*
X868000D01*
G01X881000Y1769000D02*
Y1783000D01*
G01X868000Y1769000D02*
X881000D01*
G01X859567Y1743700D02*
Y1746200D01*
X860608D01*
X860942Y1746075D01*
X861150Y1745908D01*
X861233Y1745575D01*
X861150Y1745242D01*
X860900Y1745033D01*
X860608Y1744908D01*
X859567D01*
G01X860608D02*
X861233Y1743700D01*
G01X862792Y1743992D02*
X863083Y1743783D01*
X863417Y1743700D01*
X863750Y1743783D01*
X864042Y1744033D01*
X864250Y1744408D01*
X864333Y1744783D01*
Y1745242D01*
X864250Y1745617D01*
X864042Y1745950D01*
X863792Y1746117D01*
X863500Y1746200D01*
X863167Y1746117D01*
X862917Y1745950D01*
X862750Y1745700D01*
X862667Y1745367D01*
X862750Y1745075D01*
X862958Y1744783D01*
X863208Y1744617D01*
X863500Y1744575D01*
X863833Y1744658D01*
X864083Y1744867D01*
X864333Y1745242D01*
G01X866517Y1743700D02*
X866600Y1744242D01*
X866725Y1744700D01*
X866892Y1745117D01*
X867100Y1745575D01*
X867433Y1746200D01*
X865767D01*
G01X869700Y1743700D02*
X869992Y1743742D01*
X870325Y1743867D01*
X870533Y1744075D01*
X870617Y1744367D01*
X870533Y1744658D01*
X870283Y1744908D01*
X869908Y1745033D01*
X869492D01*
X869242Y1745117D01*
X869033Y1745325D01*
X868950Y1745617D01*
X869075Y1745908D01*
X869367Y1746117D01*
X869700Y1746200D01*
X870033Y1746117D01*
X870325Y1745908D01*
X870450Y1745617D01*
X870367Y1745325D01*
X870158Y1745117D01*
X869908Y1745033D01*
X869492D01*
X869117Y1744908D01*
X868867Y1744658D01*
X868783Y1744367D01*
X868867Y1744075D01*
X869075Y1743867D01*
X869408Y1743742D01*
X869700Y1743700D01*
G01X872008Y1745783D02*
X872258Y1746033D01*
X872550Y1746158D01*
X872883Y1746200D01*
X873300Y1746117D01*
X873592Y1745908D01*
X873675Y1745658D01*
X873633Y1745408D01*
X873467Y1745200D01*
X872633Y1744783D01*
X872258Y1744492D01*
X872008Y1744075D01*
X871925Y1743700D01*
X873675D01*
G01X882550Y1775250D02*
Y1771250D01*
X889950D01*
G01X911700Y1766500D02*
Y1770500D01*
X904300D01*
G01X853167Y1744675D02*
X853375Y1745008D01*
X853500Y1745383D01*
Y1745717D01*
X853375Y1746050D01*
X853167Y1746300D01*
X852875Y1746425D01*
X852583Y1746342D01*
X852333Y1746133D01*
X852167Y1745758D01*
X852083Y1745258D01*
X851917Y1744967D01*
X851625Y1744842D01*
X851333Y1744925D01*
X851125Y1745133D01*
X851000Y1745425D01*
Y1745717D01*
X851083Y1746008D01*
X851292Y1746258D01*
G01X853500Y1747817D02*
X851000D01*
Y1748858D01*
X851125Y1749192D01*
X851292Y1749400D01*
X851625Y1749483D01*
X851958Y1749400D01*
X852167Y1749150D01*
X852292Y1748858D01*
Y1747817D01*
G01Y1748858D02*
X853500Y1749483D01*
G01Y1751750D02*
X851000D01*
X851500Y1751250D01*
G01X853500D02*
Y1752250D01*
G01Y1754850D02*
X851000D01*
X851500Y1754350D01*
G01X853500D02*
Y1755350D01*
G01X851417Y1757158D02*
X851167Y1757408D01*
X851042Y1757700D01*
X851000Y1758033D01*
X851083Y1758450D01*
X851292Y1758742D01*
X851542Y1758825D01*
X851792Y1758783D01*
X852000Y1758617D01*
X852417Y1757783D01*
X852708Y1757408D01*
X853125Y1757158D01*
X853500Y1757075D01*
Y1758825D01*
G01Y1761050D02*
X851000D01*
X851500Y1760550D01*
G01X853500D02*
Y1761550D01*
G01X859800Y1772000D02*
Y1768000D01*
X867200D01*
G01X896800Y1767300D02*
X900800D01*
Y1774700D01*
G01X909900Y1735467D02*
X907400D01*
Y1736508D01*
X907525Y1736842D01*
X907692Y1737050D01*
X908025Y1737133D01*
X908358Y1737050D01*
X908567Y1736800D01*
X908692Y1736508D01*
Y1735467D01*
G01Y1736508D02*
X909900Y1737133D01*
G01X909608Y1738692D02*
X909817Y1738983D01*
X909900Y1739317D01*
X909817Y1739650D01*
X909567Y1739942D01*
X909192Y1740150D01*
X908817Y1740233D01*
X908358D01*
X907983Y1740150D01*
X907650Y1739942D01*
X907483Y1739692D01*
X907400Y1739400D01*
X907483Y1739067D01*
X907650Y1738817D01*
X907900Y1738650D01*
X908233Y1738567D01*
X908525Y1738650D01*
X908817Y1738858D01*
X908983Y1739108D01*
X909025Y1739400D01*
X908942Y1739733D01*
X908733Y1739983D01*
X908358Y1740233D01*
G01X909900Y1742500D02*
X909858Y1742792D01*
X909733Y1743125D01*
X909525Y1743333D01*
X909233Y1743417D01*
X908942Y1743333D01*
X908692Y1743083D01*
X908567Y1742708D01*
Y1742292D01*
X908483Y1742042D01*
X908275Y1741833D01*
X907983Y1741750D01*
X907692Y1741875D01*
X907483Y1742167D01*
X907400Y1742500D01*
X907483Y1742833D01*
X907692Y1743125D01*
X907983Y1743250D01*
X908275Y1743167D01*
X908483Y1742958D01*
X908567Y1742708D01*
Y1742292D01*
X908692Y1741917D01*
X908942Y1741667D01*
X909233Y1741583D01*
X909525Y1741667D01*
X909733Y1741875D01*
X909858Y1742208D01*
X909900Y1742500D01*
G01X909608Y1744892D02*
X909817Y1745183D01*
X909900Y1745517D01*
X909817Y1745850D01*
X909567Y1746142D01*
X909192Y1746350D01*
X908817Y1746433D01*
X908358D01*
X907983Y1746350D01*
X907650Y1746142D01*
X907483Y1745892D01*
X907400Y1745600D01*
X907483Y1745267D01*
X907650Y1745017D01*
X907900Y1744850D01*
X908233Y1744767D01*
X908525Y1744850D01*
X908817Y1745058D01*
X908983Y1745308D01*
X909025Y1745600D01*
X908942Y1745933D01*
X908733Y1746183D01*
X908358Y1746433D01*
G01X909900Y1748700D02*
X907400D01*
X907900Y1748200D01*
G01X909900D02*
Y1749200D01*
G01X904500Y1725300D02*
X908500D01*
Y1732700D01*
G01X906300Y1735267D02*
X903800D01*
Y1736308D01*
X903925Y1736642D01*
X904092Y1736850D01*
X904425Y1736933D01*
X904758Y1736850D01*
X904967Y1736600D01*
X905092Y1736308D01*
Y1735267D01*
G01Y1736308D02*
X906300Y1736933D01*
G01X906008Y1738492D02*
X906217Y1738783D01*
X906300Y1739117D01*
X906217Y1739450D01*
X905967Y1739742D01*
X905592Y1739950D01*
X905217Y1740033D01*
X904758D01*
X904383Y1739950D01*
X904050Y1739742D01*
X903883Y1739492D01*
X903800Y1739200D01*
X903883Y1738867D01*
X904050Y1738617D01*
X904300Y1738450D01*
X904633Y1738367D01*
X904925Y1738450D01*
X905217Y1738658D01*
X905383Y1738908D01*
X905425Y1739200D01*
X905342Y1739533D01*
X905133Y1739783D01*
X904758Y1740033D01*
G01X904217Y1741508D02*
X903967Y1741758D01*
X903842Y1742050D01*
X903800Y1742383D01*
X903883Y1742800D01*
X904092Y1743092D01*
X904342Y1743175D01*
X904592Y1743133D01*
X904800Y1742967D01*
X905217Y1742133D01*
X905508Y1741758D01*
X905925Y1741508D01*
X906300Y1741425D01*
Y1743175D01*
G01X905800Y1744483D02*
X906092Y1744733D01*
X906258Y1745067D01*
X906300Y1745442D01*
X906258Y1745775D01*
X906050Y1746108D01*
X905800Y1746317D01*
X905550Y1746358D01*
X905258Y1746275D01*
X905050Y1745983D01*
X904967Y1745692D01*
Y1745317D01*
G01Y1745692D02*
X904842Y1745942D01*
X904633Y1746150D01*
X904383Y1746233D01*
X904133Y1746150D01*
X903925Y1745942D01*
X903800Y1745567D01*
X903842Y1745192D01*
X904008Y1744817D01*
G01X906300Y1749000D02*
X903800D01*
X905592Y1747458D01*
Y1749542D01*
G01X904500Y1732700D02*
X900500D01*
Y1725300D01*
G01X902500Y1736017D02*
X900000D01*
Y1737017D01*
X900125Y1737350D01*
X900417Y1737600D01*
X900750Y1737683D01*
X901083Y1737600D01*
X901333Y1737392D01*
X901458Y1737017D01*
Y1736017D01*
G01X902500Y1739117D02*
X900000D01*
Y1740158D01*
X900125Y1740492D01*
X900292Y1740700D01*
X900625Y1740783D01*
X900958Y1740700D01*
X901167Y1740450D01*
X901292Y1740158D01*
Y1739117D01*
G01Y1740158D02*
X902500Y1740783D01*
G01X902208Y1742342D02*
X902417Y1742633D01*
X902500Y1742967D01*
X902417Y1743300D01*
X902167Y1743592D01*
X901792Y1743800D01*
X901417Y1743883D01*
X900958D01*
X900583Y1743800D01*
X900250Y1743592D01*
X900083Y1743342D01*
X900000Y1743050D01*
X900083Y1742717D01*
X900250Y1742467D01*
X900500Y1742300D01*
X900833Y1742217D01*
X901125Y1742300D01*
X901417Y1742508D01*
X901583Y1742758D01*
X901625Y1743050D01*
X901542Y1743383D01*
X901333Y1743633D01*
X900958Y1743883D01*
G01X901458Y1745358D02*
X901167Y1745650D01*
X901000Y1745900D01*
X900917Y1746233D01*
X901000Y1746525D01*
X901167Y1746733D01*
X901417Y1746900D01*
X901708Y1746942D01*
X901958Y1746900D01*
X902208Y1746733D01*
X902417Y1746483D01*
X902500Y1746192D01*
X902417Y1745858D01*
X902167Y1745567D01*
X901792Y1745400D01*
X901375Y1745358D01*
X900833Y1745442D01*
X900542Y1745567D01*
X900250Y1745775D01*
X900042Y1746067D01*
X900000Y1746358D01*
X900083Y1746650D01*
X900292Y1746858D01*
G01X900500Y1732700D02*
X896500D01*
Y1725300D01*
G01X891500Y1733517D02*
X889000D01*
Y1734517D01*
X889125Y1734850D01*
X889417Y1735100D01*
X889750Y1735183D01*
X890083Y1735100D01*
X890333Y1734892D01*
X890458Y1734517D01*
Y1733517D01*
G01X891500Y1736617D02*
X889000D01*
Y1737658D01*
X889125Y1737992D01*
X889292Y1738200D01*
X889625Y1738283D01*
X889958Y1738200D01*
X890167Y1737950D01*
X890292Y1737658D01*
Y1736617D01*
G01Y1737658D02*
X891500Y1738283D01*
G01X891208Y1739842D02*
X891417Y1740133D01*
X891500Y1740467D01*
X891417Y1740800D01*
X891167Y1741092D01*
X890792Y1741300D01*
X890417Y1741383D01*
X889958D01*
X889583Y1741300D01*
X889250Y1741092D01*
X889083Y1740842D01*
X889000Y1740550D01*
X889083Y1740217D01*
X889250Y1739967D01*
X889500Y1739800D01*
X889833Y1739717D01*
X890125Y1739800D01*
X890417Y1740008D01*
X890583Y1740258D01*
X890625Y1740550D01*
X890542Y1740883D01*
X890333Y1741133D01*
X889958Y1741383D01*
G01X891500Y1743567D02*
X890958Y1743650D01*
X890500Y1743775D01*
X890083Y1743942D01*
X889625Y1744150D01*
X889000Y1744483D01*
Y1742817D01*
G01X888500Y1725300D02*
X892500D01*
Y1732700D01*
G01X851339Y1790207D02*
X848839D01*
Y1791248D01*
X848964Y1791582D01*
X849131Y1791790D01*
X849464Y1791873D01*
X849797Y1791790D01*
X850006Y1791540D01*
X850131Y1791248D01*
Y1790207D01*
G01Y1791248D02*
X851339Y1791873D01*
G01X850839Y1793223D02*
X851131Y1793473D01*
X851297Y1793807D01*
X851339Y1794182D01*
X851297Y1794515D01*
X851089Y1794848D01*
X850839Y1795057D01*
X850589Y1795098D01*
X850297Y1795015D01*
X850089Y1794723D01*
X850006Y1794432D01*
Y1794057D01*
G01Y1794432D02*
X849881Y1794682D01*
X849672Y1794890D01*
X849422Y1794973D01*
X849172Y1794890D01*
X848964Y1794682D01*
X848839Y1794307D01*
X848881Y1793932D01*
X849047Y1793557D01*
G01X851339Y1797240D02*
X848839D01*
X849339Y1796740D01*
G01X851339D02*
Y1797740D01*
G01X850964Y1799423D02*
X851172Y1799673D01*
X851297Y1799965D01*
X851339Y1800340D01*
X851256Y1800715D01*
X851089Y1801007D01*
X850797Y1801215D01*
X850464Y1801257D01*
X850131Y1801173D01*
X849922Y1800965D01*
X849756Y1800673D01*
X849714Y1800382D01*
X849756Y1800090D01*
X849922Y1799715D01*
X848839Y1799840D01*
Y1800965D01*
G01X839500Y1786300D02*
X843500D01*
Y1793700D01*
G01X847339Y1790207D02*
X844839D01*
Y1791248D01*
X844964Y1791582D01*
X845131Y1791790D01*
X845464Y1791873D01*
X845797Y1791790D01*
X846006Y1791540D01*
X846131Y1791248D01*
Y1790207D01*
G01Y1791248D02*
X847339Y1791873D01*
G01X846839Y1793223D02*
X847131Y1793473D01*
X847297Y1793807D01*
X847339Y1794182D01*
X847297Y1794515D01*
X847089Y1794848D01*
X846839Y1795057D01*
X846589Y1795098D01*
X846297Y1795015D01*
X846089Y1794723D01*
X846006Y1794432D01*
Y1794057D01*
G01Y1794432D02*
X845881Y1794682D01*
X845672Y1794890D01*
X845422Y1794973D01*
X845172Y1794890D01*
X844964Y1794682D01*
X844839Y1794307D01*
X844881Y1793932D01*
X845047Y1793557D01*
G01X845256Y1796448D02*
X845006Y1796698D01*
X844881Y1796990D01*
X844839Y1797323D01*
X844922Y1797740D01*
X845131Y1798032D01*
X845381Y1798115D01*
X845631Y1798073D01*
X845839Y1797907D01*
X846256Y1797073D01*
X846547Y1796698D01*
X846964Y1796448D01*
X847339Y1796365D01*
Y1798115D01*
G01X846839Y1799423D02*
X847131Y1799673D01*
X847297Y1800007D01*
X847339Y1800382D01*
X847297Y1800715D01*
X847089Y1801048D01*
X846839Y1801257D01*
X846589Y1801298D01*
X846297Y1801215D01*
X846089Y1800923D01*
X846006Y1800632D01*
Y1800257D01*
G01Y1800632D02*
X845881Y1800882D01*
X845672Y1801090D01*
X845422Y1801173D01*
X845172Y1801090D01*
X844964Y1800882D01*
X844839Y1800507D01*
X844881Y1800132D01*
X845047Y1799757D01*
G01X912500Y1733200D02*
X908500D01*
Y1725800D01*
G01X859567Y1747400D02*
Y1749900D01*
X860608D01*
X860942Y1749775D01*
X861150Y1749608D01*
X861233Y1749275D01*
X861150Y1748942D01*
X860900Y1748733D01*
X860608Y1748608D01*
X859567D01*
G01X860608D02*
X861233Y1747400D01*
G01X862792Y1747692D02*
X863083Y1747483D01*
X863417Y1747400D01*
X863750Y1747483D01*
X864042Y1747733D01*
X864250Y1748108D01*
X864333Y1748483D01*
Y1748942D01*
X864250Y1749317D01*
X864042Y1749650D01*
X863792Y1749817D01*
X863500Y1749900D01*
X863167Y1749817D01*
X862917Y1749650D01*
X862750Y1749400D01*
X862667Y1749067D01*
X862750Y1748775D01*
X862958Y1748483D01*
X863208Y1748317D01*
X863500Y1748275D01*
X863833Y1748358D01*
X864083Y1748567D01*
X864333Y1748942D01*
G01X865892Y1747692D02*
X866183Y1747483D01*
X866517Y1747400D01*
X866850Y1747483D01*
X867142Y1747733D01*
X867350Y1748108D01*
X867433Y1748483D01*
Y1748942D01*
X867350Y1749317D01*
X867142Y1749650D01*
X866892Y1749817D01*
X866600Y1749900D01*
X866267Y1749817D01*
X866017Y1749650D01*
X865850Y1749400D01*
X865767Y1749067D01*
X865850Y1748775D01*
X866058Y1748483D01*
X866308Y1748317D01*
X866600Y1748275D01*
X866933Y1748358D01*
X867183Y1748567D01*
X867433Y1748942D01*
G01X869700Y1747400D02*
Y1749900D01*
X869200Y1749400D01*
G01Y1747400D02*
X870200D01*
G01X872008Y1749483D02*
X872258Y1749733D01*
X872550Y1749858D01*
X872883Y1749900D01*
X873300Y1749817D01*
X873592Y1749608D01*
X873675Y1749358D01*
X873633Y1749108D01*
X873467Y1748900D01*
X872633Y1748483D01*
X872258Y1748192D01*
X872008Y1747775D01*
X871925Y1747400D01*
X873675D01*
G01X882550Y1779250D02*
Y1775250D01*
X889950D01*
G01X877267Y1787467D02*
Y1789967D01*
X878308D01*
X878642Y1789842D01*
X878850Y1789675D01*
X878933Y1789342D01*
X878850Y1789009D01*
X878600Y1788800D01*
X878308Y1788675D01*
X877267D01*
G01X878308D02*
X878933Y1787467D01*
G01X880492Y1787759D02*
X880783Y1787550D01*
X881117Y1787467D01*
X881450Y1787550D01*
X881742Y1787800D01*
X881950Y1788175D01*
X882033Y1788550D01*
Y1789009D01*
X881950Y1789384D01*
X881742Y1789717D01*
X881492Y1789884D01*
X881200Y1789967D01*
X880867Y1789884D01*
X880617Y1789717D01*
X880450Y1789467D01*
X880367Y1789134D01*
X880450Y1788842D01*
X880658Y1788550D01*
X880908Y1788384D01*
X881200Y1788342D01*
X881533Y1788425D01*
X881783Y1788634D01*
X882033Y1789009D01*
G01X883592Y1787759D02*
X883883Y1787550D01*
X884217Y1787467D01*
X884550Y1787550D01*
X884842Y1787800D01*
X885050Y1788175D01*
X885133Y1788550D01*
Y1789009D01*
X885050Y1789384D01*
X884842Y1789717D01*
X884592Y1789884D01*
X884300Y1789967D01*
X883967Y1789884D01*
X883717Y1789717D01*
X883550Y1789467D01*
X883467Y1789134D01*
X883550Y1788842D01*
X883758Y1788550D01*
X884008Y1788384D01*
X884300Y1788342D01*
X884633Y1788425D01*
X884883Y1788634D01*
X885133Y1789009D01*
G01X886608Y1789550D02*
X886858Y1789800D01*
X887150Y1789925D01*
X887483Y1789967D01*
X887900Y1789884D01*
X888192Y1789675D01*
X888275Y1789425D01*
X888233Y1789175D01*
X888067Y1788967D01*
X887233Y1788550D01*
X886858Y1788259D01*
X886608Y1787842D01*
X886525Y1787467D01*
X888275D01*
G01X890500D02*
X890792Y1787509D01*
X891125Y1787634D01*
X891333Y1787842D01*
X891417Y1788134D01*
X891333Y1788425D01*
X891083Y1788675D01*
X890708Y1788800D01*
X890292D01*
X890042Y1788884D01*
X889833Y1789092D01*
X889750Y1789384D01*
X889875Y1789675D01*
X890167Y1789884D01*
X890500Y1789967D01*
X890833Y1789884D01*
X891125Y1789675D01*
X891250Y1789384D01*
X891167Y1789092D01*
X890958Y1788884D01*
X890708Y1788800D01*
X890292D01*
X889917Y1788675D01*
X889667Y1788425D01*
X889583Y1788134D01*
X889667Y1787842D01*
X889875Y1787634D01*
X890208Y1787509D01*
X890500Y1787467D01*
G01X891700Y1778900D02*
Y1774900D01*
X899100D01*
G01X910267Y1794267D02*
Y1796767D01*
X911308D01*
X911642Y1796642D01*
X911850Y1796475D01*
X911933Y1796142D01*
X911850Y1795809D01*
X911600Y1795600D01*
X911308Y1795475D01*
X910267D01*
G01X911308D02*
X911933Y1794267D01*
G01X913492Y1794559D02*
X913783Y1794350D01*
X914117Y1794267D01*
X914450Y1794350D01*
X914742Y1794600D01*
X914950Y1794975D01*
X915033Y1795350D01*
Y1795809D01*
X914950Y1796184D01*
X914742Y1796517D01*
X914492Y1796684D01*
X914200Y1796767D01*
X913867Y1796684D01*
X913617Y1796517D01*
X913450Y1796267D01*
X913367Y1795934D01*
X913450Y1795642D01*
X913658Y1795350D01*
X913908Y1795184D01*
X914200Y1795142D01*
X914533Y1795225D01*
X914783Y1795434D01*
X915033Y1795809D01*
G01X916592Y1794559D02*
X916883Y1794350D01*
X917217Y1794267D01*
X917550Y1794350D01*
X917842Y1794600D01*
X918050Y1794975D01*
X918133Y1795350D01*
Y1795809D01*
X918050Y1796184D01*
X917842Y1796517D01*
X917592Y1796684D01*
X917300Y1796767D01*
X916967Y1796684D01*
X916717Y1796517D01*
X916550Y1796267D01*
X916467Y1795934D01*
X916550Y1795642D01*
X916758Y1795350D01*
X917008Y1795184D01*
X917300Y1795142D01*
X917633Y1795225D01*
X917883Y1795434D01*
X918133Y1795809D01*
G01X919608Y1796350D02*
X919858Y1796600D01*
X920150Y1796725D01*
X920483Y1796767D01*
X920900Y1796684D01*
X921192Y1796475D01*
X921275Y1796225D01*
X921233Y1795975D01*
X921067Y1795767D01*
X920233Y1795350D01*
X919858Y1795059D01*
X919608Y1794642D01*
X919525Y1794267D01*
X921275D01*
G01X923417D02*
X923500Y1794809D01*
X923625Y1795267D01*
X923792Y1795684D01*
X924000Y1796142D01*
X924333Y1796767D01*
X922667D01*
G01X900892Y1788816D02*
Y1792816D01*
X893492D01*
G01X886540Y1735157D02*
X884040D01*
Y1736157D01*
X884165Y1736490D01*
X884457Y1736740D01*
X884790Y1736823D01*
X885123Y1736740D01*
X885373Y1736532D01*
X885498Y1736157D01*
Y1735157D01*
G01X886540Y1738257D02*
X884040D01*
Y1739298D01*
X884165Y1739632D01*
X884332Y1739840D01*
X884665Y1739923D01*
X884998Y1739840D01*
X885207Y1739590D01*
X885332Y1739298D01*
Y1738257D01*
G01Y1739298D02*
X886540Y1739923D01*
G01X886248Y1741482D02*
X886457Y1741773D01*
X886540Y1742107D01*
X886457Y1742440D01*
X886207Y1742732D01*
X885832Y1742940D01*
X885457Y1743023D01*
X884998D01*
X884623Y1742940D01*
X884290Y1742732D01*
X884123Y1742482D01*
X884040Y1742190D01*
X884123Y1741857D01*
X884290Y1741607D01*
X884540Y1741440D01*
X884873Y1741357D01*
X885165Y1741440D01*
X885457Y1741648D01*
X885623Y1741898D01*
X885665Y1742190D01*
X885582Y1742523D01*
X885373Y1742773D01*
X884998Y1743023D01*
G01X884040Y1745290D02*
X884123Y1744957D01*
X884332Y1744707D01*
X884582Y1744540D01*
X884915Y1744415D01*
X885290Y1744373D01*
X885665Y1744415D01*
X885998Y1744540D01*
X886248Y1744707D01*
X886457Y1744957D01*
X886540Y1745290D01*
X886457Y1745623D01*
X886248Y1745873D01*
X885998Y1746040D01*
X885665Y1746165D01*
X885290Y1746207D01*
X884915Y1746165D01*
X884582Y1746040D01*
X884332Y1745873D01*
X884123Y1745623D01*
X884040Y1745290D01*
G01X886248Y1747682D02*
X886457Y1747973D01*
X886540Y1748307D01*
X886457Y1748640D01*
X886207Y1748932D01*
X885832Y1749140D01*
X885457Y1749223D01*
X884998D01*
X884623Y1749140D01*
X884290Y1748932D01*
X884123Y1748682D01*
X884040Y1748390D01*
X884123Y1748057D01*
X884290Y1747807D01*
X884540Y1747640D01*
X884873Y1747557D01*
X885165Y1747640D01*
X885457Y1747848D01*
X885623Y1748098D01*
X885665Y1748390D01*
X885582Y1748723D01*
X885373Y1748973D01*
X884998Y1749223D01*
G01X886540Y1751490D02*
X884040D01*
X884540Y1750990D01*
G01X886540D02*
Y1751990D01*
G01X888000Y1733700D02*
X881000D01*
G01D02*
Y1725900D01*
G01X888000Y1733700D02*
Y1728500D01*
G01X880000Y1732917D02*
X877500D01*
Y1733917D01*
X877625Y1734250D01*
X877917Y1734500D01*
X878250Y1734583D01*
X878583Y1734500D01*
X878833Y1734292D01*
X878958Y1733917D01*
Y1732917D01*
G01X877708Y1737767D02*
X877583Y1737517D01*
X877500Y1737225D01*
Y1736892D01*
X877625Y1736517D01*
X877833Y1736225D01*
X878083Y1736017D01*
X878500Y1735850D01*
X878875Y1735808D01*
X879250Y1735892D01*
X879500Y1736017D01*
X879750Y1736267D01*
X879917Y1736558D01*
X880000Y1736850D01*
Y1737142D01*
X879917Y1737433D01*
X879792Y1737683D01*
X879625Y1737892D01*
G01X880000Y1739950D02*
X877500D01*
X878000Y1739450D01*
G01X880000D02*
Y1740450D01*
G01X877917Y1742258D02*
X877667Y1742508D01*
X877542Y1742800D01*
X877500Y1743133D01*
X877583Y1743550D01*
X877792Y1743842D01*
X878042Y1743925D01*
X878292Y1743883D01*
X878500Y1743717D01*
X878917Y1742883D01*
X879208Y1742508D01*
X879625Y1742258D01*
X880000Y1742175D01*
Y1743925D01*
G01Y1746150D02*
X879958Y1746442D01*
X879833Y1746775D01*
X879625Y1746983D01*
X879333Y1747067D01*
X879042Y1746983D01*
X878792Y1746733D01*
X878667Y1746358D01*
Y1745942D01*
X878583Y1745692D01*
X878375Y1745483D01*
X878083Y1745400D01*
X877792Y1745525D01*
X877583Y1745817D01*
X877500Y1746150D01*
X877583Y1746483D01*
X877792Y1746775D01*
X878083Y1746900D01*
X878375Y1746817D01*
X878583Y1746608D01*
X878667Y1746358D01*
Y1745942D01*
X878792Y1745567D01*
X879042Y1745317D01*
X879333Y1745233D01*
X879625Y1745317D01*
X879833Y1745525D01*
X879958Y1745858D01*
X880000Y1746150D01*
G01Y1749167D02*
X879458Y1749250D01*
X879000Y1749375D01*
X878583Y1749542D01*
X878125Y1749750D01*
X877500Y1750083D01*
Y1748417D01*
G01X854367Y1736400D02*
Y1738900D01*
X855367D01*
X855700Y1738775D01*
X855950Y1738483D01*
X856033Y1738150D01*
X855950Y1737817D01*
X855742Y1737567D01*
X855367Y1737442D01*
X854367D01*
G01X857467Y1738900D02*
Y1736400D01*
X859133D01*
G01X860608Y1738483D02*
X860858Y1738733D01*
X861150Y1738858D01*
X861483Y1738900D01*
X861900Y1738817D01*
X862192Y1738608D01*
X862275Y1738358D01*
X862233Y1738108D01*
X862067Y1737900D01*
X861233Y1737483D01*
X860858Y1737192D01*
X860608Y1736775D01*
X860525Y1736400D01*
X862275D01*
G01X896000Y1733417D02*
X893500D01*
Y1734417D01*
X893625Y1734750D01*
X893917Y1735000D01*
X894250Y1735083D01*
X894583Y1735000D01*
X894833Y1734792D01*
X894958Y1734417D01*
Y1733417D01*
G01X893708Y1738267D02*
X893583Y1738017D01*
X893500Y1737725D01*
Y1737392D01*
X893625Y1737017D01*
X893833Y1736725D01*
X894083Y1736517D01*
X894500Y1736350D01*
X894875Y1736308D01*
X895250Y1736392D01*
X895500Y1736517D01*
X895750Y1736767D01*
X895917Y1737058D01*
X896000Y1737350D01*
Y1737642D01*
X895917Y1737933D01*
X895792Y1738183D01*
X895625Y1738392D01*
G01X896000Y1740450D02*
X893500D01*
X894000Y1739950D01*
G01X896000D02*
Y1740950D01*
G01X893917Y1742758D02*
X893667Y1743008D01*
X893542Y1743300D01*
X893500Y1743633D01*
X893583Y1744050D01*
X893792Y1744342D01*
X894042Y1744425D01*
X894292Y1744383D01*
X894500Y1744217D01*
X894917Y1743383D01*
X895208Y1743008D01*
X895625Y1742758D01*
X896000Y1742675D01*
Y1744425D01*
G01Y1746567D02*
X895458Y1746650D01*
X895000Y1746775D01*
X894583Y1746942D01*
X894125Y1747150D01*
X893500Y1747483D01*
Y1745817D01*
G01X895625Y1748833D02*
X895833Y1749083D01*
X895958Y1749375D01*
X896000Y1749750D01*
X895917Y1750125D01*
X895750Y1750417D01*
X895458Y1750625D01*
X895125Y1750667D01*
X894792Y1750583D01*
X894583Y1750375D01*
X894417Y1750083D01*
X894375Y1749792D01*
X894417Y1749500D01*
X894583Y1749125D01*
X893500Y1749250D01*
Y1750375D01*
G01X883500Y1757933D02*
X885292D01*
X885667Y1758100D01*
X885917Y1758433D01*
X886000Y1758850D01*
X885917Y1759267D01*
X885667Y1759600D01*
X885292Y1759767D01*
X883500D01*
G01X886000Y1761950D02*
X883500D01*
X884000Y1761450D01*
G01X886000D02*
Y1762450D01*
G01X885708Y1764342D02*
X885917Y1764633D01*
X886000Y1764967D01*
X885917Y1765300D01*
X885667Y1765592D01*
X885292Y1765800D01*
X884917Y1765883D01*
X884458D01*
X884083Y1765800D01*
X883750Y1765592D01*
X883583Y1765342D01*
X883500Y1765050D01*
X883583Y1764717D01*
X883750Y1764467D01*
X884000Y1764300D01*
X884333Y1764217D01*
X884625Y1764300D01*
X884917Y1764508D01*
X885083Y1764758D01*
X885125Y1765050D01*
X885042Y1765383D01*
X884833Y1765633D01*
X884458Y1765883D01*
G01X886000Y1768067D02*
X885458Y1768150D01*
X885000Y1768275D01*
X884583Y1768442D01*
X884125Y1768650D01*
X883500Y1768983D01*
Y1767317D01*
G01X901200Y1754500D02*
X887800D01*
G01X901200Y1764500D02*
Y1754500D01*
G01X887800Y1764500D02*
X901200D01*
G01X887800Y1754500D02*
Y1764500D01*
G01X937654Y1807865D02*
X908754D01*
Y1794965D01*
X890454D01*
Y1807865D01*
X876954D01*
Y1969065D01*
X890454D01*
Y1981965D01*
X908754D01*
Y1969065D01*
X937654D01*
Y1958715D01*
X930954D01*
Y1818215D01*
X937654D01*
Y1807865D01*
G01X868000Y1850417D02*
X865500D01*
Y1851417D01*
X865625Y1851750D01*
X865917Y1852000D01*
X866250Y1852083D01*
X866583Y1852000D01*
X866833Y1851792D01*
X866958Y1851417D01*
Y1850417D01*
G01X865708Y1855267D02*
X865583Y1855017D01*
X865500Y1854725D01*
Y1854392D01*
X865625Y1854017D01*
X865833Y1853725D01*
X866083Y1853517D01*
X866500Y1853350D01*
X866875Y1853308D01*
X867250Y1853392D01*
X867500Y1853517D01*
X867750Y1853767D01*
X867917Y1854058D01*
X868000Y1854350D01*
Y1854642D01*
X867917Y1854933D01*
X867792Y1855183D01*
X867625Y1855392D01*
G01X868000Y1857450D02*
X865500D01*
X866000Y1856950D01*
G01X868000D02*
Y1857950D01*
G01Y1860550D02*
X865500D01*
X866000Y1860050D01*
G01X868000D02*
Y1861050D01*
G01Y1863650D02*
X867958Y1863942D01*
X867833Y1864275D01*
X867625Y1864483D01*
X867333Y1864567D01*
X867042Y1864483D01*
X866792Y1864233D01*
X866667Y1863858D01*
Y1863442D01*
X866583Y1863192D01*
X866375Y1862983D01*
X866083Y1862900D01*
X865792Y1863025D01*
X865583Y1863317D01*
X865500Y1863650D01*
X865583Y1863983D01*
X865792Y1864275D01*
X866083Y1864400D01*
X866375Y1864317D01*
X866583Y1864108D01*
X866667Y1863858D01*
Y1863442D01*
X866792Y1863067D01*
X867042Y1862817D01*
X867333Y1862733D01*
X867625Y1862817D01*
X867833Y1863025D01*
X867958Y1863358D01*
X868000Y1863650D01*
G01X867708Y1866042D02*
X867917Y1866333D01*
X868000Y1866667D01*
X867917Y1867000D01*
X867667Y1867292D01*
X867292Y1867500D01*
X866917Y1867583D01*
X866458D01*
X866083Y1867500D01*
X865750Y1867292D01*
X865583Y1867042D01*
X865500Y1866750D01*
X865583Y1866417D01*
X865750Y1866167D01*
X866000Y1866000D01*
X866333Y1865917D01*
X866625Y1866000D01*
X866917Y1866208D01*
X867083Y1866458D01*
X867125Y1866750D01*
X867042Y1867083D01*
X866833Y1867333D01*
X866458Y1867583D01*
G01X843100Y1806583D02*
X844892D01*
X845267Y1806750D01*
X845517Y1807083D01*
X845600Y1807500D01*
X845517Y1807917D01*
X845267Y1808250D01*
X844892Y1808417D01*
X843100D01*
G01X845600Y1811100D02*
X843100D01*
X844892Y1809558D01*
Y1811642D01*
G01X845600Y1813617D02*
X845058Y1813700D01*
X844600Y1813825D01*
X844183Y1813992D01*
X843725Y1814200D01*
X843100Y1814533D01*
Y1812867D01*
G01X848516Y1910372D02*
X847683Y1909039D01*
X847183Y1907539D01*
Y1906205D01*
X847683Y1904872D01*
X848516Y1903872D01*
X849683Y1903372D01*
X850849Y1903705D01*
X851850Y1904539D01*
X852516Y1906039D01*
X852850Y1908039D01*
X853516Y1909205D01*
X854683Y1909705D01*
X855850Y1909372D01*
X856683Y1908539D01*
X857183Y1907372D01*
Y1906205D01*
X856850Y1905039D01*
X856016Y1904039D01*
G01X848516Y1899772D02*
X847683Y1898439D01*
X847183Y1896939D01*
Y1895605D01*
X847683Y1894272D01*
X848516Y1893272D01*
X849683Y1892772D01*
X850849Y1893105D01*
X851850Y1893939D01*
X852516Y1895439D01*
X852850Y1897439D01*
X853516Y1898605D01*
X854683Y1899105D01*
X855850Y1898772D01*
X856683Y1897939D01*
X857183Y1896772D01*
Y1895605D01*
X856850Y1894439D01*
X856016Y1893439D01*
G01X847183Y1889339D02*
X857183D01*
Y1886005D01*
X856683Y1884672D01*
X856016Y1883672D01*
X855016Y1882839D01*
X853849Y1882172D01*
X852183Y1882005D01*
X850516Y1882172D01*
X849350Y1882839D01*
X848349Y1883672D01*
X847683Y1884672D01*
X847183Y1886005D01*
Y1889339D01*
G01X857183Y1875072D02*
X856850Y1876406D01*
X856016Y1877405D01*
X855016Y1878072D01*
X853683Y1878572D01*
X852183Y1878739D01*
X850683Y1878572D01*
X849350Y1878072D01*
X848349Y1877405D01*
X847516Y1876406D01*
X847183Y1875072D01*
X847516Y1873739D01*
X848349Y1872739D01*
X849350Y1872072D01*
X850683Y1871572D01*
X852183Y1871405D01*
X853683Y1871572D01*
X855016Y1872072D01*
X856016Y1872739D01*
X856850Y1873739D01*
X857183Y1875072D01*
G01X871334Y1874518D02*
X871584Y1874726D01*
X871751Y1874976D01*
X871834Y1875268D01*
X871751Y1875601D01*
X871584Y1875851D01*
X871334Y1876101D01*
X871001Y1876184D01*
X869334D01*
G01X871834Y1878451D02*
X869334D01*
X869834Y1877951D01*
G01X871834D02*
Y1878951D01*
G01X869334Y1881551D02*
X869417Y1881218D01*
X869626Y1880968D01*
X869876Y1880801D01*
X870209Y1880676D01*
X870584Y1880634D01*
X870959Y1880676D01*
X871292Y1880801D01*
X871542Y1880968D01*
X871751Y1881218D01*
X871834Y1881551D01*
X871751Y1881884D01*
X871542Y1882134D01*
X871292Y1882301D01*
X870959Y1882426D01*
X870584Y1882468D01*
X870209Y1882426D01*
X869876Y1882301D01*
X869626Y1882134D01*
X869417Y1881884D01*
X869334Y1881551D01*
G01Y1884651D02*
X869417Y1884318D01*
X869626Y1884068D01*
X869876Y1883901D01*
X870209Y1883776D01*
X870584Y1883734D01*
X870959Y1883776D01*
X871292Y1883901D01*
X871542Y1884068D01*
X871751Y1884318D01*
X871834Y1884651D01*
X871751Y1884984D01*
X871542Y1885234D01*
X871292Y1885401D01*
X870959Y1885526D01*
X870584Y1885568D01*
X870209Y1885526D01*
X869876Y1885401D01*
X869626Y1885234D01*
X869417Y1884984D01*
X869334Y1884651D01*
G01X840775Y1930233D02*
X841108Y1930025D01*
X841483Y1929900D01*
X841817D01*
X842150Y1930025D01*
X842400Y1930233D01*
X842525Y1930525D01*
X842442Y1930817D01*
X842233Y1931067D01*
X841858Y1931233D01*
X841358Y1931317D01*
X841067Y1931483D01*
X840942Y1931775D01*
X841025Y1932067D01*
X841233Y1932275D01*
X841525Y1932400D01*
X841817D01*
X842108Y1932317D01*
X842358Y1932108D01*
G01X843917Y1929900D02*
Y1932400D01*
X844958D01*
X845292Y1932275D01*
X845500Y1932108D01*
X845583Y1931775D01*
X845500Y1931442D01*
X845250Y1931233D01*
X844958Y1931108D01*
X843917D01*
G01X844958D02*
X845583Y1929900D01*
G01X847850D02*
Y1932400D01*
X847350Y1931900D01*
G01Y1929900D02*
X848350D01*
G01X850950Y1932400D02*
X850617Y1932317D01*
X850367Y1932108D01*
X850200Y1931858D01*
X850075Y1931525D01*
X850033Y1931150D01*
X850075Y1930775D01*
X850200Y1930442D01*
X850367Y1930192D01*
X850617Y1929983D01*
X850950Y1929900D01*
X851283Y1929983D01*
X851533Y1930192D01*
X851700Y1930442D01*
X851825Y1930775D01*
X851867Y1931150D01*
X851825Y1931525D01*
X851700Y1931858D01*
X851533Y1932108D01*
X851283Y1932317D01*
X850950Y1932400D01*
G01X853342Y1930192D02*
X853633Y1929983D01*
X853967Y1929900D01*
X854300Y1929983D01*
X854592Y1930233D01*
X854800Y1930608D01*
X854883Y1930983D01*
Y1931442D01*
X854800Y1931817D01*
X854592Y1932150D01*
X854342Y1932317D01*
X854050Y1932400D01*
X853717Y1932317D01*
X853467Y1932150D01*
X853300Y1931900D01*
X853217Y1931567D01*
X853300Y1931275D01*
X853508Y1930983D01*
X853758Y1930817D01*
X854050Y1930775D01*
X854383Y1930858D01*
X854633Y1931067D01*
X854883Y1931442D01*
G01X856358Y1931983D02*
X856608Y1932233D01*
X856900Y1932358D01*
X857233Y1932400D01*
X857650Y1932317D01*
X857942Y1932108D01*
X858025Y1931858D01*
X857983Y1931608D01*
X857817Y1931400D01*
X856983Y1930983D01*
X856608Y1930692D01*
X856358Y1930275D01*
X856275Y1929900D01*
X858025D01*
G01X840275Y1925733D02*
X840608Y1925525D01*
X840983Y1925400D01*
X841317D01*
X841650Y1925525D01*
X841900Y1925733D01*
X842025Y1926025D01*
X841942Y1926317D01*
X841733Y1926567D01*
X841358Y1926733D01*
X840858Y1926817D01*
X840567Y1926983D01*
X840442Y1927275D01*
X840525Y1927567D01*
X840733Y1927775D01*
X841025Y1927900D01*
X841317D01*
X841608Y1927817D01*
X841858Y1927608D01*
G01X843417Y1925400D02*
Y1927900D01*
X844458D01*
X844792Y1927775D01*
X845000Y1927608D01*
X845083Y1927275D01*
X845000Y1926942D01*
X844750Y1926733D01*
X844458Y1926608D01*
X843417D01*
G01X844458D02*
X845083Y1925400D01*
G01X847350D02*
Y1927900D01*
X846850Y1927400D01*
G01Y1925400D02*
X847850D01*
G01X850450Y1927900D02*
X850117Y1927817D01*
X849867Y1927608D01*
X849700Y1927358D01*
X849575Y1927025D01*
X849533Y1926650D01*
X849575Y1926275D01*
X849700Y1925942D01*
X849867Y1925692D01*
X850117Y1925483D01*
X850450Y1925400D01*
X850783Y1925483D01*
X851033Y1925692D01*
X851200Y1925942D01*
X851325Y1926275D01*
X851367Y1926650D01*
X851325Y1927025D01*
X851200Y1927358D01*
X851033Y1927608D01*
X850783Y1927817D01*
X850450Y1927900D01*
G01X852842Y1925692D02*
X853133Y1925483D01*
X853467Y1925400D01*
X853800Y1925483D01*
X854092Y1925733D01*
X854300Y1926108D01*
X854383Y1926483D01*
Y1926942D01*
X854300Y1927317D01*
X854092Y1927650D01*
X853842Y1927817D01*
X853550Y1927900D01*
X853217Y1927817D01*
X852967Y1927650D01*
X852800Y1927400D01*
X852717Y1927067D01*
X852800Y1926775D01*
X853008Y1926483D01*
X853258Y1926317D01*
X853550Y1926275D01*
X853883Y1926358D01*
X854133Y1926567D01*
X854383Y1926942D01*
G01X856650Y1925400D02*
Y1927900D01*
X856150Y1927400D01*
G01Y1925400D02*
X857150D01*
G01X844187Y1920791D02*
Y1923291D01*
X845228D01*
X845562Y1923166D01*
X845770Y1922999D01*
X845853Y1922666D01*
X845770Y1922333D01*
X845520Y1922124D01*
X845228Y1921999D01*
X844187D01*
G01X845228D02*
X845853Y1920791D01*
G01X847203Y1921291D02*
X847453Y1920999D01*
X847787Y1920833D01*
X848162Y1920791D01*
X848495Y1920833D01*
X848828Y1921041D01*
X849037Y1921291D01*
X849078Y1921541D01*
X848995Y1921833D01*
X848703Y1922041D01*
X848412Y1922124D01*
X848037D01*
G01X848412D02*
X848662Y1922249D01*
X848870Y1922458D01*
X848953Y1922708D01*
X848870Y1922958D01*
X848662Y1923166D01*
X848287Y1923291D01*
X847912Y1923249D01*
X847537Y1923083D01*
G01X851220Y1920791D02*
X851512Y1920833D01*
X851845Y1920958D01*
X852053Y1921166D01*
X852137Y1921458D01*
X852053Y1921749D01*
X851803Y1921999D01*
X851428Y1922124D01*
X851012D01*
X850762Y1922208D01*
X850553Y1922416D01*
X850470Y1922708D01*
X850595Y1922999D01*
X850887Y1923208D01*
X851220Y1923291D01*
X851553Y1923208D01*
X851845Y1922999D01*
X851970Y1922708D01*
X851887Y1922416D01*
X851678Y1922208D01*
X851428Y1922124D01*
X851012D01*
X850637Y1921999D01*
X850387Y1921749D01*
X850303Y1921458D01*
X850387Y1921166D01*
X850595Y1920958D01*
X850928Y1920833D01*
X851220Y1920791D01*
G01X854820D02*
Y1923291D01*
X853278Y1921499D01*
X855362D01*
G01X857200Y1938800D02*
Y1942800D01*
X849800D01*
G01X844187Y1915791D02*
Y1918291D01*
X845228D01*
X845562Y1918166D01*
X845770Y1917999D01*
X845853Y1917666D01*
X845770Y1917333D01*
X845520Y1917124D01*
X845228Y1916999D01*
X844187D01*
G01X845228D02*
X845853Y1915791D01*
G01X847203Y1916291D02*
X847453Y1915999D01*
X847787Y1915833D01*
X848162Y1915791D01*
X848495Y1915833D01*
X848828Y1916041D01*
X849037Y1916291D01*
X849078Y1916541D01*
X848995Y1916833D01*
X848703Y1917041D01*
X848412Y1917124D01*
X848037D01*
G01X848412D02*
X848662Y1917249D01*
X848870Y1917458D01*
X848953Y1917708D01*
X848870Y1917958D01*
X848662Y1918166D01*
X848287Y1918291D01*
X847912Y1918249D01*
X847537Y1918083D01*
G01X851220Y1915791D02*
X851512Y1915833D01*
X851845Y1915958D01*
X852053Y1916166D01*
X852137Y1916458D01*
X852053Y1916749D01*
X851803Y1916999D01*
X851428Y1917124D01*
X851012D01*
X850762Y1917208D01*
X850553Y1917416D01*
X850470Y1917708D01*
X850595Y1917999D01*
X850887Y1918208D01*
X851220Y1918291D01*
X851553Y1918208D01*
X851845Y1917999D01*
X851970Y1917708D01*
X851887Y1917416D01*
X851678Y1917208D01*
X851428Y1917124D01*
X851012D01*
X850637Y1916999D01*
X850387Y1916749D01*
X850303Y1916458D01*
X850387Y1916166D01*
X850595Y1915958D01*
X850928Y1915833D01*
X851220Y1915791D01*
G01X854320Y1918291D02*
X853987Y1918208D01*
X853737Y1917999D01*
X853570Y1917749D01*
X853445Y1917416D01*
X853403Y1917041D01*
X853445Y1916666D01*
X853570Y1916333D01*
X853737Y1916083D01*
X853987Y1915874D01*
X854320Y1915791D01*
X854653Y1915874D01*
X854903Y1916083D01*
X855070Y1916333D01*
X855195Y1916666D01*
X855237Y1917041D01*
X855195Y1917416D01*
X855070Y1917749D01*
X854903Y1917999D01*
X854653Y1918208D01*
X854320Y1918291D01*
G01X857200Y1933800D02*
Y1937800D01*
X849800D01*
G01X862267Y1978550D02*
Y1981050D01*
X863267D01*
X863600Y1980925D01*
X863850Y1980633D01*
X863933Y1980300D01*
X863850Y1979967D01*
X863642Y1979717D01*
X863267Y1979592D01*
X862267D01*
G01X867117Y1980842D02*
X866867Y1980967D01*
X866575Y1981050D01*
X866242D01*
X865867Y1980925D01*
X865575Y1980717D01*
X865367Y1980467D01*
X865200Y1980050D01*
X865158Y1979675D01*
X865242Y1979300D01*
X865367Y1979050D01*
X865617Y1978800D01*
X865908Y1978633D01*
X866200Y1978550D01*
X866492D01*
X866783Y1978633D01*
X867033Y1978758D01*
X867242Y1978925D01*
G01X869300Y1978550D02*
Y1981050D01*
X868800Y1980550D01*
G01Y1978550D02*
X869800D01*
G01X872400D02*
Y1981050D01*
X871900Y1980550D01*
G01Y1978550D02*
X872900D01*
G01X875500D02*
X875792Y1978592D01*
X876125Y1978717D01*
X876333Y1978925D01*
X876417Y1979217D01*
X876333Y1979508D01*
X876083Y1979758D01*
X875708Y1979883D01*
X875292D01*
X875042Y1979967D01*
X874833Y1980175D01*
X874750Y1980467D01*
X874875Y1980758D01*
X875167Y1980967D01*
X875500Y1981050D01*
X875833Y1980967D01*
X876125Y1980758D01*
X876250Y1980467D01*
X876167Y1980175D01*
X875958Y1979967D01*
X875708Y1979883D01*
X875292D01*
X874917Y1979758D01*
X874667Y1979508D01*
X874583Y1979217D01*
X874667Y1978925D01*
X874875Y1978717D01*
X875208Y1978592D01*
X875500Y1978550D01*
G01X878600D02*
X878892Y1978592D01*
X879225Y1978717D01*
X879433Y1978925D01*
X879517Y1979217D01*
X879433Y1979508D01*
X879183Y1979758D01*
X878808Y1979883D01*
X878392D01*
X878142Y1979967D01*
X877933Y1980175D01*
X877850Y1980467D01*
X877975Y1980758D01*
X878267Y1980967D01*
X878600Y1981050D01*
X878933Y1980967D01*
X879225Y1980758D01*
X879350Y1980467D01*
X879267Y1980175D01*
X879058Y1979967D01*
X878808Y1979883D01*
X878392D01*
X878017Y1979758D01*
X877767Y1979508D01*
X877683Y1979217D01*
X877767Y1978925D01*
X877975Y1978717D01*
X878308Y1978592D01*
X878600Y1978550D01*
G01X843717Y1975000D02*
Y1977500D01*
X844717D01*
X845050Y1977375D01*
X845300Y1977083D01*
X845383Y1976750D01*
X845300Y1976417D01*
X845092Y1976167D01*
X844717Y1976042D01*
X843717D01*
G01X848567Y1977292D02*
X848317Y1977417D01*
X848025Y1977500D01*
X847692D01*
X847317Y1977375D01*
X847025Y1977167D01*
X846817Y1976917D01*
X846650Y1976500D01*
X846608Y1976125D01*
X846692Y1975750D01*
X846817Y1975500D01*
X847067Y1975250D01*
X847358Y1975083D01*
X847650Y1975000D01*
X847942D01*
X848233Y1975083D01*
X848483Y1975208D01*
X848692Y1975375D01*
G01X850750Y1975000D02*
Y1977500D01*
X850250Y1977000D01*
G01Y1975000D02*
X851250D01*
G01X853850D02*
Y1977500D01*
X853350Y1977000D01*
G01Y1975000D02*
X854350D01*
G01X856950D02*
X857242Y1975042D01*
X857575Y1975167D01*
X857783Y1975375D01*
X857867Y1975667D01*
X857783Y1975958D01*
X857533Y1976208D01*
X857158Y1976333D01*
X856742D01*
X856492Y1976417D01*
X856283Y1976625D01*
X856200Y1976917D01*
X856325Y1977208D01*
X856617Y1977417D01*
X856950Y1977500D01*
X857283Y1977417D01*
X857575Y1977208D01*
X857700Y1976917D01*
X857617Y1976625D01*
X857408Y1976417D01*
X857158Y1976333D01*
X856742D01*
X856367Y1976208D01*
X856117Y1975958D01*
X856033Y1975667D01*
X856117Y1975375D01*
X856325Y1975167D01*
X856658Y1975042D01*
X856950Y1975000D01*
G01X859967D02*
X860050Y1975542D01*
X860175Y1976000D01*
X860342Y1976417D01*
X860550Y1976875D01*
X860883Y1977500D01*
X859217D01*
G01X853300Y1947700D02*
Y1951700D01*
X845900D01*
G01Y1947200D02*
Y1943200D01*
X853300D01*
G01X862367Y1982500D02*
Y1985000D01*
X863408D01*
X863742Y1984875D01*
X863950Y1984708D01*
X864033Y1984375D01*
X863950Y1984042D01*
X863700Y1983833D01*
X863408Y1983708D01*
X862367D01*
G01X863408D02*
X864033Y1982500D01*
G01X865592Y1982792D02*
X865883Y1982583D01*
X866217Y1982500D01*
X866550Y1982583D01*
X866842Y1982833D01*
X867050Y1983208D01*
X867133Y1983583D01*
Y1984042D01*
X867050Y1984417D01*
X866842Y1984750D01*
X866592Y1984917D01*
X866300Y1985000D01*
X865967Y1984917D01*
X865717Y1984750D01*
X865550Y1984500D01*
X865467Y1984167D01*
X865550Y1983875D01*
X865758Y1983583D01*
X866008Y1983417D01*
X866300Y1983375D01*
X866633Y1983458D01*
X866883Y1983667D01*
X867133Y1984042D01*
G01X868608Y1984583D02*
X868858Y1984833D01*
X869150Y1984958D01*
X869483Y1985000D01*
X869900Y1984917D01*
X870192Y1984708D01*
X870275Y1984458D01*
X870233Y1984208D01*
X870067Y1984000D01*
X869233Y1983583D01*
X868858Y1983292D01*
X868608Y1982875D01*
X868525Y1982500D01*
X870275D01*
G01X871583Y1983000D02*
X871833Y1982708D01*
X872167Y1982542D01*
X872542Y1982500D01*
X872875Y1982542D01*
X873208Y1982750D01*
X873417Y1983000D01*
X873458Y1983250D01*
X873375Y1983542D01*
X873083Y1983750D01*
X872792Y1983833D01*
X872417D01*
G01X872792D02*
X873042Y1983958D01*
X873250Y1984167D01*
X873333Y1984417D01*
X873250Y1984667D01*
X873042Y1984875D01*
X872667Y1985000D01*
X872292Y1984958D01*
X871917Y1984792D01*
G01X874892Y1982792D02*
X875183Y1982583D01*
X875517Y1982500D01*
X875850Y1982583D01*
X876142Y1982833D01*
X876350Y1983208D01*
X876433Y1983583D01*
Y1984042D01*
X876350Y1984417D01*
X876142Y1984750D01*
X875892Y1984917D01*
X875600Y1985000D01*
X875267Y1984917D01*
X875017Y1984750D01*
X874850Y1984500D01*
X874767Y1984167D01*
X874850Y1983875D01*
X875058Y1983583D01*
X875308Y1983417D01*
X875600Y1983375D01*
X875933Y1983458D01*
X876183Y1983667D01*
X876433Y1984042D01*
G01X875500Y1959000D02*
Y1972000D01*
G01X849500Y1959000D02*
X875500D01*
G01X849500Y1972000D02*
Y1959000D01*
G01X875500Y1972000D02*
X849500D01*
G01X928475Y152533D02*
X928808Y152325D01*
X929183Y152200D01*
X929517D01*
X929850Y152325D01*
X930100Y152533D01*
X930225Y152825D01*
X930142Y153117D01*
X929933Y153367D01*
X929558Y153533D01*
X929058Y153617D01*
X928767Y153783D01*
X928642Y154075D01*
X928725Y154367D01*
X928933Y154575D01*
X929225Y154700D01*
X929517D01*
X929808Y154617D01*
X930058Y154408D01*
G01X931533Y152200D02*
Y154700D01*
X932367D01*
X932700Y154575D01*
X932950Y154408D01*
X933158Y154158D01*
X933325Y153867D01*
X933367Y153450D01*
X933325Y153033D01*
X933158Y152742D01*
X932950Y152492D01*
X932700Y152325D01*
X932367Y152200D01*
X931533D01*
G01X934633D02*
Y154700D01*
X935467D01*
X935800Y154575D01*
X936050Y154408D01*
X936258Y154158D01*
X936425Y153867D01*
X936467Y153450D01*
X936425Y153033D01*
X936258Y152742D01*
X936050Y152492D01*
X935800Y152325D01*
X935467Y152200D01*
X934633D01*
G01X940708D02*
X941750Y154700D01*
X942792Y152200D01*
G01X942417Y153075D02*
X941083D01*
G01X945767Y154492D02*
X945517Y154617D01*
X945225Y154700D01*
X944892D01*
X944517Y154575D01*
X944225Y154367D01*
X944017Y154117D01*
X943850Y153700D01*
X943808Y153325D01*
X943892Y152950D01*
X944017Y152700D01*
X944267Y152450D01*
X944558Y152283D01*
X944850Y152200D01*
X945142D01*
X945433Y152283D01*
X945683Y152408D01*
X945892Y152575D01*
G01X947950Y154700D02*
Y152200D01*
G01X946992Y154700D02*
X948908D01*
G01X951550Y152200D02*
Y154700D01*
X950008Y152908D01*
X952092D01*
G01X920600Y148900D02*
X920267Y148942D01*
X919975Y149108D01*
X919725Y149358D01*
X919558Y149650D01*
X919475Y149983D01*
Y150317D01*
X919558Y150650D01*
X919725Y150942D01*
X919975Y151192D01*
X920267Y151358D01*
X920600Y151400D01*
X920933Y151358D01*
X921225Y151192D01*
X921475Y150942D01*
X921642Y150650D01*
X921725Y150317D01*
Y149983D01*
X921642Y149650D01*
X921475Y149358D01*
X921225Y149108D01*
X920933Y148942D01*
X920600Y148900D01*
G01X920933Y149567D02*
X921433Y148900D01*
G01X924200D02*
Y151400D01*
X922658Y149608D01*
X924742D01*
G01X926800Y148900D02*
X927092Y148942D01*
X927425Y149067D01*
X927633Y149275D01*
X927717Y149567D01*
X927633Y149858D01*
X927383Y150108D01*
X927008Y150233D01*
X926592D01*
X926342Y150317D01*
X926133Y150525D01*
X926050Y150817D01*
X926175Y151108D01*
X926467Y151317D01*
X926800Y151400D01*
X927133Y151317D01*
X927425Y151108D01*
X927550Y150817D01*
X927467Y150525D01*
X927258Y150317D01*
X927008Y150233D01*
X926592D01*
X926217Y150108D01*
X925967Y149858D01*
X925883Y149567D01*
X925967Y149275D01*
X926175Y149067D01*
X926508Y148942D01*
X926800Y148900D01*
G01X927000Y147953D02*
X914000D01*
G01D02*
Y133953D01*
G01D02*
X927000D01*
G01D02*
Y147953D01*
G01X929767Y166100D02*
Y168600D01*
X930808D01*
X931142Y168475D01*
X931350Y168308D01*
X931433Y167975D01*
X931350Y167642D01*
X931100Y167433D01*
X930808Y167308D01*
X929767D01*
G01X930808D02*
X931433Y166100D01*
G01X932992Y166392D02*
X933283Y166183D01*
X933617Y166100D01*
X933950Y166183D01*
X934242Y166433D01*
X934450Y166808D01*
X934533Y167183D01*
Y167642D01*
X934450Y168017D01*
X934242Y168350D01*
X933992Y168517D01*
X933700Y168600D01*
X933367Y168517D01*
X933117Y168350D01*
X932950Y168100D01*
X932867Y167767D01*
X932950Y167475D01*
X933158Y167183D01*
X933408Y167017D01*
X933700Y166975D01*
X934033Y167058D01*
X934283Y167267D01*
X934533Y167642D01*
G01X937300Y166100D02*
Y168600D01*
X935758Y166808D01*
X937842D01*
G01X939900Y168600D02*
X939567Y168517D01*
X939317Y168308D01*
X939150Y168058D01*
X939025Y167725D01*
X938983Y167350D01*
X939025Y166975D01*
X939150Y166642D01*
X939317Y166392D01*
X939567Y166183D01*
X939900Y166100D01*
X940233Y166183D01*
X940483Y166392D01*
X940650Y166642D01*
X940775Y166975D01*
X940817Y167350D01*
X940775Y167725D01*
X940650Y168058D01*
X940483Y168308D01*
X940233Y168517D01*
X939900Y168600D01*
G01X942917Y166100D02*
X943000Y166642D01*
X943125Y167100D01*
X943292Y167517D01*
X943500Y167975D01*
X943833Y168600D01*
X942167D01*
G01X925200Y162453D02*
Y166453D01*
X917800D01*
G01X926967Y128500D02*
Y131000D01*
X928008D01*
X928342Y130875D01*
X928550Y130708D01*
X928633Y130375D01*
X928550Y130042D01*
X928300Y129833D01*
X928008Y129708D01*
X926967D01*
G01X928008D02*
X928633Y128500D01*
G01X930192Y128792D02*
X930483Y128583D01*
X930817Y128500D01*
X931150Y128583D01*
X931442Y128833D01*
X931650Y129208D01*
X931733Y129583D01*
Y130042D01*
X931650Y130417D01*
X931442Y130750D01*
X931192Y130917D01*
X930900Y131000D01*
X930567Y130917D01*
X930317Y130750D01*
X930150Y130500D01*
X930067Y130167D01*
X930150Y129875D01*
X930358Y129583D01*
X930608Y129417D01*
X930900Y129375D01*
X931233Y129458D01*
X931483Y129667D01*
X931733Y130042D01*
G01X934000Y128500D02*
X934292Y128542D01*
X934625Y128667D01*
X934833Y128875D01*
X934917Y129167D01*
X934833Y129458D01*
X934583Y129708D01*
X934208Y129833D01*
X933792D01*
X933542Y129917D01*
X933333Y130125D01*
X933250Y130417D01*
X933375Y130708D01*
X933667Y130917D01*
X934000Y131000D01*
X934333Y130917D01*
X934625Y130708D01*
X934750Y130417D01*
X934667Y130125D01*
X934458Y129917D01*
X934208Y129833D01*
X933792D01*
X933417Y129708D01*
X933167Y129458D01*
X933083Y129167D01*
X933167Y128875D01*
X933375Y128667D01*
X933708Y128542D01*
X934000Y128500D01*
G01X937100Y131000D02*
X936767Y130917D01*
X936517Y130708D01*
X936350Y130458D01*
X936225Y130125D01*
X936183Y129750D01*
X936225Y129375D01*
X936350Y129042D01*
X936517Y128792D01*
X936767Y128583D01*
X937100Y128500D01*
X937433Y128583D01*
X937683Y128792D01*
X937850Y129042D01*
X937975Y129375D01*
X938017Y129750D01*
X937975Y130125D01*
X937850Y130458D01*
X937683Y130708D01*
X937433Y130917D01*
X937100Y131000D01*
G01X940117Y128500D02*
X940200Y129042D01*
X940325Y129500D01*
X940492Y129917D01*
X940700Y130375D01*
X941033Y131000D01*
X939367D01*
G01X917800Y131953D02*
Y127953D01*
X925200D01*
G01X929567Y156567D02*
Y159067D01*
X930608D01*
X930942Y158942D01*
X931150Y158775D01*
X931233Y158442D01*
X931150Y158109D01*
X930900Y157900D01*
X930608Y157775D01*
X929567D01*
G01X930608D02*
X931233Y156567D01*
G01X932792Y156859D02*
X933083Y156650D01*
X933417Y156567D01*
X933750Y156650D01*
X934042Y156900D01*
X934250Y157275D01*
X934333Y157650D01*
Y158109D01*
X934250Y158484D01*
X934042Y158817D01*
X933792Y158984D01*
X933500Y159067D01*
X933167Y158984D01*
X932917Y158817D01*
X932750Y158567D01*
X932667Y158234D01*
X932750Y157942D01*
X932958Y157650D01*
X933208Y157484D01*
X933500Y157442D01*
X933833Y157525D01*
X934083Y157734D01*
X934333Y158109D01*
G01X936600Y156567D02*
X936892Y156609D01*
X937225Y156734D01*
X937433Y156942D01*
X937517Y157234D01*
X937433Y157525D01*
X937183Y157775D01*
X936808Y157900D01*
X936392D01*
X936142Y157984D01*
X935933Y158192D01*
X935850Y158484D01*
X935975Y158775D01*
X936267Y158984D01*
X936600Y159067D01*
X936933Y158984D01*
X937225Y158775D01*
X937350Y158484D01*
X937267Y158192D01*
X937058Y157984D01*
X936808Y157900D01*
X936392D01*
X936017Y157775D01*
X935767Y157525D01*
X935683Y157234D01*
X935767Y156942D01*
X935975Y156734D01*
X936308Y156609D01*
X936600Y156567D01*
G01X938992Y156859D02*
X939283Y156650D01*
X939617Y156567D01*
X939950Y156650D01*
X940242Y156900D01*
X940450Y157275D01*
X940533Y157650D01*
Y158109D01*
X940450Y158484D01*
X940242Y158817D01*
X939992Y158984D01*
X939700Y159067D01*
X939367Y158984D01*
X939117Y158817D01*
X938950Y158567D01*
X938867Y158234D01*
X938950Y157942D01*
X939158Y157650D01*
X939408Y157484D01*
X939700Y157442D01*
X940033Y157525D01*
X940283Y157734D01*
X940533Y158109D01*
G01X942008Y157609D02*
X942300Y157900D01*
X942550Y158067D01*
X942883Y158150D01*
X943175Y158067D01*
X943383Y157900D01*
X943550Y157650D01*
X943592Y157359D01*
X943550Y157109D01*
X943383Y156859D01*
X943133Y156650D01*
X942842Y156567D01*
X942508Y156650D01*
X942217Y156900D01*
X942050Y157275D01*
X942008Y157692D01*
X942092Y158234D01*
X942217Y158525D01*
X942425Y158817D01*
X942717Y159025D01*
X943008Y159067D01*
X943300Y158984D01*
X943508Y158775D01*
G01X925200Y153500D02*
Y157500D01*
X917800D01*
G01X929767Y162100D02*
Y164600D01*
X930808D01*
X931142Y164475D01*
X931350Y164308D01*
X931433Y163975D01*
X931350Y163642D01*
X931100Y163433D01*
X930808Y163308D01*
X929767D01*
G01X930808D02*
X931433Y162100D01*
G01X932992Y162392D02*
X933283Y162183D01*
X933617Y162100D01*
X933950Y162183D01*
X934242Y162433D01*
X934450Y162808D01*
X934533Y163183D01*
Y163642D01*
X934450Y164017D01*
X934242Y164350D01*
X933992Y164517D01*
X933700Y164600D01*
X933367Y164517D01*
X933117Y164350D01*
X932950Y164100D01*
X932867Y163767D01*
X932950Y163475D01*
X933158Y163183D01*
X933408Y163017D01*
X933700Y162975D01*
X934033Y163058D01*
X934283Y163267D01*
X934533Y163642D01*
G01X937300Y162100D02*
Y164600D01*
X935758Y162808D01*
X937842D01*
G01X939900Y164600D02*
X939567Y164517D01*
X939317Y164308D01*
X939150Y164058D01*
X939025Y163725D01*
X938983Y163350D01*
X939025Y162975D01*
X939150Y162642D01*
X939317Y162392D01*
X939567Y162183D01*
X939900Y162100D01*
X940233Y162183D01*
X940483Y162392D01*
X940650Y162642D01*
X940775Y162975D01*
X940817Y163350D01*
X940775Y163725D01*
X940650Y164058D01*
X940483Y164308D01*
X940233Y164517D01*
X939900Y164600D01*
G01X943000Y162100D02*
X943292Y162142D01*
X943625Y162267D01*
X943833Y162475D01*
X943917Y162767D01*
X943833Y163058D01*
X943583Y163308D01*
X943208Y163433D01*
X942792D01*
X942542Y163517D01*
X942333Y163725D01*
X942250Y164017D01*
X942375Y164308D01*
X942667Y164517D01*
X943000Y164600D01*
X943333Y164517D01*
X943625Y164308D01*
X943750Y164017D01*
X943667Y163725D01*
X943458Y163517D01*
X943208Y163433D01*
X942792D01*
X942417Y163308D01*
X942167Y163058D01*
X942083Y162767D01*
X942167Y162475D01*
X942375Y162267D01*
X942708Y162142D01*
X943000Y162100D01*
G01X925200Y158000D02*
Y162000D01*
X917800D01*
G01X912000Y362100D02*
Y375100D01*
G01X919175Y555533D02*
X919508Y555325D01*
X919883Y555200D01*
X920217D01*
X920550Y555325D01*
X920800Y555533D01*
X920925Y555825D01*
X920842Y556117D01*
X920633Y556367D01*
X920258Y556533D01*
X919758Y556617D01*
X919467Y556783D01*
X919342Y557075D01*
X919425Y557367D01*
X919633Y557575D01*
X919925Y557700D01*
X920217D01*
X920508Y557617D01*
X920758Y557408D01*
G01X922233Y555200D02*
Y557700D01*
X923067D01*
X923400Y557575D01*
X923650Y557408D01*
X923858Y557158D01*
X924025Y556867D01*
X924067Y556450D01*
X924025Y556033D01*
X923858Y555742D01*
X923650Y555492D01*
X923400Y555325D01*
X923067Y555200D01*
X922233D01*
G01X925333D02*
Y557700D01*
X926167D01*
X926500Y557575D01*
X926750Y557408D01*
X926958Y557158D01*
X927125Y556867D01*
X927167Y556450D01*
X927125Y556033D01*
X926958Y555742D01*
X926750Y555492D01*
X926500Y555325D01*
X926167Y555200D01*
X925333D01*
G01X931408D02*
X932450Y557700D01*
X933492Y555200D01*
G01X933117Y556075D02*
X931783D01*
G01X936467Y557492D02*
X936217Y557617D01*
X935925Y557700D01*
X935592D01*
X935217Y557575D01*
X934925Y557367D01*
X934717Y557117D01*
X934550Y556700D01*
X934508Y556325D01*
X934592Y555950D01*
X934717Y555700D01*
X934967Y555450D01*
X935258Y555283D01*
X935550Y555200D01*
X935842D01*
X936133Y555283D01*
X936383Y555408D01*
X936592Y555575D01*
G01X938650Y557700D02*
Y555200D01*
G01X937692Y557700D02*
X939608D01*
G01X940833Y555700D02*
X941083Y555408D01*
X941417Y555242D01*
X941792Y555200D01*
X942125Y555242D01*
X942458Y555450D01*
X942667Y555700D01*
X942708Y555950D01*
X942625Y556242D01*
X942333Y556450D01*
X942042Y556533D01*
X941667D01*
G01X942042D02*
X942292Y556658D01*
X942500Y556867D01*
X942583Y557117D01*
X942500Y557367D01*
X942292Y557575D01*
X941917Y557700D01*
X941542Y557658D01*
X941167Y557492D01*
G01X936700Y543200D02*
X936658Y542867D01*
X936492Y542575D01*
X936242Y542325D01*
X935950Y542158D01*
X935617Y542075D01*
X935283D01*
X934950Y542158D01*
X934658Y542325D01*
X934408Y542575D01*
X934242Y542867D01*
X934200Y543200D01*
X934242Y543533D01*
X934408Y543825D01*
X934658Y544075D01*
X934950Y544242D01*
X935283Y544325D01*
X935617D01*
X935950Y544242D01*
X936242Y544075D01*
X936492Y543825D01*
X936658Y543533D01*
X936700Y543200D01*
G01X936033Y543533D02*
X936700Y544033D01*
G01Y546800D02*
X934200D01*
X935992Y545258D01*
Y547342D01*
G01X936200Y548483D02*
X936492Y548733D01*
X936658Y549067D01*
X936700Y549442D01*
X936658Y549775D01*
X936450Y550108D01*
X936200Y550317D01*
X935950Y550358D01*
X935658Y550275D01*
X935450Y549983D01*
X935367Y549692D01*
Y549317D01*
G01Y549692D02*
X935242Y549942D01*
X935033Y550150D01*
X934783Y550233D01*
X934533Y550150D01*
X934325Y549942D01*
X934200Y549567D01*
X934242Y549192D01*
X934408Y548817D01*
G01X927000Y553465D02*
X914000D01*
G01D02*
Y539465D01*
G01D02*
X927000D01*
G01D02*
Y553465D01*
G01X926967Y533500D02*
Y536000D01*
X928008D01*
X928342Y535875D01*
X928550Y535708D01*
X928633Y535375D01*
X928550Y535042D01*
X928300Y534833D01*
X928008Y534708D01*
X926967D01*
G01X928008D02*
X928633Y533500D01*
G01X930192Y533792D02*
X930483Y533583D01*
X930817Y533500D01*
X931150Y533583D01*
X931442Y533833D01*
X931650Y534208D01*
X931733Y534583D01*
Y535042D01*
X931650Y535417D01*
X931442Y535750D01*
X931192Y535917D01*
X930900Y536000D01*
X930567Y535917D01*
X930317Y535750D01*
X930150Y535500D01*
X930067Y535167D01*
X930150Y534875D01*
X930358Y534583D01*
X930608Y534417D01*
X930900Y534375D01*
X931233Y534458D01*
X931483Y534667D01*
X931733Y535042D01*
G01X934000Y533500D02*
X934292Y533542D01*
X934625Y533667D01*
X934833Y533875D01*
X934917Y534167D01*
X934833Y534458D01*
X934583Y534708D01*
X934208Y534833D01*
X933792D01*
X933542Y534917D01*
X933333Y535125D01*
X933250Y535417D01*
X933375Y535708D01*
X933667Y535917D01*
X934000Y536000D01*
X934333Y535917D01*
X934625Y535708D01*
X934750Y535417D01*
X934667Y535125D01*
X934458Y534917D01*
X934208Y534833D01*
X933792D01*
X933417Y534708D01*
X933167Y534458D01*
X933083Y534167D01*
X933167Y533875D01*
X933375Y533667D01*
X933708Y533542D01*
X934000Y533500D01*
G01X937100Y536000D02*
X936767Y535917D01*
X936517Y535708D01*
X936350Y535458D01*
X936225Y535125D01*
X936183Y534750D01*
X936225Y534375D01*
X936350Y534042D01*
X936517Y533792D01*
X936767Y533583D01*
X937100Y533500D01*
X937433Y533583D01*
X937683Y533792D01*
X937850Y534042D01*
X937975Y534375D01*
X938017Y534750D01*
X937975Y535125D01*
X937850Y535458D01*
X937683Y535708D01*
X937433Y535917D01*
X937100Y536000D01*
G01X940200Y533500D02*
Y536000D01*
X939700Y535500D01*
G01Y533500D02*
X940700D01*
G01X917800Y537465D02*
Y533465D01*
X925200D01*
G01X929067Y567900D02*
Y570400D01*
X930108D01*
X930442Y570275D01*
X930650Y570108D01*
X930733Y569775D01*
X930650Y569442D01*
X930400Y569233D01*
X930108Y569108D01*
X929067D01*
G01X930108D02*
X930733Y567900D01*
G01X932292Y568192D02*
X932583Y567983D01*
X932917Y567900D01*
X933250Y567983D01*
X933542Y568233D01*
X933750Y568608D01*
X933833Y568983D01*
Y569442D01*
X933750Y569817D01*
X933542Y570150D01*
X933292Y570317D01*
X933000Y570400D01*
X932667Y570317D01*
X932417Y570150D01*
X932250Y569900D01*
X932167Y569567D01*
X932250Y569275D01*
X932458Y568983D01*
X932708Y568817D01*
X933000Y568775D01*
X933333Y568858D01*
X933583Y569067D01*
X933833Y569442D01*
G01X936600Y567900D02*
Y570400D01*
X935058Y568608D01*
X937142D01*
G01X939700Y567900D02*
Y570400D01*
X938158Y568608D01*
X940242D01*
G01X941508Y569983D02*
X941758Y570233D01*
X942050Y570358D01*
X942383Y570400D01*
X942800Y570317D01*
X943092Y570108D01*
X943175Y569858D01*
X943133Y569608D01*
X942967Y569400D01*
X942133Y568983D01*
X941758Y568692D01*
X941508Y568275D01*
X941425Y567900D01*
X943175D01*
G01X925200Y567965D02*
Y571965D01*
X917800D01*
G01X929067Y559900D02*
Y562400D01*
X930108D01*
X930442Y562275D01*
X930650Y562108D01*
X930733Y561775D01*
X930650Y561442D01*
X930400Y561233D01*
X930108Y561108D01*
X929067D01*
G01X930108D02*
X930733Y559900D01*
G01X932292Y560192D02*
X932583Y559983D01*
X932917Y559900D01*
X933250Y559983D01*
X933542Y560233D01*
X933750Y560608D01*
X933833Y560983D01*
Y561442D01*
X933750Y561817D01*
X933542Y562150D01*
X933292Y562317D01*
X933000Y562400D01*
X932667Y562317D01*
X932417Y562150D01*
X932250Y561900D01*
X932167Y561567D01*
X932250Y561275D01*
X932458Y560983D01*
X932708Y560817D01*
X933000Y560775D01*
X933333Y560858D01*
X933583Y561067D01*
X933833Y561442D01*
G01X936100Y559900D02*
X936392Y559942D01*
X936725Y560067D01*
X936933Y560275D01*
X937017Y560567D01*
X936933Y560858D01*
X936683Y561108D01*
X936308Y561233D01*
X935892D01*
X935642Y561317D01*
X935433Y561525D01*
X935350Y561817D01*
X935475Y562108D01*
X935767Y562317D01*
X936100Y562400D01*
X936433Y562317D01*
X936725Y562108D01*
X936850Y561817D01*
X936767Y561525D01*
X936558Y561317D01*
X936308Y561233D01*
X935892D01*
X935517Y561108D01*
X935267Y560858D01*
X935183Y560567D01*
X935267Y560275D01*
X935475Y560067D01*
X935808Y559942D01*
X936100Y559900D01*
G01X938492Y560192D02*
X938783Y559983D01*
X939117Y559900D01*
X939450Y559983D01*
X939742Y560233D01*
X939950Y560608D01*
X940033Y560983D01*
Y561442D01*
X939950Y561817D01*
X939742Y562150D01*
X939492Y562317D01*
X939200Y562400D01*
X938867Y562317D01*
X938617Y562150D01*
X938450Y561900D01*
X938367Y561567D01*
X938450Y561275D01*
X938658Y560983D01*
X938908Y560817D01*
X939200Y560775D01*
X939533Y560858D01*
X939783Y561067D01*
X940033Y561442D01*
G01X941383Y560275D02*
X941633Y560067D01*
X941925Y559942D01*
X942300Y559900D01*
X942675Y559983D01*
X942967Y560150D01*
X943175Y560442D01*
X943217Y560775D01*
X943133Y561108D01*
X942925Y561317D01*
X942633Y561483D01*
X942342Y561525D01*
X942050Y561483D01*
X941675Y561317D01*
X941800Y562400D01*
X942925D01*
G01X925200Y559000D02*
Y563000D01*
X917800D01*
G01X929067Y563900D02*
Y566400D01*
X930108D01*
X930442Y566275D01*
X930650Y566108D01*
X930733Y565775D01*
X930650Y565442D01*
X930400Y565233D01*
X930108Y565108D01*
X929067D01*
G01X930108D02*
X930733Y563900D01*
G01X932292Y564192D02*
X932583Y563983D01*
X932917Y563900D01*
X933250Y563983D01*
X933542Y564233D01*
X933750Y564608D01*
X933833Y564983D01*
Y565442D01*
X933750Y565817D01*
X933542Y566150D01*
X933292Y566317D01*
X933000Y566400D01*
X932667Y566317D01*
X932417Y566150D01*
X932250Y565900D01*
X932167Y565567D01*
X932250Y565275D01*
X932458Y564983D01*
X932708Y564817D01*
X933000Y564775D01*
X933333Y564858D01*
X933583Y565067D01*
X933833Y565442D01*
G01X936600Y563900D02*
Y566400D01*
X935058Y564608D01*
X937142D01*
G01X939700Y563900D02*
Y566400D01*
X938158Y564608D01*
X940242D01*
G01X941383Y564400D02*
X941633Y564108D01*
X941967Y563942D01*
X942342Y563900D01*
X942675Y563942D01*
X943008Y564150D01*
X943217Y564400D01*
X943258Y564650D01*
X943175Y564942D01*
X942883Y565150D01*
X942592Y565233D01*
X942217D01*
G01X942592D02*
X942842Y565358D01*
X943050Y565567D01*
X943133Y565817D01*
X943050Y566067D01*
X942842Y566275D01*
X942467Y566400D01*
X942092Y566358D01*
X941717Y566192D01*
G01X925200Y563500D02*
Y567500D01*
X917800D01*
G01X917575Y961033D02*
X917908Y960825D01*
X918283Y960700D01*
X918617D01*
X918950Y960825D01*
X919200Y961033D01*
X919325Y961325D01*
X919242Y961617D01*
X919033Y961867D01*
X918658Y962033D01*
X918158Y962117D01*
X917867Y962283D01*
X917742Y962575D01*
X917825Y962867D01*
X918033Y963075D01*
X918325Y963200D01*
X918617D01*
X918908Y963117D01*
X919158Y962908D01*
G01X920633Y960700D02*
Y963200D01*
X921467D01*
X921800Y963075D01*
X922050Y962908D01*
X922258Y962658D01*
X922425Y962367D01*
X922467Y961950D01*
X922425Y961533D01*
X922258Y961242D01*
X922050Y960992D01*
X921800Y960825D01*
X921467Y960700D01*
X920633D01*
G01X923733D02*
Y963200D01*
X924567D01*
X924900Y963075D01*
X925150Y962908D01*
X925358Y962658D01*
X925525Y962367D01*
X925567Y961950D01*
X925525Y961533D01*
X925358Y961242D01*
X925150Y960992D01*
X924900Y960825D01*
X924567Y960700D01*
X923733D01*
G01X929808D02*
X930850Y963200D01*
X931892Y960700D01*
G01X931517Y961575D02*
X930183D01*
G01X934867Y962992D02*
X934617Y963117D01*
X934325Y963200D01*
X933992D01*
X933617Y963075D01*
X933325Y962867D01*
X933117Y962617D01*
X932950Y962200D01*
X932908Y961825D01*
X932992Y961450D01*
X933117Y961200D01*
X933367Y960950D01*
X933658Y960783D01*
X933950Y960700D01*
X934242D01*
X934533Y960783D01*
X934783Y960908D01*
X934992Y961075D01*
G01X937050Y963200D02*
Y960700D01*
G01X936092Y963200D02*
X938008D01*
G01X939358Y962783D02*
X939608Y963033D01*
X939900Y963158D01*
X940233Y963200D01*
X940650Y963117D01*
X940942Y962908D01*
X941025Y962658D01*
X940983Y962408D01*
X940817Y962200D01*
X939983Y961783D01*
X939608Y961492D01*
X939358Y961075D01*
X939275Y960700D01*
X941025D01*
G01X936600Y948400D02*
X936558Y948067D01*
X936392Y947775D01*
X936142Y947525D01*
X935850Y947358D01*
X935517Y947275D01*
X935183D01*
X934850Y947358D01*
X934558Y947525D01*
X934308Y947775D01*
X934142Y948067D01*
X934100Y948400D01*
X934142Y948733D01*
X934308Y949025D01*
X934558Y949275D01*
X934850Y949442D01*
X935183Y949525D01*
X935517D01*
X935850Y949442D01*
X936142Y949275D01*
X936392Y949025D01*
X936558Y948733D01*
X936600Y948400D01*
G01X935933Y948733D02*
X936600Y949233D01*
G01X936100Y950583D02*
X936392Y950833D01*
X936558Y951167D01*
X936600Y951542D01*
X936558Y951875D01*
X936350Y952208D01*
X936100Y952417D01*
X935850Y952458D01*
X935558Y952375D01*
X935350Y952083D01*
X935267Y951792D01*
Y951417D01*
G01Y951792D02*
X935142Y952042D01*
X934933Y952250D01*
X934683Y952333D01*
X934433Y952250D01*
X934225Y952042D01*
X934100Y951667D01*
X934142Y951292D01*
X934308Y950917D01*
G01X936600Y954600D02*
X936558Y954892D01*
X936433Y955225D01*
X936225Y955433D01*
X935933Y955517D01*
X935642Y955433D01*
X935392Y955183D01*
X935267Y954808D01*
Y954392D01*
X935183Y954142D01*
X934975Y953933D01*
X934683Y953850D01*
X934392Y953975D01*
X934183Y954267D01*
X934100Y954600D01*
X934183Y954933D01*
X934392Y955225D01*
X934683Y955350D01*
X934975Y955267D01*
X935183Y955058D01*
X935267Y954808D01*
Y954392D01*
X935392Y954017D01*
X935642Y953767D01*
X935933Y953683D01*
X936225Y953767D01*
X936433Y953975D01*
X936558Y954308D01*
X936600Y954600D01*
G01X927000Y958977D02*
X914000D01*
G01D02*
Y944977D01*
G01D02*
X927000D01*
G01D02*
Y958977D01*
G01X929767Y973900D02*
Y976400D01*
X930808D01*
X931142Y976275D01*
X931350Y976108D01*
X931433Y975775D01*
X931350Y975442D01*
X931100Y975233D01*
X930808Y975108D01*
X929767D01*
G01X930808D02*
X931433Y973900D01*
G01X932992Y974192D02*
X933283Y973983D01*
X933617Y973900D01*
X933950Y973983D01*
X934242Y974233D01*
X934450Y974608D01*
X934533Y974983D01*
Y975442D01*
X934450Y975817D01*
X934242Y976150D01*
X933992Y976317D01*
X933700Y976400D01*
X933367Y976317D01*
X933117Y976150D01*
X932950Y975900D01*
X932867Y975567D01*
X932950Y975275D01*
X933158Y974983D01*
X933408Y974817D01*
X933700Y974775D01*
X934033Y974858D01*
X934283Y975067D01*
X934533Y975442D01*
G01X937300Y973900D02*
Y976400D01*
X935758Y974608D01*
X937842D01*
G01X939900Y976400D02*
X939567Y976317D01*
X939317Y976108D01*
X939150Y975858D01*
X939025Y975525D01*
X938983Y975150D01*
X939025Y974775D01*
X939150Y974442D01*
X939317Y974192D01*
X939567Y973983D01*
X939900Y973900D01*
X940233Y973983D01*
X940483Y974192D01*
X940650Y974442D01*
X940775Y974775D01*
X940817Y975150D01*
X940775Y975525D01*
X940650Y975858D01*
X940483Y976108D01*
X940233Y976317D01*
X939900Y976400D01*
G01X943000D02*
X942667Y976317D01*
X942417Y976108D01*
X942250Y975858D01*
X942125Y975525D01*
X942083Y975150D01*
X942125Y974775D01*
X942250Y974442D01*
X942417Y974192D01*
X942667Y973983D01*
X943000Y973900D01*
X943333Y973983D01*
X943583Y974192D01*
X943750Y974442D01*
X943875Y974775D01*
X943917Y975150D01*
X943875Y975525D01*
X943750Y975858D01*
X943583Y976108D01*
X943333Y976317D01*
X943000Y976400D01*
G01X925200Y973477D02*
Y977477D01*
X917800D01*
G01X914967Y935500D02*
Y938000D01*
X916008D01*
X916342Y937875D01*
X916550Y937708D01*
X916633Y937375D01*
X916550Y937042D01*
X916300Y936833D01*
X916008Y936708D01*
X914967D01*
G01X916008D02*
X916633Y935500D01*
G01X918192Y935792D02*
X918483Y935583D01*
X918817Y935500D01*
X919150Y935583D01*
X919442Y935833D01*
X919650Y936208D01*
X919733Y936583D01*
Y937042D01*
X919650Y937417D01*
X919442Y937750D01*
X919192Y937917D01*
X918900Y938000D01*
X918567Y937917D01*
X918317Y937750D01*
X918150Y937500D01*
X918067Y937167D01*
X918150Y936875D01*
X918358Y936583D01*
X918608Y936417D01*
X918900Y936375D01*
X919233Y936458D01*
X919483Y936667D01*
X919733Y937042D01*
G01X921917Y935500D02*
X922000Y936042D01*
X922125Y936500D01*
X922292Y936917D01*
X922500Y937375D01*
X922833Y938000D01*
X921167D01*
G01X924392Y935792D02*
X924683Y935583D01*
X925017Y935500D01*
X925350Y935583D01*
X925642Y935833D01*
X925850Y936208D01*
X925933Y936583D01*
Y937042D01*
X925850Y937417D01*
X925642Y937750D01*
X925392Y937917D01*
X925100Y938000D01*
X924767Y937917D01*
X924517Y937750D01*
X924350Y937500D01*
X924267Y937167D01*
X924350Y936875D01*
X924558Y936583D01*
X924808Y936417D01*
X925100Y936375D01*
X925433Y936458D01*
X925683Y936667D01*
X925933Y937042D01*
G01X927283Y935875D02*
X927533Y935667D01*
X927825Y935542D01*
X928200Y935500D01*
X928575Y935583D01*
X928867Y935750D01*
X929075Y936042D01*
X929117Y936375D01*
X929033Y936708D01*
X928825Y936917D01*
X928533Y937083D01*
X928242Y937125D01*
X927950Y937083D01*
X927575Y936917D01*
X927700Y938000D01*
X928825D01*
G01X917800Y942977D02*
Y938977D01*
X925200D01*
G01X929767Y965900D02*
Y968400D01*
X930808D01*
X931142Y968275D01*
X931350Y968108D01*
X931433Y967775D01*
X931350Y967442D01*
X931100Y967233D01*
X930808Y967108D01*
X929767D01*
G01X930808D02*
X931433Y965900D01*
G01X932992Y966192D02*
X933283Y965983D01*
X933617Y965900D01*
X933950Y965983D01*
X934242Y966233D01*
X934450Y966608D01*
X934533Y966983D01*
Y967442D01*
X934450Y967817D01*
X934242Y968150D01*
X933992Y968317D01*
X933700Y968400D01*
X933367Y968317D01*
X933117Y968150D01*
X932950Y967900D01*
X932867Y967567D01*
X932950Y967275D01*
X933158Y966983D01*
X933408Y966817D01*
X933700Y966775D01*
X934033Y966858D01*
X934283Y967067D01*
X934533Y967442D01*
G01X936800Y965900D02*
X937092Y965942D01*
X937425Y966067D01*
X937633Y966275D01*
X937717Y966567D01*
X937633Y966858D01*
X937383Y967108D01*
X937008Y967233D01*
X936592D01*
X936342Y967317D01*
X936133Y967525D01*
X936050Y967817D01*
X936175Y968108D01*
X936467Y968317D01*
X936800Y968400D01*
X937133Y968317D01*
X937425Y968108D01*
X937550Y967817D01*
X937467Y967525D01*
X937258Y967317D01*
X937008Y967233D01*
X936592D01*
X936217Y967108D01*
X935967Y966858D01*
X935883Y966567D01*
X935967Y966275D01*
X936175Y966067D01*
X936508Y965942D01*
X936800Y965900D01*
G01X939192Y966192D02*
X939483Y965983D01*
X939817Y965900D01*
X940150Y965983D01*
X940442Y966233D01*
X940650Y966608D01*
X940733Y966983D01*
Y967442D01*
X940650Y967817D01*
X940442Y968150D01*
X940192Y968317D01*
X939900Y968400D01*
X939567Y968317D01*
X939317Y968150D01*
X939150Y967900D01*
X939067Y967567D01*
X939150Y967275D01*
X939358Y966983D01*
X939608Y966817D01*
X939900Y966775D01*
X940233Y966858D01*
X940483Y967067D01*
X940733Y967442D01*
G01X943500Y965900D02*
Y968400D01*
X941958Y966608D01*
X944042D01*
G01X925200Y964500D02*
Y968500D01*
X917800D01*
G01X929767Y969900D02*
Y972400D01*
X930808D01*
X931142Y972275D01*
X931350Y972108D01*
X931433Y971775D01*
X931350Y971442D01*
X931100Y971233D01*
X930808Y971108D01*
X929767D01*
G01X930808D02*
X931433Y969900D01*
G01X932992Y970192D02*
X933283Y969983D01*
X933617Y969900D01*
X933950Y969983D01*
X934242Y970233D01*
X934450Y970608D01*
X934533Y970983D01*
Y971442D01*
X934450Y971817D01*
X934242Y972150D01*
X933992Y972317D01*
X933700Y972400D01*
X933367Y972317D01*
X933117Y972150D01*
X932950Y971900D01*
X932867Y971567D01*
X932950Y971275D01*
X933158Y970983D01*
X933408Y970817D01*
X933700Y970775D01*
X934033Y970858D01*
X934283Y971067D01*
X934533Y971442D01*
G01X937300Y969900D02*
Y972400D01*
X935758Y970608D01*
X937842D01*
G01X939900Y972400D02*
X939567Y972317D01*
X939317Y972108D01*
X939150Y971858D01*
X939025Y971525D01*
X938983Y971150D01*
X939025Y970775D01*
X939150Y970442D01*
X939317Y970192D01*
X939567Y969983D01*
X939900Y969900D01*
X940233Y969983D01*
X940483Y970192D01*
X940650Y970442D01*
X940775Y970775D01*
X940817Y971150D01*
X940775Y971525D01*
X940650Y971858D01*
X940483Y972108D01*
X940233Y972317D01*
X939900Y972400D01*
G01X943000Y969900D02*
Y972400D01*
X942500Y971900D01*
G01Y969900D02*
X943500D01*
G01X925200Y969000D02*
Y973000D01*
X917800D01*
G01X915800Y1174100D02*
Y1187100D01*
G01X936800Y1354000D02*
X936758Y1353667D01*
X936592Y1353375D01*
X936342Y1353125D01*
X936050Y1352958D01*
X935717Y1352875D01*
X935383D01*
X935050Y1352958D01*
X934758Y1353125D01*
X934508Y1353375D01*
X934342Y1353667D01*
X934300Y1354000D01*
X934342Y1354333D01*
X934508Y1354625D01*
X934758Y1354875D01*
X935050Y1355042D01*
X935383Y1355125D01*
X935717D01*
X936050Y1355042D01*
X936342Y1354875D01*
X936592Y1354625D01*
X936758Y1354333D01*
X936800Y1354000D01*
G01X936133Y1354333D02*
X936800Y1354833D01*
G01X936300Y1356183D02*
X936592Y1356433D01*
X936758Y1356767D01*
X936800Y1357142D01*
X936758Y1357475D01*
X936550Y1357808D01*
X936300Y1358017D01*
X936050Y1358058D01*
X935758Y1357975D01*
X935550Y1357683D01*
X935467Y1357392D01*
Y1357017D01*
G01Y1357392D02*
X935342Y1357642D01*
X935133Y1357850D01*
X934883Y1357933D01*
X934633Y1357850D01*
X934425Y1357642D01*
X934300Y1357267D01*
X934342Y1356892D01*
X934508Y1356517D01*
G01X936300Y1359283D02*
X936592Y1359533D01*
X936758Y1359867D01*
X936800Y1360242D01*
X936758Y1360575D01*
X936550Y1360908D01*
X936300Y1361117D01*
X936050Y1361158D01*
X935758Y1361075D01*
X935550Y1360783D01*
X935467Y1360492D01*
Y1360117D01*
G01Y1360492D02*
X935342Y1360742D01*
X935133Y1360950D01*
X934883Y1361033D01*
X934633Y1360950D01*
X934425Y1360742D01*
X934300Y1360367D01*
X934342Y1359992D01*
X934508Y1359617D01*
G01X914000Y1364488D02*
Y1350488D01*
G01D02*
X927000D01*
G01D02*
Y1364488D01*
G01X927967Y1345000D02*
Y1347500D01*
X929008D01*
X929342Y1347375D01*
X929550Y1347208D01*
X929633Y1346875D01*
X929550Y1346542D01*
X929300Y1346333D01*
X929008Y1346208D01*
X927967D01*
G01X929008D02*
X929633Y1345000D01*
G01X931192Y1345292D02*
X931483Y1345083D01*
X931817Y1345000D01*
X932150Y1345083D01*
X932442Y1345333D01*
X932650Y1345708D01*
X932733Y1346083D01*
Y1346542D01*
X932650Y1346917D01*
X932442Y1347250D01*
X932192Y1347417D01*
X931900Y1347500D01*
X931567Y1347417D01*
X931317Y1347250D01*
X931150Y1347000D01*
X931067Y1346667D01*
X931150Y1346375D01*
X931358Y1346083D01*
X931608Y1345917D01*
X931900Y1345875D01*
X932233Y1345958D01*
X932483Y1346167D01*
X932733Y1346542D01*
G01X934917Y1345000D02*
X935000Y1345542D01*
X935125Y1346000D01*
X935292Y1346417D01*
X935500Y1346875D01*
X935833Y1347500D01*
X934167D01*
G01X938100Y1345000D02*
X938392Y1345042D01*
X938725Y1345167D01*
X938933Y1345375D01*
X939017Y1345667D01*
X938933Y1345958D01*
X938683Y1346208D01*
X938308Y1346333D01*
X937892D01*
X937642Y1346417D01*
X937433Y1346625D01*
X937350Y1346917D01*
X937475Y1347208D01*
X937767Y1347417D01*
X938100Y1347500D01*
X938433Y1347417D01*
X938725Y1347208D01*
X938850Y1346917D01*
X938767Y1346625D01*
X938558Y1346417D01*
X938308Y1346333D01*
X937892D01*
X937517Y1346208D01*
X937267Y1345958D01*
X937183Y1345667D01*
X937267Y1345375D01*
X937475Y1345167D01*
X937808Y1345042D01*
X938100Y1345000D01*
G01X941117D02*
X941200Y1345542D01*
X941325Y1346000D01*
X941492Y1346417D01*
X941700Y1346875D01*
X942033Y1347500D01*
X940367D01*
G01X917800Y1348488D02*
Y1344488D01*
X925200D01*
G01X986500Y1389617D02*
X984000D01*
Y1390617D01*
X984125Y1390950D01*
X984417Y1391200D01*
X984750Y1391283D01*
X985083Y1391200D01*
X985333Y1390992D01*
X985458Y1390617D01*
Y1389617D01*
G01X984208Y1394467D02*
X984083Y1394217D01*
X984000Y1393925D01*
Y1393592D01*
X984125Y1393217D01*
X984333Y1392925D01*
X984583Y1392717D01*
X985000Y1392550D01*
X985375Y1392508D01*
X985750Y1392592D01*
X986000Y1392717D01*
X986250Y1392967D01*
X986417Y1393258D01*
X986500Y1393550D01*
Y1393842D01*
X986417Y1394133D01*
X986292Y1394383D01*
X986125Y1394592D01*
G01X986500Y1396650D02*
X984000D01*
X984500Y1396150D01*
G01X986500D02*
Y1397150D01*
G01X984417Y1398958D02*
X984167Y1399208D01*
X984042Y1399500D01*
X984000Y1399833D01*
X984083Y1400250D01*
X984292Y1400542D01*
X984542Y1400625D01*
X984792Y1400583D01*
X985000Y1400417D01*
X985417Y1399583D01*
X985708Y1399208D01*
X986125Y1398958D01*
X986500Y1398875D01*
Y1400625D01*
G01X986208Y1402142D02*
X986417Y1402433D01*
X986500Y1402767D01*
X986417Y1403100D01*
X986167Y1403392D01*
X985792Y1403600D01*
X985417Y1403683D01*
X984958D01*
X984583Y1403600D01*
X984250Y1403392D01*
X984083Y1403142D01*
X984000Y1402850D01*
X984083Y1402517D01*
X984250Y1402267D01*
X984500Y1402100D01*
X984833Y1402017D01*
X985125Y1402100D01*
X985417Y1402308D01*
X985583Y1402558D01*
X985625Y1402850D01*
X985542Y1403183D01*
X985333Y1403433D01*
X984958Y1403683D01*
G01X984000Y1405950D02*
X984083Y1405617D01*
X984292Y1405367D01*
X984542Y1405200D01*
X984875Y1405075D01*
X985250Y1405033D01*
X985625Y1405075D01*
X985958Y1405200D01*
X986208Y1405367D01*
X986417Y1405617D01*
X986500Y1405950D01*
X986417Y1406283D01*
X986208Y1406533D01*
X985958Y1406700D01*
X985625Y1406825D01*
X985250Y1406867D01*
X984875Y1406825D01*
X984542Y1406700D01*
X984292Y1406533D01*
X984083Y1406283D01*
X984000Y1405950D01*
G01X979800Y1428600D02*
X987800D01*
G01X979800Y1423100D02*
Y1428600D01*
G01Y1411000D02*
Y1416500D01*
G01X987800Y1411000D02*
X979800D01*
G01X927000Y1364488D02*
X914000D01*
G01X928867Y1378400D02*
Y1380900D01*
X929908D01*
X930242Y1380775D01*
X930450Y1380608D01*
X930533Y1380275D01*
X930450Y1379942D01*
X930200Y1379733D01*
X929908Y1379608D01*
X928867D01*
G01X929908D02*
X930533Y1378400D01*
G01X932092Y1378692D02*
X932383Y1378483D01*
X932717Y1378400D01*
X933050Y1378483D01*
X933342Y1378733D01*
X933550Y1379108D01*
X933633Y1379483D01*
Y1379942D01*
X933550Y1380317D01*
X933342Y1380650D01*
X933092Y1380817D01*
X932800Y1380900D01*
X932467Y1380817D01*
X932217Y1380650D01*
X932050Y1380400D01*
X931967Y1380067D01*
X932050Y1379775D01*
X932258Y1379483D01*
X932508Y1379317D01*
X932800Y1379275D01*
X933133Y1379358D01*
X933383Y1379567D01*
X933633Y1379942D01*
G01X936400Y1378400D02*
Y1380900D01*
X934858Y1379108D01*
X936942D01*
G01X939500Y1378400D02*
Y1380900D01*
X937958Y1379108D01*
X940042D01*
G01X941392Y1378692D02*
X941683Y1378483D01*
X942017Y1378400D01*
X942350Y1378483D01*
X942642Y1378733D01*
X942850Y1379108D01*
X942933Y1379483D01*
Y1379942D01*
X942850Y1380317D01*
X942642Y1380650D01*
X942392Y1380817D01*
X942100Y1380900D01*
X941767Y1380817D01*
X941517Y1380650D01*
X941350Y1380400D01*
X941267Y1380067D01*
X941350Y1379775D01*
X941558Y1379483D01*
X941808Y1379317D01*
X942100Y1379275D01*
X942433Y1379358D01*
X942683Y1379567D01*
X942933Y1379942D01*
G01X925200Y1378988D02*
Y1382988D01*
X917800D01*
G01X928867Y1370400D02*
Y1372900D01*
X929908D01*
X930242Y1372775D01*
X930450Y1372608D01*
X930533Y1372275D01*
X930450Y1371942D01*
X930200Y1371733D01*
X929908Y1371608D01*
X928867D01*
G01X929908D02*
X930533Y1370400D01*
G01X932092Y1370692D02*
X932383Y1370483D01*
X932717Y1370400D01*
X933050Y1370483D01*
X933342Y1370733D01*
X933550Y1371108D01*
X933633Y1371483D01*
Y1371942D01*
X933550Y1372317D01*
X933342Y1372650D01*
X933092Y1372817D01*
X932800Y1372900D01*
X932467Y1372817D01*
X932217Y1372650D01*
X932050Y1372400D01*
X931967Y1372067D01*
X932050Y1371775D01*
X932258Y1371483D01*
X932508Y1371317D01*
X932800Y1371275D01*
X933133Y1371358D01*
X933383Y1371567D01*
X933633Y1371942D01*
G01X935900Y1370400D02*
X936192Y1370442D01*
X936525Y1370567D01*
X936733Y1370775D01*
X936817Y1371067D01*
X936733Y1371358D01*
X936483Y1371608D01*
X936108Y1371733D01*
X935692D01*
X935442Y1371817D01*
X935233Y1372025D01*
X935150Y1372317D01*
X935275Y1372608D01*
X935567Y1372817D01*
X935900Y1372900D01*
X936233Y1372817D01*
X936525Y1372608D01*
X936650Y1372317D01*
X936567Y1372025D01*
X936358Y1371817D01*
X936108Y1371733D01*
X935692D01*
X935317Y1371608D01*
X935067Y1371358D01*
X934983Y1371067D01*
X935067Y1370775D01*
X935275Y1370567D01*
X935608Y1370442D01*
X935900Y1370400D01*
G01X938292Y1370692D02*
X938583Y1370483D01*
X938917Y1370400D01*
X939250Y1370483D01*
X939542Y1370733D01*
X939750Y1371108D01*
X939833Y1371483D01*
Y1371942D01*
X939750Y1372317D01*
X939542Y1372650D01*
X939292Y1372817D01*
X939000Y1372900D01*
X938667Y1372817D01*
X938417Y1372650D01*
X938250Y1372400D01*
X938167Y1372067D01*
X938250Y1371775D01*
X938458Y1371483D01*
X938708Y1371317D01*
X939000Y1371275D01*
X939333Y1371358D01*
X939583Y1371567D01*
X939833Y1371942D01*
G01X941183Y1370900D02*
X941433Y1370608D01*
X941767Y1370442D01*
X942142Y1370400D01*
X942475Y1370442D01*
X942808Y1370650D01*
X943017Y1370900D01*
X943058Y1371150D01*
X942975Y1371442D01*
X942683Y1371650D01*
X942392Y1371733D01*
X942017D01*
G01X942392D02*
X942642Y1371858D01*
X942850Y1372067D01*
X942933Y1372317D01*
X942850Y1372567D01*
X942642Y1372775D01*
X942267Y1372900D01*
X941892Y1372858D01*
X941517Y1372692D01*
G01X925200Y1370000D02*
Y1374000D01*
X917800D01*
G01X928867Y1374400D02*
Y1376900D01*
X929908D01*
X930242Y1376775D01*
X930450Y1376608D01*
X930533Y1376275D01*
X930450Y1375942D01*
X930200Y1375733D01*
X929908Y1375608D01*
X928867D01*
G01X929908D02*
X930533Y1374400D01*
G01X932092Y1374692D02*
X932383Y1374483D01*
X932717Y1374400D01*
X933050Y1374483D01*
X933342Y1374733D01*
X933550Y1375108D01*
X933633Y1375483D01*
Y1375942D01*
X933550Y1376317D01*
X933342Y1376650D01*
X933092Y1376817D01*
X932800Y1376900D01*
X932467Y1376817D01*
X932217Y1376650D01*
X932050Y1376400D01*
X931967Y1376067D01*
X932050Y1375775D01*
X932258Y1375483D01*
X932508Y1375317D01*
X932800Y1375275D01*
X933133Y1375358D01*
X933383Y1375567D01*
X933633Y1375942D01*
G01X936400Y1374400D02*
Y1376900D01*
X934858Y1375108D01*
X936942D01*
G01X938083Y1374775D02*
X938333Y1374567D01*
X938625Y1374442D01*
X939000Y1374400D01*
X939375Y1374483D01*
X939667Y1374650D01*
X939875Y1374942D01*
X939917Y1375275D01*
X939833Y1375608D01*
X939625Y1375817D01*
X939333Y1375983D01*
X939042Y1376025D01*
X938750Y1375983D01*
X938375Y1375817D01*
X938500Y1376900D01*
X939625D01*
G01X942100D02*
X941767Y1376817D01*
X941517Y1376608D01*
X941350Y1376358D01*
X941225Y1376025D01*
X941183Y1375650D01*
X941225Y1375275D01*
X941350Y1374942D01*
X941517Y1374692D01*
X941767Y1374483D01*
X942100Y1374400D01*
X942433Y1374483D01*
X942683Y1374692D01*
X942850Y1374942D01*
X942975Y1375275D01*
X943017Y1375650D01*
X942975Y1376025D01*
X942850Y1376358D01*
X942683Y1376608D01*
X942433Y1376817D01*
X942100Y1376900D01*
G01X925200Y1374500D02*
Y1378500D01*
X917800D01*
G01X968808Y1396867D02*
X968683Y1396617D01*
X968600Y1396325D01*
Y1395992D01*
X968725Y1395617D01*
X968933Y1395325D01*
X969183Y1395117D01*
X969600Y1394950D01*
X969975Y1394908D01*
X970350Y1394992D01*
X970600Y1395117D01*
X970850Y1395367D01*
X971017Y1395658D01*
X971100Y1395950D01*
Y1396242D01*
X971017Y1396533D01*
X970892Y1396783D01*
X970725Y1396992D01*
G01X970600Y1398133D02*
X970892Y1398383D01*
X971058Y1398717D01*
X971100Y1399092D01*
X971058Y1399425D01*
X970850Y1399758D01*
X970600Y1399967D01*
X970350Y1400008D01*
X970058Y1399925D01*
X969850Y1399633D01*
X969767Y1399342D01*
Y1398967D01*
G01Y1399342D02*
X969642Y1399592D01*
X969433Y1399800D01*
X969183Y1399883D01*
X968933Y1399800D01*
X968725Y1399592D01*
X968600Y1399217D01*
X968642Y1398842D01*
X968808Y1398467D01*
G01X971100Y1402650D02*
X968600D01*
X970392Y1401108D01*
Y1403192D01*
G01X971100Y1405250D02*
X971058Y1405542D01*
X970933Y1405875D01*
X970725Y1406083D01*
X970433Y1406167D01*
X970142Y1406083D01*
X969892Y1405833D01*
X969767Y1405458D01*
Y1405042D01*
X969683Y1404792D01*
X969475Y1404583D01*
X969183Y1404500D01*
X968892Y1404625D01*
X968683Y1404917D01*
X968600Y1405250D01*
X968683Y1405583D01*
X968892Y1405875D01*
X969183Y1406000D01*
X969475Y1405917D01*
X969683Y1405708D01*
X969767Y1405458D01*
Y1405042D01*
X969892Y1404667D01*
X970142Y1404417D01*
X970433Y1404333D01*
X970725Y1404417D01*
X970933Y1404625D01*
X971058Y1404958D01*
X971100Y1405250D01*
G01X968050Y1410350D02*
Y1429050D01*
X978350D01*
Y1410350D01*
X968050D01*
G01X964808Y1396867D02*
X964683Y1396617D01*
X964600Y1396325D01*
Y1395992D01*
X964725Y1395617D01*
X964933Y1395325D01*
X965183Y1395117D01*
X965600Y1394950D01*
X965975Y1394908D01*
X966350Y1394992D01*
X966600Y1395117D01*
X966850Y1395367D01*
X967017Y1395658D01*
X967100Y1395950D01*
Y1396242D01*
X967017Y1396533D01*
X966892Y1396783D01*
X966725Y1396992D01*
G01X966600Y1398133D02*
X966892Y1398383D01*
X967058Y1398717D01*
X967100Y1399092D01*
X967058Y1399425D01*
X966850Y1399758D01*
X966600Y1399967D01*
X966350Y1400008D01*
X966058Y1399925D01*
X965850Y1399633D01*
X965767Y1399342D01*
Y1398967D01*
G01Y1399342D02*
X965642Y1399592D01*
X965433Y1399800D01*
X965183Y1399883D01*
X964933Y1399800D01*
X964725Y1399592D01*
X964600Y1399217D01*
X964642Y1398842D01*
X964808Y1398467D01*
G01X967100Y1402650D02*
X964600D01*
X966392Y1401108D01*
Y1403192D01*
G01X966808Y1404542D02*
X967017Y1404833D01*
X967100Y1405167D01*
X967017Y1405500D01*
X966767Y1405792D01*
X966392Y1406000D01*
X966017Y1406083D01*
X965558D01*
X965183Y1406000D01*
X964850Y1405792D01*
X964683Y1405542D01*
X964600Y1405250D01*
X964683Y1404917D01*
X964850Y1404667D01*
X965100Y1404500D01*
X965433Y1404417D01*
X965725Y1404500D01*
X966017Y1404708D01*
X966183Y1404958D01*
X966225Y1405250D01*
X966142Y1405583D01*
X965933Y1405833D01*
X965558Y1406083D01*
G01X955550Y1410350D02*
Y1429050D01*
X965850D01*
Y1410350D01*
X955550D01*
G01X1037401Y1400276D02*
Y1424882D01*
X1033464Y1428819D01*
X1028149D01*
G02X1023228Y1433740I0J4921D01*
G01Y1610886D01*
X1022244Y1611870D01*
X993681D01*
G02Y1616082I0J2106D01*
G01X1022244D01*
X1023228Y1617066D01*
Y1676496D01*
G02X1028149Y1681417I4921J0D01*
G01X1033464D01*
X1037401Y1685354D01*
Y1709976D01*
X1007428D01*
Y1678726D01*
X994628D01*
Y1617076D01*
X990528D01*
Y1611876D01*
X980828D01*
Y1432676D01*
X1007428D01*
Y1400276D01*
X1037401D01*
G01X969208Y1594817D02*
X969083Y1594567D01*
X969000Y1594275D01*
Y1593942D01*
X969125Y1593567D01*
X969333Y1593275D01*
X969583Y1593067D01*
X970000Y1592900D01*
X970375Y1592858D01*
X970750Y1592942D01*
X971000Y1593067D01*
X971250Y1593317D01*
X971417Y1593608D01*
X971500Y1593900D01*
Y1594192D01*
X971417Y1594483D01*
X971292Y1594733D01*
X971125Y1594942D01*
G01X971500Y1596042D02*
X969000D01*
X971500Y1597958D01*
X969000D01*
G01X971500Y1600017D02*
X970958Y1600100D01*
X970500Y1600225D01*
X970083Y1600392D01*
X969625Y1600600D01*
X969000Y1600933D01*
Y1599267D01*
G01X954100Y1616717D02*
X951600D01*
Y1617717D01*
X951725Y1618050D01*
X952017Y1618300D01*
X952350Y1618383D01*
X952683Y1618300D01*
X952933Y1618092D01*
X953058Y1617717D01*
Y1616717D01*
G01X951808Y1621567D02*
X951683Y1621317D01*
X951600Y1621025D01*
Y1620692D01*
X951725Y1620317D01*
X951933Y1620025D01*
X952183Y1619817D01*
X952600Y1619650D01*
X952975Y1619608D01*
X953350Y1619692D01*
X953600Y1619817D01*
X953850Y1620067D01*
X954017Y1620358D01*
X954100Y1620650D01*
Y1620942D01*
X954017Y1621233D01*
X953892Y1621483D01*
X953725Y1621692D01*
G01X954100Y1623750D02*
X951600D01*
X952100Y1623250D01*
G01X954100D02*
Y1624250D01*
G01X952017Y1626058D02*
X951767Y1626308D01*
X951642Y1626600D01*
X951600Y1626933D01*
X951683Y1627350D01*
X951892Y1627642D01*
X952142Y1627725D01*
X952392Y1627683D01*
X952600Y1627517D01*
X953017Y1626683D01*
X953308Y1626308D01*
X953725Y1626058D01*
X954100Y1625975D01*
Y1627725D01*
G01Y1629950D02*
X954058Y1630242D01*
X953933Y1630575D01*
X953725Y1630783D01*
X953433Y1630867D01*
X953142Y1630783D01*
X952892Y1630533D01*
X952767Y1630158D01*
Y1629742D01*
X952683Y1629492D01*
X952475Y1629283D01*
X952183Y1629200D01*
X951892Y1629325D01*
X951683Y1629617D01*
X951600Y1629950D01*
X951683Y1630283D01*
X951892Y1630575D01*
X952183Y1630700D01*
X952475Y1630617D01*
X952683Y1630408D01*
X952767Y1630158D01*
Y1629742D01*
X952892Y1629367D01*
X953142Y1629117D01*
X953433Y1629033D01*
X953725Y1629117D01*
X953933Y1629325D01*
X954058Y1629658D01*
X954100Y1629950D01*
G01X953808Y1632342D02*
X954017Y1632633D01*
X954100Y1632967D01*
X954017Y1633300D01*
X953767Y1633592D01*
X953392Y1633800D01*
X953017Y1633883D01*
X952558D01*
X952183Y1633800D01*
X951850Y1633592D01*
X951683Y1633342D01*
X951600Y1633050D01*
X951683Y1632717D01*
X951850Y1632467D01*
X952100Y1632300D01*
X952433Y1632217D01*
X952725Y1632300D01*
X953017Y1632508D01*
X953183Y1632758D01*
X953225Y1633050D01*
X953142Y1633383D01*
X952933Y1633633D01*
X952558Y1633883D01*
G01X957900Y1643000D02*
Y1640500D01*
G01X956942Y1643000D02*
X958858D01*
G01X960167Y1640500D02*
Y1643000D01*
X961167D01*
X961500Y1642875D01*
X961750Y1642583D01*
X961833Y1642250D01*
X961750Y1641917D01*
X961542Y1641667D01*
X961167Y1641542D01*
X960167D01*
G01X963183Y1641000D02*
X963433Y1640708D01*
X963767Y1640542D01*
X964142Y1640500D01*
X964475Y1640542D01*
X964808Y1640750D01*
X965017Y1641000D01*
X965058Y1641250D01*
X964975Y1641542D01*
X964683Y1641750D01*
X964392Y1641833D01*
X964017D01*
G01X964392D02*
X964642Y1641958D01*
X964850Y1642167D01*
X964933Y1642417D01*
X964850Y1642667D01*
X964642Y1642875D01*
X964267Y1643000D01*
X963892Y1642958D01*
X963517Y1642792D01*
G01X965400Y1636500D02*
Y1634000D01*
G01X964442Y1636500D02*
X966358D01*
G01X967667Y1634000D02*
Y1636500D01*
X968667D01*
X969000Y1636375D01*
X969250Y1636083D01*
X969333Y1635750D01*
X969250Y1635417D01*
X969042Y1635167D01*
X968667Y1635042D01*
X967667D01*
G01X971600Y1634000D02*
Y1636500D01*
X971100Y1636000D01*
G01Y1634000D02*
X972100D01*
G01X914300Y1578100D02*
Y1591100D01*
G01X931917Y1687000D02*
Y1689500D01*
X932917D01*
X933250Y1689375D01*
X933500Y1689083D01*
X933583Y1688750D01*
X933500Y1688417D01*
X933292Y1688167D01*
X932917Y1688042D01*
X931917D01*
G01X936767Y1689292D02*
X936517Y1689417D01*
X936225Y1689500D01*
X935892D01*
X935517Y1689375D01*
X935225Y1689167D01*
X935017Y1688917D01*
X934850Y1688500D01*
X934808Y1688125D01*
X934892Y1687750D01*
X935017Y1687500D01*
X935267Y1687250D01*
X935558Y1687083D01*
X935850Y1687000D01*
X936142D01*
X936433Y1687083D01*
X936683Y1687208D01*
X936892Y1687375D01*
G01X938950Y1687000D02*
Y1689500D01*
X938450Y1689000D01*
G01Y1687000D02*
X939450D01*
G01X941258Y1689083D02*
X941508Y1689333D01*
X941800Y1689458D01*
X942133Y1689500D01*
X942550Y1689417D01*
X942842Y1689208D01*
X942925Y1688958D01*
X942883Y1688708D01*
X942717Y1688500D01*
X941883Y1688083D01*
X941508Y1687792D01*
X941258Y1687375D01*
X941175Y1687000D01*
X942925D01*
G01X945150D02*
X945442Y1687042D01*
X945775Y1687167D01*
X945983Y1687375D01*
X946067Y1687667D01*
X945983Y1687958D01*
X945733Y1688208D01*
X945358Y1688333D01*
X944942D01*
X944692Y1688417D01*
X944483Y1688625D01*
X944400Y1688917D01*
X944525Y1689208D01*
X944817Y1689417D01*
X945150Y1689500D01*
X945483Y1689417D01*
X945775Y1689208D01*
X945900Y1688917D01*
X945817Y1688625D01*
X945608Y1688417D01*
X945358Y1688333D01*
X944942D01*
X944567Y1688208D01*
X944317Y1687958D01*
X944233Y1687667D01*
X944317Y1687375D01*
X944525Y1687167D01*
X944858Y1687042D01*
X945150Y1687000D01*
G01X947333Y1687500D02*
X947583Y1687208D01*
X947917Y1687042D01*
X948292Y1687000D01*
X948625Y1687042D01*
X948958Y1687250D01*
X949167Y1687500D01*
X949208Y1687750D01*
X949125Y1688042D01*
X948833Y1688250D01*
X948542Y1688333D01*
X948167D01*
G01X948542D02*
X948792Y1688458D01*
X949000Y1688667D01*
X949083Y1688917D01*
X949000Y1689167D01*
X948792Y1689375D01*
X948417Y1689500D01*
X948042Y1689458D01*
X947667Y1689292D01*
G01X930427Y1695270D02*
Y1697770D01*
X931427D01*
X931760Y1697645D01*
X932010Y1697353D01*
X932093Y1697020D01*
X932010Y1696687D01*
X931802Y1696437D01*
X931427Y1696312D01*
X930427D01*
G01X935277Y1697562D02*
X935027Y1697687D01*
X934735Y1697770D01*
X934402D01*
X934027Y1697645D01*
X933735Y1697437D01*
X933527Y1697187D01*
X933360Y1696770D01*
X933318Y1696395D01*
X933402Y1696020D01*
X933527Y1695770D01*
X933777Y1695520D01*
X934068Y1695353D01*
X934360Y1695270D01*
X934652D01*
X934943Y1695353D01*
X935193Y1695478D01*
X935402Y1695645D01*
G01X937460Y1695270D02*
Y1697770D01*
X936960Y1697270D01*
G01Y1695270D02*
X937960D01*
G01X939768Y1697353D02*
X940018Y1697603D01*
X940310Y1697728D01*
X940643Y1697770D01*
X941060Y1697687D01*
X941352Y1697478D01*
X941435Y1697228D01*
X941393Y1696978D01*
X941227Y1696770D01*
X940393Y1696353D01*
X940018Y1696062D01*
X939768Y1695645D01*
X939685Y1695270D01*
X941435D01*
G01X943660D02*
X943952Y1695312D01*
X944285Y1695437D01*
X944493Y1695645D01*
X944577Y1695937D01*
X944493Y1696228D01*
X944243Y1696478D01*
X943868Y1696603D01*
X943452D01*
X943202Y1696687D01*
X942993Y1696895D01*
X942910Y1697187D01*
X943035Y1697478D01*
X943327Y1697687D01*
X943660Y1697770D01*
X943993Y1697687D01*
X944285Y1697478D01*
X944410Y1697187D01*
X944327Y1696895D01*
X944118Y1696687D01*
X943868Y1696603D01*
X943452D01*
X943077Y1696478D01*
X942827Y1696228D01*
X942743Y1695937D01*
X942827Y1695645D01*
X943035Y1695437D01*
X943368Y1695312D01*
X943660Y1695270D01*
G01X946760D02*
X947052Y1695312D01*
X947385Y1695437D01*
X947593Y1695645D01*
X947677Y1695937D01*
X947593Y1696228D01*
X947343Y1696478D01*
X946968Y1696603D01*
X946552D01*
X946302Y1696687D01*
X946093Y1696895D01*
X946010Y1697187D01*
X946135Y1697478D01*
X946427Y1697687D01*
X946760Y1697770D01*
X947093Y1697687D01*
X947385Y1697478D01*
X947510Y1697187D01*
X947427Y1696895D01*
X947218Y1696687D01*
X946968Y1696603D01*
X946552D01*
X946177Y1696478D01*
X945927Y1696228D01*
X945843Y1695937D01*
X945927Y1695645D01*
X946135Y1695437D01*
X946468Y1695312D01*
X946760Y1695270D01*
G01X930727Y1717650D02*
Y1720150D01*
X931727D01*
X932060Y1720025D01*
X932310Y1719733D01*
X932393Y1719400D01*
X932310Y1719067D01*
X932102Y1718817D01*
X931727Y1718692D01*
X930727D01*
G01X935577Y1719942D02*
X935327Y1720067D01*
X935035Y1720150D01*
X934702D01*
X934327Y1720025D01*
X934035Y1719817D01*
X933827Y1719567D01*
X933660Y1719150D01*
X933618Y1718775D01*
X933702Y1718400D01*
X933827Y1718150D01*
X934077Y1717900D01*
X934368Y1717733D01*
X934660Y1717650D01*
X934952D01*
X935243Y1717733D01*
X935493Y1717858D01*
X935702Y1718025D01*
G01X937760Y1717650D02*
Y1720150D01*
X937260Y1719650D01*
G01Y1717650D02*
X938260D01*
G01X940068Y1719733D02*
X940318Y1719983D01*
X940610Y1720108D01*
X940943Y1720150D01*
X941360Y1720067D01*
X941652Y1719858D01*
X941735Y1719608D01*
X941693Y1719358D01*
X941527Y1719150D01*
X940693Y1718733D01*
X940318Y1718442D01*
X940068Y1718025D01*
X939985Y1717650D01*
X941735D01*
G01X943877D02*
X943960Y1718192D01*
X944085Y1718650D01*
X944252Y1719067D01*
X944460Y1719525D01*
X944793Y1720150D01*
X943127D01*
G01X946352Y1717942D02*
X946643Y1717733D01*
X946977Y1717650D01*
X947310Y1717733D01*
X947602Y1717983D01*
X947810Y1718358D01*
X947893Y1718733D01*
Y1719192D01*
X947810Y1719567D01*
X947602Y1719900D01*
X947352Y1720067D01*
X947060Y1720150D01*
X946727Y1720067D01*
X946477Y1719900D01*
X946310Y1719650D01*
X946227Y1719317D01*
X946310Y1719025D01*
X946518Y1718733D01*
X946768Y1718567D01*
X947060Y1718525D01*
X947393Y1718608D01*
X947643Y1718817D01*
X947893Y1719192D01*
G01X975267Y1659792D02*
X975017Y1659917D01*
X974725Y1660000D01*
X974392D01*
X974017Y1659875D01*
X973725Y1659667D01*
X973517Y1659417D01*
X973350Y1659000D01*
X973308Y1658625D01*
X973392Y1658250D01*
X973517Y1658000D01*
X973767Y1657750D01*
X974058Y1657583D01*
X974350Y1657500D01*
X974642D01*
X974933Y1657583D01*
X975183Y1657708D01*
X975392Y1657875D01*
G01X976533Y1658000D02*
X976783Y1657708D01*
X977117Y1657542D01*
X977492Y1657500D01*
X977825Y1657542D01*
X978158Y1657750D01*
X978367Y1658000D01*
X978408Y1658250D01*
X978325Y1658542D01*
X978033Y1658750D01*
X977742Y1658833D01*
X977367D01*
G01X977742D02*
X977992Y1658958D01*
X978200Y1659167D01*
X978283Y1659417D01*
X978200Y1659667D01*
X977992Y1659875D01*
X977617Y1660000D01*
X977242Y1659958D01*
X976867Y1659792D01*
G01X979633Y1657875D02*
X979883Y1657667D01*
X980175Y1657542D01*
X980550Y1657500D01*
X980925Y1657583D01*
X981217Y1657750D01*
X981425Y1658042D01*
X981467Y1658375D01*
X981383Y1658708D01*
X981175Y1658917D01*
X980883Y1659083D01*
X980592Y1659125D01*
X980300Y1659083D01*
X979925Y1658917D01*
X980050Y1660000D01*
X981175D01*
G01X982733Y1657875D02*
X982983Y1657667D01*
X983275Y1657542D01*
X983650Y1657500D01*
X984025Y1657583D01*
X984317Y1657750D01*
X984525Y1658042D01*
X984567Y1658375D01*
X984483Y1658708D01*
X984275Y1658917D01*
X983983Y1659083D01*
X983692Y1659125D01*
X983400Y1659083D01*
X983025Y1658917D01*
X983150Y1660000D01*
X984275D01*
G01X975267Y1674292D02*
X975017Y1674417D01*
X974725Y1674500D01*
X974392D01*
X974017Y1674375D01*
X973725Y1674167D01*
X973517Y1673917D01*
X973350Y1673500D01*
X973308Y1673125D01*
X973392Y1672750D01*
X973517Y1672500D01*
X973767Y1672250D01*
X974058Y1672083D01*
X974350Y1672000D01*
X974642D01*
X974933Y1672083D01*
X975183Y1672208D01*
X975392Y1672375D01*
G01X976533Y1672500D02*
X976783Y1672208D01*
X977117Y1672042D01*
X977492Y1672000D01*
X977825Y1672042D01*
X978158Y1672250D01*
X978367Y1672500D01*
X978408Y1672750D01*
X978325Y1673042D01*
X978033Y1673250D01*
X977742Y1673333D01*
X977367D01*
G01X977742D02*
X977992Y1673458D01*
X978200Y1673667D01*
X978283Y1673917D01*
X978200Y1674167D01*
X977992Y1674375D01*
X977617Y1674500D01*
X977242Y1674458D01*
X976867Y1674292D01*
G01X979633Y1672375D02*
X979883Y1672167D01*
X980175Y1672042D01*
X980550Y1672000D01*
X980925Y1672083D01*
X981217Y1672250D01*
X981425Y1672542D01*
X981467Y1672875D01*
X981383Y1673208D01*
X981175Y1673417D01*
X980883Y1673583D01*
X980592Y1673625D01*
X980300Y1673583D01*
X979925Y1673417D01*
X980050Y1674500D01*
X981175D01*
G01X982858Y1673042D02*
X983150Y1673333D01*
X983400Y1673500D01*
X983733Y1673583D01*
X984025Y1673500D01*
X984233Y1673333D01*
X984400Y1673083D01*
X984442Y1672792D01*
X984400Y1672542D01*
X984233Y1672292D01*
X983983Y1672083D01*
X983692Y1672000D01*
X983358Y1672083D01*
X983067Y1672333D01*
X982900Y1672708D01*
X982858Y1673125D01*
X982942Y1673667D01*
X983067Y1673958D01*
X983275Y1674250D01*
X983567Y1674458D01*
X983858Y1674500D01*
X984150Y1674417D01*
X984358Y1674208D01*
G01X926770Y1703197D02*
X924270D01*
Y1704197D01*
X924395Y1704530D01*
X924687Y1704780D01*
X925020Y1704863D01*
X925353Y1704780D01*
X925603Y1704572D01*
X925728Y1704197D01*
Y1703197D01*
G01X924478Y1708047D02*
X924353Y1707797D01*
X924270Y1707505D01*
Y1707172D01*
X924395Y1706797D01*
X924603Y1706505D01*
X924853Y1706297D01*
X925270Y1706130D01*
X925645Y1706088D01*
X926020Y1706172D01*
X926270Y1706297D01*
X926520Y1706547D01*
X926687Y1706838D01*
X926770Y1707130D01*
Y1707422D01*
X926687Y1707713D01*
X926562Y1707963D01*
X926395Y1708172D01*
G01X926770Y1710230D02*
X924270D01*
X924770Y1709730D01*
G01X926770D02*
Y1710730D01*
G01X924687Y1712538D02*
X924437Y1712788D01*
X924312Y1713080D01*
X924270Y1713413D01*
X924353Y1713830D01*
X924562Y1714122D01*
X924812Y1714205D01*
X925062Y1714163D01*
X925270Y1713997D01*
X925687Y1713163D01*
X925978Y1712788D01*
X926395Y1712538D01*
X926770Y1712455D01*
Y1714205D01*
G01X925728Y1715638D02*
X925437Y1715930D01*
X925270Y1716180D01*
X925187Y1716513D01*
X925270Y1716805D01*
X925437Y1717013D01*
X925687Y1717180D01*
X925978Y1717222D01*
X926228Y1717180D01*
X926478Y1717013D01*
X926687Y1716763D01*
X926770Y1716472D01*
X926687Y1716138D01*
X926437Y1715847D01*
X926062Y1715680D01*
X925645Y1715638D01*
X925103Y1715722D01*
X924812Y1715847D01*
X924520Y1716055D01*
X924312Y1716347D01*
X924270Y1716638D01*
X924353Y1716930D01*
X924562Y1717138D01*
G01X926270Y1718613D02*
X926562Y1718863D01*
X926728Y1719197D01*
X926770Y1719572D01*
X926728Y1719905D01*
X926520Y1720238D01*
X926270Y1720447D01*
X926020Y1720488D01*
X925728Y1720405D01*
X925520Y1720113D01*
X925437Y1719822D01*
Y1719447D01*
G01Y1719822D02*
X925312Y1720072D01*
X925103Y1720280D01*
X924853Y1720363D01*
X924603Y1720280D01*
X924395Y1720072D01*
X924270Y1719697D01*
X924312Y1719322D01*
X924478Y1718947D01*
G01X923777Y1668221D02*
Y1670721D01*
X924777D01*
X925110Y1670596D01*
X925360Y1670304D01*
X925443Y1669971D01*
X925360Y1669638D01*
X925152Y1669388D01*
X924777Y1669263D01*
X923777D01*
G01X926877Y1668221D02*
Y1670721D01*
X927918D01*
X928252Y1670596D01*
X928460Y1670429D01*
X928543Y1670096D01*
X928460Y1669763D01*
X928210Y1669554D01*
X927918Y1669429D01*
X926877D01*
G01X927918D02*
X928543Y1668221D01*
G01X930102Y1668513D02*
X930393Y1668304D01*
X930727Y1668221D01*
X931060Y1668304D01*
X931352Y1668554D01*
X931560Y1668929D01*
X931643Y1669304D01*
Y1669763D01*
X931560Y1670138D01*
X931352Y1670471D01*
X931102Y1670638D01*
X930810Y1670721D01*
X930477Y1670638D01*
X930227Y1670471D01*
X930060Y1670221D01*
X929977Y1669888D01*
X930060Y1669596D01*
X930268Y1669304D01*
X930518Y1669138D01*
X930810Y1669096D01*
X931143Y1669179D01*
X931393Y1669388D01*
X931643Y1669763D01*
G01X933910Y1670721D02*
X933577Y1670638D01*
X933327Y1670429D01*
X933160Y1670179D01*
X933035Y1669846D01*
X932993Y1669471D01*
X933035Y1669096D01*
X933160Y1668763D01*
X933327Y1668513D01*
X933577Y1668304D01*
X933910Y1668221D01*
X934243Y1668304D01*
X934493Y1668513D01*
X934660Y1668763D01*
X934785Y1669096D01*
X934827Y1669471D01*
X934785Y1669846D01*
X934660Y1670179D01*
X934493Y1670429D01*
X934243Y1670638D01*
X933910Y1670721D01*
G01X936218Y1669263D02*
X936510Y1669554D01*
X936760Y1669721D01*
X937093Y1669804D01*
X937385Y1669721D01*
X937593Y1669554D01*
X937760Y1669304D01*
X937802Y1669013D01*
X937760Y1668763D01*
X937593Y1668513D01*
X937343Y1668304D01*
X937052Y1668221D01*
X936718Y1668304D01*
X936427Y1668554D01*
X936260Y1668929D01*
X936218Y1669346D01*
X936302Y1669888D01*
X936427Y1670179D01*
X936635Y1670471D01*
X936927Y1670679D01*
X937218Y1670721D01*
X937510Y1670638D01*
X937718Y1670429D01*
G01X940110Y1670721D02*
X939777Y1670638D01*
X939527Y1670429D01*
X939360Y1670179D01*
X939235Y1669846D01*
X939193Y1669471D01*
X939235Y1669096D01*
X939360Y1668763D01*
X939527Y1668513D01*
X939777Y1668304D01*
X940110Y1668221D01*
X940443Y1668304D01*
X940693Y1668513D01*
X940860Y1668763D01*
X940985Y1669096D01*
X941027Y1669471D01*
X940985Y1669846D01*
X940860Y1670179D01*
X940693Y1670429D01*
X940443Y1670638D01*
X940110Y1670721D01*
G01X949300Y1670500D02*
Y1666500D01*
X956700D01*
G01X923477Y1661521D02*
Y1664021D01*
X924477D01*
X924810Y1663896D01*
X925060Y1663604D01*
X925143Y1663271D01*
X925060Y1662938D01*
X924852Y1662688D01*
X924477Y1662563D01*
X923477D01*
G01X926577Y1661521D02*
Y1664021D01*
X927618D01*
X927952Y1663896D01*
X928160Y1663729D01*
X928243Y1663396D01*
X928160Y1663063D01*
X927910Y1662854D01*
X927618Y1662729D01*
X926577D01*
G01X927618D02*
X928243Y1661521D01*
G01X929802Y1661813D02*
X930093Y1661604D01*
X930427Y1661521D01*
X930760Y1661604D01*
X931052Y1661854D01*
X931260Y1662229D01*
X931343Y1662604D01*
Y1663063D01*
X931260Y1663438D01*
X931052Y1663771D01*
X930802Y1663938D01*
X930510Y1664021D01*
X930177Y1663938D01*
X929927Y1663771D01*
X929760Y1663521D01*
X929677Y1663188D01*
X929760Y1662896D01*
X929968Y1662604D01*
X930218Y1662438D01*
X930510Y1662396D01*
X930843Y1662479D01*
X931093Y1662688D01*
X931343Y1663063D01*
G01X933610Y1664021D02*
X933277Y1663938D01*
X933027Y1663729D01*
X932860Y1663479D01*
X932735Y1663146D01*
X932693Y1662771D01*
X932735Y1662396D01*
X932860Y1662063D01*
X933027Y1661813D01*
X933277Y1661604D01*
X933610Y1661521D01*
X933943Y1661604D01*
X934193Y1661813D01*
X934360Y1662063D01*
X934485Y1662396D01*
X934527Y1662771D01*
X934485Y1663146D01*
X934360Y1663479D01*
X934193Y1663729D01*
X933943Y1663938D01*
X933610Y1664021D01*
G01X935918Y1662563D02*
X936210Y1662854D01*
X936460Y1663021D01*
X936793Y1663104D01*
X937085Y1663021D01*
X937293Y1662854D01*
X937460Y1662604D01*
X937502Y1662313D01*
X937460Y1662063D01*
X937293Y1661813D01*
X937043Y1661604D01*
X936752Y1661521D01*
X936418Y1661604D01*
X936127Y1661854D01*
X935960Y1662229D01*
X935918Y1662646D01*
X936002Y1663188D01*
X936127Y1663479D01*
X936335Y1663771D01*
X936627Y1663979D01*
X936918Y1664021D01*
X937210Y1663938D01*
X937418Y1663729D01*
G01X938893Y1661896D02*
X939143Y1661688D01*
X939435Y1661563D01*
X939810Y1661521D01*
X940185Y1661604D01*
X940477Y1661771D01*
X940685Y1662063D01*
X940727Y1662396D01*
X940643Y1662729D01*
X940435Y1662938D01*
X940143Y1663104D01*
X939852Y1663146D01*
X939560Y1663104D01*
X939185Y1662938D01*
X939310Y1664021D01*
X940435D01*
G01X949300Y1665500D02*
Y1661500D01*
X956700D01*
G01X945910Y1668057D02*
X943410D01*
Y1669098D01*
X943535Y1669432D01*
X943702Y1669640D01*
X944035Y1669723D01*
X944368Y1669640D01*
X944577Y1669390D01*
X944702Y1669098D01*
Y1668057D01*
G01Y1669098D02*
X945910Y1669723D01*
G01X945410Y1671073D02*
X945702Y1671323D01*
X945868Y1671657D01*
X945910Y1672032D01*
X945868Y1672365D01*
X945660Y1672698D01*
X945410Y1672907D01*
X945160Y1672948D01*
X944868Y1672865D01*
X944660Y1672573D01*
X944577Y1672282D01*
Y1671907D01*
G01Y1672282D02*
X944452Y1672532D01*
X944243Y1672740D01*
X943993Y1672823D01*
X943743Y1672740D01*
X943535Y1672532D01*
X943410Y1672157D01*
X943452Y1671782D01*
X943618Y1671407D01*
G01X944868Y1674298D02*
X944577Y1674590D01*
X944410Y1674840D01*
X944327Y1675173D01*
X944410Y1675465D01*
X944577Y1675673D01*
X944827Y1675840D01*
X945118Y1675882D01*
X945368Y1675840D01*
X945618Y1675673D01*
X945827Y1675423D01*
X945910Y1675132D01*
X945827Y1674798D01*
X945577Y1674507D01*
X945202Y1674340D01*
X944785Y1674298D01*
X944243Y1674382D01*
X943952Y1674507D01*
X943660Y1674715D01*
X943452Y1675007D01*
X943410Y1675298D01*
X943493Y1675590D01*
X943702Y1675798D01*
G01X945618Y1677482D02*
X945827Y1677773D01*
X945910Y1678107D01*
X945827Y1678440D01*
X945577Y1678732D01*
X945202Y1678940D01*
X944827Y1679023D01*
X944368D01*
X943993Y1678940D01*
X943660Y1678732D01*
X943493Y1678482D01*
X943410Y1678190D01*
X943493Y1677857D01*
X943660Y1677607D01*
X943910Y1677440D01*
X944243Y1677357D01*
X944535Y1677440D01*
X944827Y1677648D01*
X944993Y1677898D01*
X945035Y1678190D01*
X944952Y1678523D01*
X944743Y1678773D01*
X944368Y1679023D01*
G01X961000Y1673700D02*
X957000D01*
Y1666300D01*
G01X945640Y1653047D02*
X943140D01*
Y1654088D01*
X943265Y1654422D01*
X943432Y1654630D01*
X943765Y1654713D01*
X944098Y1654630D01*
X944307Y1654380D01*
X944432Y1654088D01*
Y1653047D01*
G01Y1654088D02*
X945640Y1654713D01*
G01X945140Y1656063D02*
X945432Y1656313D01*
X945598Y1656647D01*
X945640Y1657022D01*
X945598Y1657355D01*
X945390Y1657688D01*
X945140Y1657897D01*
X944890Y1657938D01*
X944598Y1657855D01*
X944390Y1657563D01*
X944307Y1657272D01*
Y1656897D01*
G01Y1657272D02*
X944182Y1657522D01*
X943973Y1657730D01*
X943723Y1657813D01*
X943473Y1657730D01*
X943265Y1657522D01*
X943140Y1657147D01*
X943182Y1656772D01*
X943348Y1656397D01*
G01X945640Y1659997D02*
X945098Y1660080D01*
X944640Y1660205D01*
X944223Y1660372D01*
X943765Y1660580D01*
X943140Y1660913D01*
Y1659247D01*
G01Y1663180D02*
X943223Y1662847D01*
X943432Y1662597D01*
X943682Y1662430D01*
X944015Y1662305D01*
X944390Y1662263D01*
X944765Y1662305D01*
X945098Y1662430D01*
X945348Y1662597D01*
X945557Y1662847D01*
X945640Y1663180D01*
X945557Y1663513D01*
X945348Y1663763D01*
X945098Y1663930D01*
X944765Y1664055D01*
X944390Y1664097D01*
X944015Y1664055D01*
X943682Y1663930D01*
X943432Y1663763D01*
X943223Y1663513D01*
X943140Y1663180D01*
G01X957000Y1658300D02*
X961000D01*
Y1665700D01*
G01X930427Y1691270D02*
Y1693770D01*
X931427D01*
X931760Y1693645D01*
X932010Y1693353D01*
X932093Y1693020D01*
X932010Y1692687D01*
X931802Y1692437D01*
X931427Y1692312D01*
X930427D01*
G01X933527Y1691270D02*
Y1693770D01*
X934568D01*
X934902Y1693645D01*
X935110Y1693478D01*
X935193Y1693145D01*
X935110Y1692812D01*
X934860Y1692603D01*
X934568Y1692478D01*
X933527D01*
G01X934568D02*
X935193Y1691270D01*
G01X936752Y1691562D02*
X937043Y1691353D01*
X937377Y1691270D01*
X937710Y1691353D01*
X938002Y1691603D01*
X938210Y1691978D01*
X938293Y1692353D01*
Y1692812D01*
X938210Y1693187D01*
X938002Y1693520D01*
X937752Y1693687D01*
X937460Y1693770D01*
X937127Y1693687D01*
X936877Y1693520D01*
X936710Y1693270D01*
X936627Y1692937D01*
X936710Y1692645D01*
X936918Y1692353D01*
X937168Y1692187D01*
X937460Y1692145D01*
X937793Y1692228D01*
X938043Y1692437D01*
X938293Y1692812D01*
G01X940560Y1693770D02*
X940227Y1693687D01*
X939977Y1693478D01*
X939810Y1693228D01*
X939685Y1692895D01*
X939643Y1692520D01*
X939685Y1692145D01*
X939810Y1691812D01*
X939977Y1691562D01*
X940227Y1691353D01*
X940560Y1691270D01*
X940893Y1691353D01*
X941143Y1691562D01*
X941310Y1691812D01*
X941435Y1692145D01*
X941477Y1692520D01*
X941435Y1692895D01*
X941310Y1693228D01*
X941143Y1693478D01*
X940893Y1693687D01*
X940560Y1693770D01*
G01X942952Y1691562D02*
X943243Y1691353D01*
X943577Y1691270D01*
X943910Y1691353D01*
X944202Y1691603D01*
X944410Y1691978D01*
X944493Y1692353D01*
Y1692812D01*
X944410Y1693187D01*
X944202Y1693520D01*
X943952Y1693687D01*
X943660Y1693770D01*
X943327Y1693687D01*
X943077Y1693520D01*
X942910Y1693270D01*
X942827Y1692937D01*
X942910Y1692645D01*
X943118Y1692353D01*
X943368Y1692187D01*
X943660Y1692145D01*
X943993Y1692228D01*
X944243Y1692437D01*
X944493Y1692812D01*
G01X946760Y1693770D02*
X946427Y1693687D01*
X946177Y1693478D01*
X946010Y1693228D01*
X945885Y1692895D01*
X945843Y1692520D01*
X945885Y1692145D01*
X946010Y1691812D01*
X946177Y1691562D01*
X946427Y1691353D01*
X946760Y1691270D01*
X947093Y1691353D01*
X947343Y1691562D01*
X947510Y1691812D01*
X947635Y1692145D01*
X947677Y1692520D01*
X947635Y1692895D01*
X947510Y1693228D01*
X947343Y1693478D01*
X947093Y1693687D01*
X946760Y1693770D01*
G01X929917Y1713000D02*
Y1715500D01*
X930917D01*
X931250Y1715375D01*
X931500Y1715083D01*
X931583Y1714750D01*
X931500Y1714417D01*
X931292Y1714167D01*
X930917Y1714042D01*
X929917D01*
G01X933017Y1713000D02*
Y1715500D01*
X934058D01*
X934392Y1715375D01*
X934600Y1715208D01*
X934683Y1714875D01*
X934600Y1714542D01*
X934350Y1714333D01*
X934058Y1714208D01*
X933017D01*
G01X934058D02*
X934683Y1713000D01*
G01X936242Y1713292D02*
X936533Y1713083D01*
X936867Y1713000D01*
X937200Y1713083D01*
X937492Y1713333D01*
X937700Y1713708D01*
X937783Y1714083D01*
Y1714542D01*
X937700Y1714917D01*
X937492Y1715250D01*
X937242Y1715417D01*
X936950Y1715500D01*
X936617Y1715417D01*
X936367Y1715250D01*
X936200Y1715000D01*
X936117Y1714667D01*
X936200Y1714375D01*
X936408Y1714083D01*
X936658Y1713917D01*
X936950Y1713875D01*
X937283Y1713958D01*
X937533Y1714167D01*
X937783Y1714542D01*
G01X940050Y1715500D02*
X939717Y1715417D01*
X939467Y1715208D01*
X939300Y1714958D01*
X939175Y1714625D01*
X939133Y1714250D01*
X939175Y1713875D01*
X939300Y1713542D01*
X939467Y1713292D01*
X939717Y1713083D01*
X940050Y1713000D01*
X940383Y1713083D01*
X940633Y1713292D01*
X940800Y1713542D01*
X940925Y1713875D01*
X940967Y1714250D01*
X940925Y1714625D01*
X940800Y1714958D01*
X940633Y1715208D01*
X940383Y1715417D01*
X940050Y1715500D01*
G01X943067Y1713000D02*
X943150Y1713542D01*
X943275Y1714000D01*
X943442Y1714417D01*
X943650Y1714875D01*
X943983Y1715500D01*
X942317D01*
G01X945542Y1713292D02*
X945833Y1713083D01*
X946167Y1713000D01*
X946500Y1713083D01*
X946792Y1713333D01*
X947000Y1713708D01*
X947083Y1714083D01*
Y1714542D01*
X947000Y1714917D01*
X946792Y1715250D01*
X946542Y1715417D01*
X946250Y1715500D01*
X945917Y1715417D01*
X945667Y1715250D01*
X945500Y1715000D01*
X945417Y1714667D01*
X945500Y1714375D01*
X945708Y1714083D01*
X945958Y1713917D01*
X946250Y1713875D01*
X946583Y1713958D01*
X946833Y1714167D01*
X947083Y1714542D01*
G01X913800Y1717000D02*
Y1713000D01*
X921200D01*
G01X930427Y1699270D02*
Y1701770D01*
X931427D01*
X931760Y1701645D01*
X932010Y1701353D01*
X932093Y1701020D01*
X932010Y1700687D01*
X931802Y1700437D01*
X931427Y1700312D01*
X930427D01*
G01X933527Y1699270D02*
Y1701770D01*
X934568D01*
X934902Y1701645D01*
X935110Y1701478D01*
X935193Y1701145D01*
X935110Y1700812D01*
X934860Y1700603D01*
X934568Y1700478D01*
X933527D01*
G01X934568D02*
X935193Y1699270D01*
G01X936752Y1699562D02*
X937043Y1699353D01*
X937377Y1699270D01*
X937710Y1699353D01*
X938002Y1699603D01*
X938210Y1699978D01*
X938293Y1700353D01*
Y1700812D01*
X938210Y1701187D01*
X938002Y1701520D01*
X937752Y1701687D01*
X937460Y1701770D01*
X937127Y1701687D01*
X936877Y1701520D01*
X936710Y1701270D01*
X936627Y1700937D01*
X936710Y1700645D01*
X936918Y1700353D01*
X937168Y1700187D01*
X937460Y1700145D01*
X937793Y1700228D01*
X938043Y1700437D01*
X938293Y1700812D01*
G01X940560Y1701770D02*
X940227Y1701687D01*
X939977Y1701478D01*
X939810Y1701228D01*
X939685Y1700895D01*
X939643Y1700520D01*
X939685Y1700145D01*
X939810Y1699812D01*
X939977Y1699562D01*
X940227Y1699353D01*
X940560Y1699270D01*
X940893Y1699353D01*
X941143Y1699562D01*
X941310Y1699812D01*
X941435Y1700145D01*
X941477Y1700520D01*
X941435Y1700895D01*
X941310Y1701228D01*
X941143Y1701478D01*
X940893Y1701687D01*
X940560Y1701770D01*
G01X943577Y1699270D02*
X943660Y1699812D01*
X943785Y1700270D01*
X943952Y1700687D01*
X944160Y1701145D01*
X944493Y1701770D01*
X942827D01*
G01X946677Y1699270D02*
X946760Y1699812D01*
X946885Y1700270D01*
X947052Y1700687D01*
X947260Y1701145D01*
X947593Y1701770D01*
X945927D01*
G01X950227Y1692540D02*
Y1695040D01*
X951227D01*
X951560Y1694915D01*
X951810Y1694623D01*
X951893Y1694290D01*
X951810Y1693957D01*
X951602Y1693707D01*
X951227Y1693582D01*
X950227D01*
G01X953327Y1692540D02*
Y1695040D01*
X954368D01*
X954702Y1694915D01*
X954910Y1694748D01*
X954993Y1694415D01*
X954910Y1694082D01*
X954660Y1693873D01*
X954368Y1693748D01*
X953327D01*
G01X954368D02*
X954993Y1692540D01*
G01X956552Y1692832D02*
X956843Y1692623D01*
X957177Y1692540D01*
X957510Y1692623D01*
X957802Y1692873D01*
X958010Y1693248D01*
X958093Y1693623D01*
Y1694082D01*
X958010Y1694457D01*
X957802Y1694790D01*
X957552Y1694957D01*
X957260Y1695040D01*
X956927Y1694957D01*
X956677Y1694790D01*
X956510Y1694540D01*
X956427Y1694207D01*
X956510Y1693915D01*
X956718Y1693623D01*
X956968Y1693457D01*
X957260Y1693415D01*
X957593Y1693498D01*
X957843Y1693707D01*
X958093Y1694082D01*
G01X960360Y1695040D02*
X960027Y1694957D01*
X959777Y1694748D01*
X959610Y1694498D01*
X959485Y1694165D01*
X959443Y1693790D01*
X959485Y1693415D01*
X959610Y1693082D01*
X959777Y1692832D01*
X960027Y1692623D01*
X960360Y1692540D01*
X960693Y1692623D01*
X960943Y1692832D01*
X961110Y1693082D01*
X961235Y1693415D01*
X961277Y1693790D01*
X961235Y1694165D01*
X961110Y1694498D01*
X960943Y1694748D01*
X960693Y1694957D01*
X960360Y1695040D01*
G01X963460Y1692540D02*
X963752Y1692582D01*
X964085Y1692707D01*
X964293Y1692915D01*
X964377Y1693207D01*
X964293Y1693498D01*
X964043Y1693748D01*
X963668Y1693873D01*
X963252D01*
X963002Y1693957D01*
X962793Y1694165D01*
X962710Y1694457D01*
X962835Y1694748D01*
X963127Y1694957D01*
X963460Y1695040D01*
X963793Y1694957D01*
X964085Y1694748D01*
X964210Y1694457D01*
X964127Y1694165D01*
X963918Y1693957D01*
X963668Y1693873D01*
X963252D01*
X962877Y1693748D01*
X962627Y1693498D01*
X962543Y1693207D01*
X962627Y1692915D01*
X962835Y1692707D01*
X963168Y1692582D01*
X963460Y1692540D01*
G01X965643Y1692915D02*
X965893Y1692707D01*
X966185Y1692582D01*
X966560Y1692540D01*
X966935Y1692623D01*
X967227Y1692790D01*
X967435Y1693082D01*
X967477Y1693415D01*
X967393Y1693748D01*
X967185Y1693957D01*
X966893Y1694123D01*
X966602Y1694165D01*
X966310Y1694123D01*
X965935Y1693957D01*
X966060Y1695040D01*
X967185D01*
G01X968500Y1680400D02*
X971000D01*
G01X968500Y1679442D02*
Y1681358D01*
G01X971000Y1682667D02*
X968500D01*
Y1683667D01*
X968625Y1684000D01*
X968917Y1684250D01*
X969250Y1684333D01*
X969583Y1684250D01*
X969833Y1684042D01*
X969958Y1683667D01*
Y1682667D01*
G01X968917Y1685808D02*
X968667Y1686058D01*
X968542Y1686350D01*
X968500Y1686683D01*
X968583Y1687100D01*
X968792Y1687392D01*
X969042Y1687475D01*
X969292Y1687433D01*
X969500Y1687267D01*
X969917Y1686433D01*
X970208Y1686058D01*
X970625Y1685808D01*
X971000Y1685725D01*
Y1687475D01*
G01X918775Y1772300D02*
X919108Y1772092D01*
X919483Y1771967D01*
X919817D01*
X920150Y1772092D01*
X920400Y1772300D01*
X920525Y1772592D01*
X920442Y1772884D01*
X920233Y1773134D01*
X919858Y1773300D01*
X919358Y1773384D01*
X919067Y1773550D01*
X918942Y1773842D01*
X919025Y1774134D01*
X919233Y1774342D01*
X919525Y1774467D01*
X919817D01*
X920108Y1774384D01*
X920358Y1774175D01*
G01X921833Y1771967D02*
Y1774467D01*
X922667D01*
X923000Y1774342D01*
X923250Y1774175D01*
X923458Y1773925D01*
X923625Y1773634D01*
X923667Y1773217D01*
X923625Y1772800D01*
X923458Y1772509D01*
X923250Y1772259D01*
X923000Y1772092D01*
X922667Y1771967D01*
X921833D01*
G01X924933D02*
Y1774467D01*
X925767D01*
X926100Y1774342D01*
X926350Y1774175D01*
X926558Y1773925D01*
X926725Y1773634D01*
X926767Y1773217D01*
X926725Y1772800D01*
X926558Y1772509D01*
X926350Y1772259D01*
X926100Y1772092D01*
X925767Y1771967D01*
X924933D01*
G01X931008D02*
X932050Y1774467D01*
X933092Y1771967D01*
G01X932717Y1772842D02*
X931383D01*
G01X936067Y1774259D02*
X935817Y1774384D01*
X935525Y1774467D01*
X935192D01*
X934817Y1774342D01*
X934525Y1774134D01*
X934317Y1773884D01*
X934150Y1773467D01*
X934108Y1773092D01*
X934192Y1772717D01*
X934317Y1772467D01*
X934567Y1772217D01*
X934858Y1772050D01*
X935150Y1771967D01*
X935442D01*
X935733Y1772050D01*
X935983Y1772175D01*
X936192Y1772342D01*
G01X938250Y1774467D02*
Y1771967D01*
G01X937292Y1774467D02*
X939208D01*
G01X941350D02*
X941017Y1774384D01*
X940767Y1774175D01*
X940600Y1773925D01*
X940475Y1773592D01*
X940433Y1773217D01*
X940475Y1772842D01*
X940600Y1772509D01*
X940767Y1772259D01*
X941017Y1772050D01*
X941350Y1771967D01*
X941683Y1772050D01*
X941933Y1772259D01*
X942100Y1772509D01*
X942225Y1772842D01*
X942267Y1773217D01*
X942225Y1773592D01*
X942100Y1773925D01*
X941933Y1774175D01*
X941683Y1774384D01*
X941350Y1774467D01*
G01X945200Y1758900D02*
X945158Y1758567D01*
X944992Y1758275D01*
X944742Y1758025D01*
X944450Y1757858D01*
X944117Y1757775D01*
X943783D01*
X943450Y1757858D01*
X943158Y1758025D01*
X942908Y1758275D01*
X942742Y1758567D01*
X942700Y1758900D01*
X942742Y1759233D01*
X942908Y1759525D01*
X943158Y1759775D01*
X943450Y1759942D01*
X943783Y1760025D01*
X944117D01*
X944450Y1759942D01*
X944742Y1759775D01*
X944992Y1759525D01*
X945158Y1759233D01*
X945200Y1758900D01*
G01X944533Y1759233D02*
X945200Y1759733D01*
G01X943117Y1761208D02*
X942867Y1761458D01*
X942742Y1761750D01*
X942700Y1762083D01*
X942783Y1762500D01*
X942992Y1762792D01*
X943242Y1762875D01*
X943492Y1762833D01*
X943700Y1762667D01*
X944117Y1761833D01*
X944408Y1761458D01*
X944825Y1761208D01*
X945200Y1761125D01*
Y1762875D01*
G01X944908Y1764392D02*
X945117Y1764683D01*
X945200Y1765017D01*
X945117Y1765350D01*
X944867Y1765642D01*
X944492Y1765850D01*
X944117Y1765933D01*
X943658D01*
X943283Y1765850D01*
X942950Y1765642D01*
X942783Y1765392D01*
X942700Y1765100D01*
X942783Y1764767D01*
X942950Y1764517D01*
X943200Y1764350D01*
X943533Y1764267D01*
X943825Y1764350D01*
X944117Y1764558D01*
X944283Y1764808D01*
X944325Y1765100D01*
X944242Y1765433D01*
X944033Y1765683D01*
X943658Y1765933D01*
G01X927000Y1756000D02*
Y1770000D01*
G01X914000Y1756000D02*
X927000D01*
G01X914000Y1770000D02*
Y1756000D01*
G01X927000Y1770000D02*
X914000D01*
G01X928917Y1785600D02*
Y1788100D01*
X929958D01*
X930292Y1787975D01*
X930500Y1787808D01*
X930583Y1787475D01*
X930500Y1787142D01*
X930250Y1786933D01*
X929958Y1786808D01*
X928917D01*
G01X929958D02*
X930583Y1785600D01*
G01X932850D02*
Y1788100D01*
X932350Y1787600D01*
G01Y1785600D02*
X933350D01*
G01X935950D02*
Y1788100D01*
X935450Y1787600D01*
G01Y1785600D02*
X936450D01*
G01X939050D02*
Y1788100D01*
X938550Y1787600D01*
G01Y1785600D02*
X939550D01*
G01X925200Y1784500D02*
Y1788500D01*
X917800D01*
G01X918467Y1746500D02*
Y1749000D01*
X919508D01*
X919842Y1748875D01*
X920050Y1748708D01*
X920133Y1748375D01*
X920050Y1748042D01*
X919800Y1747833D01*
X919508Y1747708D01*
X918467D01*
G01X919508D02*
X920133Y1746500D01*
G01X921692Y1746792D02*
X921983Y1746583D01*
X922317Y1746500D01*
X922650Y1746583D01*
X922942Y1746833D01*
X923150Y1747208D01*
X923233Y1747583D01*
Y1748042D01*
X923150Y1748417D01*
X922942Y1748750D01*
X922692Y1748917D01*
X922400Y1749000D01*
X922067Y1748917D01*
X921817Y1748750D01*
X921650Y1748500D01*
X921567Y1748167D01*
X921650Y1747875D01*
X921858Y1747583D01*
X922108Y1747417D01*
X922400Y1747375D01*
X922733Y1747458D01*
X922983Y1747667D01*
X923233Y1748042D01*
G01X925417Y1746500D02*
X925500Y1747042D01*
X925625Y1747500D01*
X925792Y1747917D01*
X926000Y1748375D01*
X926333Y1749000D01*
X924667D01*
G01X928600Y1746500D02*
X928892Y1746542D01*
X929225Y1746667D01*
X929433Y1746875D01*
X929517Y1747167D01*
X929433Y1747458D01*
X929183Y1747708D01*
X928808Y1747833D01*
X928392D01*
X928142Y1747917D01*
X927933Y1748125D01*
X927850Y1748417D01*
X927975Y1748708D01*
X928267Y1748917D01*
X928600Y1749000D01*
X928933Y1748917D01*
X929225Y1748708D01*
X929350Y1748417D01*
X929267Y1748125D01*
X929058Y1747917D01*
X928808Y1747833D01*
X928392D01*
X928017Y1747708D01*
X927767Y1747458D01*
X927683Y1747167D01*
X927767Y1746875D01*
X927975Y1746667D01*
X928308Y1746542D01*
X928600Y1746500D01*
G01X931700D02*
Y1749000D01*
X931200Y1748500D01*
G01Y1746500D02*
X932200D01*
G01X917800Y1754000D02*
Y1750000D01*
X925200D01*
G01X941200Y1754967D02*
X938700D01*
Y1756008D01*
X938825Y1756342D01*
X938992Y1756550D01*
X939325Y1756633D01*
X939658Y1756550D01*
X939867Y1756300D01*
X939992Y1756008D01*
Y1754967D01*
G01Y1756008D02*
X941200Y1756633D01*
G01X940908Y1758192D02*
X941117Y1758483D01*
X941200Y1758817D01*
X941117Y1759150D01*
X940867Y1759442D01*
X940492Y1759650D01*
X940117Y1759733D01*
X939658D01*
X939283Y1759650D01*
X938950Y1759442D01*
X938783Y1759192D01*
X938700Y1758900D01*
X938783Y1758567D01*
X938950Y1758317D01*
X939200Y1758150D01*
X939533Y1758067D01*
X939825Y1758150D01*
X940117Y1758358D01*
X940283Y1758608D01*
X940325Y1758900D01*
X940242Y1759233D01*
X940033Y1759483D01*
X939658Y1759733D01*
G01X941200Y1761917D02*
X940658Y1762000D01*
X940200Y1762125D01*
X939783Y1762292D01*
X939325Y1762500D01*
X938700Y1762833D01*
Y1761167D01*
G01X941200Y1765100D02*
X941158Y1765392D01*
X941033Y1765725D01*
X940825Y1765933D01*
X940533Y1766017D01*
X940242Y1765933D01*
X939992Y1765683D01*
X939867Y1765308D01*
Y1764892D01*
X939783Y1764642D01*
X939575Y1764433D01*
X939283Y1764350D01*
X938992Y1764475D01*
X938783Y1764767D01*
X938700Y1765100D01*
X938783Y1765433D01*
X938992Y1765725D01*
X939283Y1765850D01*
X939575Y1765767D01*
X939783Y1765558D01*
X939867Y1765308D01*
Y1764892D01*
X939992Y1764517D01*
X940242Y1764267D01*
X940533Y1764183D01*
X940825Y1764267D01*
X941033Y1764475D01*
X941158Y1764808D01*
X941200Y1765100D01*
G01X940700Y1767283D02*
X940992Y1767533D01*
X941158Y1767867D01*
X941200Y1768242D01*
X941158Y1768575D01*
X940950Y1768908D01*
X940700Y1769117D01*
X940450Y1769158D01*
X940158Y1769075D01*
X939950Y1768783D01*
X939867Y1768492D01*
Y1768117D01*
G01Y1768492D02*
X939742Y1768742D01*
X939533Y1768950D01*
X939283Y1769033D01*
X939033Y1768950D01*
X938825Y1768742D01*
X938700Y1768367D01*
X938742Y1767992D01*
X938908Y1767617D01*
G01X936867Y1751875D02*
X937075Y1752208D01*
X937200Y1752583D01*
Y1752917D01*
X937075Y1753250D01*
X936867Y1753500D01*
X936575Y1753625D01*
X936283Y1753542D01*
X936033Y1753333D01*
X935867Y1752958D01*
X935783Y1752458D01*
X935617Y1752167D01*
X935325Y1752042D01*
X935033Y1752125D01*
X934825Y1752333D01*
X934700Y1752625D01*
Y1752917D01*
X934783Y1753208D01*
X934992Y1753458D01*
G01X937200Y1755017D02*
X934700D01*
Y1756058D01*
X934825Y1756392D01*
X934992Y1756600D01*
X935325Y1756683D01*
X935658Y1756600D01*
X935867Y1756350D01*
X935992Y1756058D01*
Y1755017D01*
G01Y1756058D02*
X937200Y1756683D01*
G01Y1758950D02*
X934700D01*
X935200Y1758450D01*
G01X937200D02*
Y1759450D01*
G01Y1762050D02*
X934700D01*
X935200Y1761550D01*
G01X937200D02*
Y1762550D01*
G01X935117Y1764358D02*
X934867Y1764608D01*
X934742Y1764900D01*
X934700Y1765233D01*
X934783Y1765650D01*
X934992Y1765942D01*
X935242Y1766025D01*
X935492Y1765983D01*
X935700Y1765817D01*
X936117Y1764983D01*
X936408Y1764608D01*
X936825Y1764358D01*
X937200Y1764275D01*
Y1766025D01*
G01X935117Y1767458D02*
X934867Y1767708D01*
X934742Y1768000D01*
X934700Y1768333D01*
X934783Y1768750D01*
X934992Y1769042D01*
X935242Y1769125D01*
X935492Y1769083D01*
X935700Y1768917D01*
X936117Y1768083D01*
X936408Y1767708D01*
X936825Y1767458D01*
X937200Y1767375D01*
Y1769125D01*
G01X915000Y1734467D02*
X912500D01*
Y1735508D01*
X912625Y1735842D01*
X912792Y1736050D01*
X913125Y1736133D01*
X913458Y1736050D01*
X913667Y1735800D01*
X913792Y1735508D01*
Y1734467D01*
G01Y1735508D02*
X915000Y1736133D01*
G01X914708Y1737692D02*
X914917Y1737983D01*
X915000Y1738317D01*
X914917Y1738650D01*
X914667Y1738942D01*
X914292Y1739150D01*
X913917Y1739233D01*
X913458D01*
X913083Y1739150D01*
X912750Y1738942D01*
X912583Y1738692D01*
X912500Y1738400D01*
X912583Y1738067D01*
X912750Y1737817D01*
X913000Y1737650D01*
X913333Y1737567D01*
X913625Y1737650D01*
X913917Y1737858D01*
X914083Y1738108D01*
X914125Y1738400D01*
X914042Y1738733D01*
X913833Y1738983D01*
X913458Y1739233D01*
G01X915000Y1741417D02*
X914458Y1741500D01*
X914000Y1741625D01*
X913583Y1741792D01*
X913125Y1742000D01*
X912500Y1742333D01*
Y1740667D01*
G01X914625Y1743683D02*
X914833Y1743933D01*
X914958Y1744225D01*
X915000Y1744600D01*
X914917Y1744975D01*
X914750Y1745267D01*
X914458Y1745475D01*
X914125Y1745517D01*
X913792Y1745433D01*
X913583Y1745225D01*
X913417Y1744933D01*
X913375Y1744642D01*
X913417Y1744350D01*
X913583Y1743975D01*
X912500Y1744100D01*
Y1745225D01*
G01X913958Y1746908D02*
X913667Y1747200D01*
X913500Y1747450D01*
X913417Y1747783D01*
X913500Y1748075D01*
X913667Y1748283D01*
X913917Y1748450D01*
X914208Y1748492D01*
X914458Y1748450D01*
X914708Y1748283D01*
X914917Y1748033D01*
X915000Y1747742D01*
X914917Y1747408D01*
X914667Y1747117D01*
X914292Y1746950D01*
X913875Y1746908D01*
X913333Y1746992D01*
X913042Y1747117D01*
X912750Y1747325D01*
X912542Y1747617D01*
X912500Y1747908D01*
X912583Y1748200D01*
X912792Y1748408D01*
G01X928917Y1777600D02*
Y1780100D01*
X929958D01*
X930292Y1779975D01*
X930500Y1779808D01*
X930583Y1779475D01*
X930500Y1779142D01*
X930250Y1778933D01*
X929958Y1778808D01*
X928917D01*
G01X929958D02*
X930583Y1777600D01*
G01X932142Y1777892D02*
X932433Y1777683D01*
X932767Y1777600D01*
X933100Y1777683D01*
X933392Y1777933D01*
X933600Y1778308D01*
X933683Y1778683D01*
Y1779142D01*
X933600Y1779517D01*
X933392Y1779850D01*
X933142Y1780017D01*
X932850Y1780100D01*
X932517Y1780017D01*
X932267Y1779850D01*
X932100Y1779600D01*
X932017Y1779267D01*
X932100Y1778975D01*
X932308Y1778683D01*
X932558Y1778517D01*
X932850Y1778475D01*
X933183Y1778558D01*
X933433Y1778767D01*
X933683Y1779142D01*
G01X935950Y1777600D02*
X936242Y1777642D01*
X936575Y1777767D01*
X936783Y1777975D01*
X936867Y1778267D01*
X936783Y1778558D01*
X936533Y1778808D01*
X936158Y1778933D01*
X935742D01*
X935492Y1779017D01*
X935283Y1779225D01*
X935200Y1779517D01*
X935325Y1779808D01*
X935617Y1780017D01*
X935950Y1780100D01*
X936283Y1780017D01*
X936575Y1779808D01*
X936700Y1779517D01*
X936617Y1779225D01*
X936408Y1779017D01*
X936158Y1778933D01*
X935742D01*
X935367Y1778808D01*
X935117Y1778558D01*
X935033Y1778267D01*
X935117Y1777975D01*
X935325Y1777767D01*
X935658Y1777642D01*
X935950Y1777600D01*
G01X938342Y1777892D02*
X938633Y1777683D01*
X938967Y1777600D01*
X939300Y1777683D01*
X939592Y1777933D01*
X939800Y1778308D01*
X939883Y1778683D01*
Y1779142D01*
X939800Y1779517D01*
X939592Y1779850D01*
X939342Y1780017D01*
X939050Y1780100D01*
X938717Y1780017D01*
X938467Y1779850D01*
X938300Y1779600D01*
X938217Y1779267D01*
X938300Y1778975D01*
X938508Y1778683D01*
X938758Y1778517D01*
X939050Y1778475D01*
X939383Y1778558D01*
X939633Y1778767D01*
X939883Y1779142D01*
G01X941358Y1779683D02*
X941608Y1779933D01*
X941900Y1780058D01*
X942233Y1780100D01*
X942650Y1780017D01*
X942942Y1779808D01*
X943025Y1779558D01*
X942983Y1779308D01*
X942817Y1779100D01*
X941983Y1778683D01*
X941608Y1778392D01*
X941358Y1777975D01*
X941275Y1777600D01*
X943025D01*
G01X925200Y1775500D02*
Y1779500D01*
X917800D01*
G01X928917Y1781600D02*
Y1784100D01*
X929958D01*
X930292Y1783975D01*
X930500Y1783808D01*
X930583Y1783475D01*
X930500Y1783142D01*
X930250Y1782933D01*
X929958Y1782808D01*
X928917D01*
G01X929958D02*
X930583Y1781600D01*
G01X932850D02*
Y1784100D01*
X932350Y1783600D01*
G01Y1781600D02*
X933350D01*
G01X935158Y1783683D02*
X935408Y1783933D01*
X935700Y1784058D01*
X936033Y1784100D01*
X936450Y1784017D01*
X936742Y1783808D01*
X936825Y1783558D01*
X936783Y1783308D01*
X936617Y1783100D01*
X935783Y1782683D01*
X935408Y1782392D01*
X935158Y1781975D01*
X935075Y1781600D01*
X936825D01*
G01X939050Y1784100D02*
X938717Y1784017D01*
X938467Y1783808D01*
X938300Y1783558D01*
X938175Y1783225D01*
X938133Y1782850D01*
X938175Y1782475D01*
X938300Y1782142D01*
X938467Y1781892D01*
X938717Y1781683D01*
X939050Y1781600D01*
X939383Y1781683D01*
X939633Y1781892D01*
X939800Y1782142D01*
X939925Y1782475D01*
X939967Y1782850D01*
X939925Y1783225D01*
X939800Y1783558D01*
X939633Y1783808D01*
X939383Y1784017D01*
X939050Y1784100D01*
G01X925200Y1780000D02*
Y1784000D01*
X917800D01*
G01X919067Y1729500D02*
Y1732000D01*
X920067D01*
X920400Y1731875D01*
X920650Y1731583D01*
X920733Y1731250D01*
X920650Y1730917D01*
X920442Y1730667D01*
X920067Y1730542D01*
X919067D01*
G01X923250Y1730750D02*
X924083D01*
Y1730000D01*
X923833Y1729750D01*
X923542Y1729583D01*
X923125Y1729500D01*
X922708Y1729583D01*
X922417Y1729750D01*
X922167Y1730000D01*
X922000Y1730292D01*
X921917Y1730625D01*
Y1730917D01*
X922000Y1731167D01*
X922167Y1731458D01*
X922417Y1731708D01*
X922667Y1731875D01*
X923000Y1732000D01*
X923292D01*
X923625Y1731917D01*
X923875Y1731750D01*
G01X925183Y1730000D02*
X925433Y1729708D01*
X925767Y1729542D01*
X926142Y1729500D01*
X926475Y1729542D01*
X926808Y1729750D01*
X927017Y1730000D01*
X927058Y1730250D01*
X926975Y1730542D01*
X926683Y1730750D01*
X926392Y1730833D01*
X926017D01*
G01X926392D02*
X926642Y1730958D01*
X926850Y1731167D01*
X926933Y1731417D01*
X926850Y1731667D01*
X926642Y1731875D01*
X926267Y1732000D01*
X925892Y1731958D01*
X925517Y1731792D01*
G01X995725Y186467D02*
Y188967D01*
G01X997475D02*
Y186467D01*
G01Y187717D02*
X995725D01*
G01X999700Y186467D02*
Y188967D01*
X999200Y188467D01*
G01Y186467D02*
X1000200D01*
G01X1002800D02*
Y188967D01*
X1002300Y188467D01*
G01Y186467D02*
X1003300D01*
G01X999675Y710067D02*
Y712567D01*
G01X1001425D02*
Y710067D01*
G01Y711317D02*
X999675D01*
G01X1003650Y710067D02*
X1003942Y710109D01*
X1004275Y710234D01*
X1004483Y710442D01*
X1004567Y710734D01*
X1004483Y711025D01*
X1004233Y711275D01*
X1003858Y711400D01*
X1003442D01*
X1003192Y711484D01*
X1002983Y711692D01*
X1002900Y711984D01*
X1003025Y712275D01*
X1003317Y712484D01*
X1003650Y712567D01*
X1003983Y712484D01*
X1004275Y712275D01*
X1004400Y711984D01*
X1004317Y711692D01*
X1004108Y711484D01*
X1003858Y711400D01*
X1003442D01*
X1003067Y711275D01*
X1002817Y711025D01*
X1002733Y710734D01*
X1002817Y710442D01*
X1003025Y710234D01*
X1003358Y710109D01*
X1003650Y710067D01*
G01X997875Y1106167D02*
Y1108667D01*
G01X999625D02*
Y1106167D01*
G01Y1107417D02*
X997875D01*
G01X1000933Y1106542D02*
X1001183Y1106334D01*
X1001475Y1106209D01*
X1001850Y1106167D01*
X1002225Y1106250D01*
X1002517Y1106417D01*
X1002725Y1106709D01*
X1002767Y1107042D01*
X1002683Y1107375D01*
X1002475Y1107584D01*
X1002183Y1107750D01*
X1001892Y1107792D01*
X1001600Y1107750D01*
X1001225Y1107584D01*
X1001350Y1108667D01*
X1002475D01*
G01X993208Y1394467D02*
X993083Y1394217D01*
X993000Y1393925D01*
Y1393592D01*
X993125Y1393217D01*
X993333Y1392925D01*
X993583Y1392717D01*
X994000Y1392550D01*
X994375Y1392508D01*
X994750Y1392592D01*
X995000Y1392717D01*
X995250Y1392967D01*
X995417Y1393258D01*
X995500Y1393550D01*
Y1393842D01*
X995417Y1394133D01*
X995292Y1394383D01*
X995125Y1394592D01*
G01X995208Y1395942D02*
X995417Y1396233D01*
X995500Y1396567D01*
X995417Y1396900D01*
X995167Y1397192D01*
X994792Y1397400D01*
X994417Y1397483D01*
X993958D01*
X993583Y1397400D01*
X993250Y1397192D01*
X993083Y1396942D01*
X993000Y1396650D01*
X993083Y1396317D01*
X993250Y1396067D01*
X993500Y1395900D01*
X993833Y1395817D01*
X994125Y1395900D01*
X994417Y1396108D01*
X994583Y1396358D01*
X994625Y1396650D01*
X994542Y1396983D01*
X994333Y1397233D01*
X993958Y1397483D01*
G01X995125Y1398833D02*
X995333Y1399083D01*
X995458Y1399375D01*
X995500Y1399750D01*
X995417Y1400125D01*
X995250Y1400417D01*
X994958Y1400625D01*
X994625Y1400667D01*
X994292Y1400583D01*
X994083Y1400375D01*
X993917Y1400083D01*
X993875Y1399792D01*
X993917Y1399500D01*
X994083Y1399125D01*
X993000Y1399250D01*
Y1400375D01*
G01X995000Y1401933D02*
X995292Y1402183D01*
X995458Y1402517D01*
X995500Y1402892D01*
X995458Y1403225D01*
X995250Y1403558D01*
X995000Y1403767D01*
X994750Y1403808D01*
X994458Y1403725D01*
X994250Y1403433D01*
X994167Y1403142D01*
Y1402767D01*
G01Y1403142D02*
X994042Y1403392D01*
X993833Y1403600D01*
X993583Y1403683D01*
X993333Y1403600D01*
X993125Y1403392D01*
X993000Y1403017D01*
X993042Y1402642D01*
X993208Y1402267D01*
G01X995000Y1405033D02*
X995292Y1405283D01*
X995458Y1405617D01*
X995500Y1405992D01*
X995458Y1406325D01*
X995250Y1406658D01*
X995000Y1406867D01*
X994750Y1406908D01*
X994458Y1406825D01*
X994250Y1406533D01*
X994167Y1406242D01*
Y1405867D01*
G01Y1406242D02*
X994042Y1406492D01*
X993833Y1406700D01*
X993583Y1406783D01*
X993333Y1406700D01*
X993125Y1406492D01*
X993000Y1406117D01*
X993042Y1405742D01*
X993208Y1405367D01*
G01X991500Y1392717D02*
X989000D01*
Y1393717D01*
X989125Y1394050D01*
X989417Y1394300D01*
X989750Y1394383D01*
X990083Y1394300D01*
X990333Y1394092D01*
X990458Y1393717D01*
Y1392717D01*
G01X989208Y1397567D02*
X989083Y1397317D01*
X989000Y1397025D01*
Y1396692D01*
X989125Y1396317D01*
X989333Y1396025D01*
X989583Y1395817D01*
X990000Y1395650D01*
X990375Y1395608D01*
X990750Y1395692D01*
X991000Y1395817D01*
X991250Y1396067D01*
X991417Y1396358D01*
X991500Y1396650D01*
Y1396942D01*
X991417Y1397233D01*
X991292Y1397483D01*
X991125Y1397692D01*
G01X991500Y1399750D02*
X989000D01*
X989500Y1399250D01*
G01X991500D02*
Y1400250D01*
G01X989417Y1402058D02*
X989167Y1402308D01*
X989042Y1402600D01*
X989000Y1402933D01*
X989083Y1403350D01*
X989292Y1403642D01*
X989542Y1403725D01*
X989792Y1403683D01*
X990000Y1403517D01*
X990417Y1402683D01*
X990708Y1402308D01*
X991125Y1402058D01*
X991500Y1401975D01*
Y1403725D01*
G01X991208Y1405242D02*
X991417Y1405533D01*
X991500Y1405867D01*
X991417Y1406200D01*
X991167Y1406492D01*
X990792Y1406700D01*
X990417Y1406783D01*
X989958D01*
X989583Y1406700D01*
X989250Y1406492D01*
X989083Y1406242D01*
X989000Y1405950D01*
X989083Y1405617D01*
X989250Y1405367D01*
X989500Y1405200D01*
X989833Y1405117D01*
X990125Y1405200D01*
X990417Y1405408D01*
X990583Y1405658D01*
X990625Y1405950D01*
X990542Y1406283D01*
X990333Y1406533D01*
X989958Y1406783D01*
G01X991500Y1409050D02*
X989000D01*
X989500Y1408550D01*
G01X991500D02*
Y1409550D01*
G01X987800Y1428600D02*
Y1423100D01*
G01Y1416500D02*
Y1411000D01*
G01X1042679Y1545801D02*
X1042887Y1546134D01*
X1043012Y1546509D01*
Y1546843D01*
X1042887Y1547176D01*
X1042679Y1547426D01*
X1042387Y1547551D01*
X1042095Y1547468D01*
X1041845Y1547259D01*
X1041679Y1546884D01*
X1041595Y1546384D01*
X1041429Y1546093D01*
X1041137Y1545968D01*
X1040845Y1546051D01*
X1040637Y1546259D01*
X1040512Y1546551D01*
Y1546843D01*
X1040595Y1547134D01*
X1040804Y1547384D01*
G01X1043012Y1549776D02*
X1040512D01*
G01X1041345Y1552876D02*
X1043012D01*
G01X1040679D02*
X1040637Y1552793D01*
X1040554D01*
X1040512Y1552876D01*
X1040554Y1552959D01*
X1040637D01*
X1040679Y1552876D01*
G01X1040512Y1555976D02*
X1043012D01*
G01X1041345Y1555393D02*
Y1556559D01*
G01X993625Y1926167D02*
Y1928667D01*
G01X995375D02*
Y1926167D01*
G01Y1927417D02*
X993625D01*
G01X997600Y1926167D02*
Y1928667D01*
X997100Y1928167D01*
G01Y1926167D02*
X998100D01*
G01X999908Y1928250D02*
X1000158Y1928500D01*
X1000450Y1928625D01*
X1000783Y1928667D01*
X1001200Y1928584D01*
X1001492Y1928375D01*
X1001575Y1928125D01*
X1001533Y1927875D01*
X1001367Y1927667D01*
X1000533Y1927250D01*
X1000158Y1926959D01*
X999908Y1926542D01*
X999825Y1926167D01*
X1001575D01*
G01X1122721Y316763D02*
X1123188Y317229D01*
X1123588Y317496D01*
X1124121Y317629D01*
X1124588Y317496D01*
X1124921Y317229D01*
X1125188Y316829D01*
X1125255Y316363D01*
X1125188Y315963D01*
X1124921Y315563D01*
X1124521Y315229D01*
X1124055Y315096D01*
X1123521Y315229D01*
X1123055Y315629D01*
X1122788Y316229D01*
X1122721Y316896D01*
X1122855Y317763D01*
X1123055Y318229D01*
X1123388Y318696D01*
X1123855Y319029D01*
X1124321Y319096D01*
X1124788Y318963D01*
X1125121Y318629D01*
G01X1122603Y345858D02*
X1123003Y345525D01*
X1123470Y345325D01*
X1124070Y345258D01*
X1124670Y345391D01*
X1125137Y345658D01*
X1125470Y346125D01*
X1125537Y346658D01*
X1125403Y347191D01*
X1125070Y347525D01*
X1124603Y347791D01*
X1124137Y347858D01*
X1123670Y347791D01*
X1123070Y347525D01*
X1123270Y349258D01*
X1125070D01*
G01X1125315Y377205D02*
Y381205D01*
X1122848Y378338D01*
X1126182D01*
G01X1122811Y409523D02*
X1123211Y409056D01*
X1123745Y408790D01*
X1124345Y408723D01*
X1124878Y408790D01*
X1125411Y409123D01*
X1125745Y409523D01*
X1125811Y409923D01*
X1125678Y410390D01*
X1125211Y410723D01*
X1124745Y410856D01*
X1124145D01*
G01X1124745D02*
X1125145Y411056D01*
X1125478Y411390D01*
X1125611Y411790D01*
X1125478Y412190D01*
X1125145Y412523D01*
X1124545Y412723D01*
X1123945Y412656D01*
X1123345Y412390D01*
G01X1123261Y443785D02*
X1123661Y444185D01*
X1124128Y444385D01*
X1124661Y444452D01*
X1125328Y444319D01*
X1125795Y443985D01*
X1125928Y443585D01*
X1125861Y443185D01*
X1125595Y442852D01*
X1124261Y442185D01*
X1123661Y441719D01*
X1123261Y441052D01*
X1123128Y440452D01*
X1125928D01*
G01X1123890Y471999D02*
Y475999D01*
X1123090Y475199D01*
G01Y471999D02*
X1124690D01*
G54D18*
G01X34300Y1834100D02*
Y1830100D01*
G01Y1829300D02*
Y1825300D01*
G01X98000Y122000D02*
X102000D01*
G01X110400Y414800D02*
X106400D01*
G01X98000Y528000D02*
X102000D01*
G01X110700Y820300D02*
X106700D01*
G01X98000Y933000D02*
X102000D01*
G01X99600Y1226400D02*
X95600D01*
G01X98000Y1338000D02*
X102000D01*
G01X110600Y1631000D02*
X106600D01*
G01X98000Y1752500D02*
X102000D01*
G01X129000Y53800D02*
X133000D01*
G01X142000Y244500D02*
X146000D01*
G01X144600Y360300D02*
X148600D01*
G01X142000Y651000D02*
X146000D01*
G01X144500Y765100D02*
X148500D01*
G01X142000Y1056500D02*
X146000D01*
G01X146500Y1171500D02*
X150500D01*
G01X142000Y1461000D02*
X146000D01*
G01X134700Y1577000D02*
X138700D01*
G01X142000Y1867000D02*
X146000D01*
G01X116500Y1964600D02*
X120500D01*
G01X310900Y414200D02*
Y418200D01*
G01X323100Y585400D02*
Y581400D01*
G01X310900Y844700D02*
Y848700D01*
G01X311000Y1215500D02*
Y1219500D01*
G01X299600Y1398500D02*
X295600D01*
G01X312000Y1713700D02*
Y1717700D01*
G01X290000Y1749000D02*
X286000D01*
G01X295000D02*
X291000D01*
G01X271500Y1770500D02*
X284000D01*
G01X271500Y1756500D02*
Y1770500D01*
G01X284000Y1756500D02*
X271500D01*
G01X284000D02*
Y1774000D01*
G01X281500Y1763500D02*
X284000Y1761000D01*
G01X281500Y1763500D02*
X284000Y1766000D01*
G01X874500Y248000D02*
X870500D01*
G01X863500Y360000D02*
X867500D01*
G01X870500Y651000D02*
X874500D01*
G01X863000Y765900D02*
X867000D01*
G01X870500Y1056500D02*
X874500D01*
G01X872500Y1172000D02*
X876500D01*
G01X870500Y1462000D02*
X874500D01*
G01X864000Y1577500D02*
X868000D01*
G01X898500Y1688000D02*
X894500D01*
G01X908500Y1710500D02*
X912500D01*
G01X853000Y1699500D02*
X857000D01*
G01X879000Y1698000D02*
X875000D01*
G01X899600Y1688000D02*
X900700D01*
G01X902300D02*
X903400D01*
G01X876000Y1726000D02*
X880000D01*
G01X869500Y1867000D02*
X873500D01*
G01X844500Y1964500D02*
X848500D01*
G01X961000Y1624400D02*
X957000D01*
G01X966500Y1659000D02*
Y1663000D01*
G01Y1669000D02*
Y1673000D01*
G01X922500Y1696900D02*
Y1695800D01*
G01Y1694200D02*
Y1693100D01*
G01X992500Y1419500D02*
X988500D01*
M02*
